G04 ================== begin FILE IDENTIFICATION RECORD ==================*
G04 Layout Name:  9324_DA0F0TMBIJ0_F0T_Motherboard_J_v01_20230324_0910.brd*
G04 Film Name:    top*
G04 File Format:  Gerber RS274X*
G04 File Origin:  Cadence Allegro 17.2-S081*
G04 Origin Date:  Sat Mar 25 08:44:48 2023*
G04 *
G04 Layer:  PIN/SPECIAL_DRILL*
G04 Layer:  DRAWING FORMAT/TITLE_BLOCK_A*
G04 Layer:  DRAWING FORMAT/TITLE_BLOCK*
G04 Layer:  VIA CLASS/TOP*
G04 Layer:  PIN/TOP*
G04 Layer:  MANUFACTURING/PHOTOPLOT_OUTLINE*
G04 Layer:  ETCH/TOP*
G04 Layer:  DRAWING FORMAT/TITLE_DATA_TOP*
G04 *
G04 Offset:    (0.00 0.00)*
G04 Mirror:    No*
G04 Mode:      Positive*
G04 Rotation:  0*
G04 FullContactRelief:  No*
G04 UndefLineWidth:     6.00*
G04 ================== end FILE IDENTIFICATION RECORD ====================*
%FSLAX25Y25*MOIN*%
%IR0*IPPOS*OFA0.00000B0.00000*MIA0B0*SFA1.00000B1.00000*%
%AMMACRO321*
4,1,28,.00051,-.00748,
.00051,-.00984,
.00602,-.00985,
.006695,-.009788,
.00735,-.009614,
.007964,-.009329,
.00852,-.008942,
.009,-.008464,
.00939,-.00791,
.009677,-.007296,
.009854,-.006642,
.009915,-.005967,
.00991,-.00592,
.00993,.0059,
.009875,.006576,
.009708,.007232,
.009429,.00785,
.009047,.008409,
.008574,.008894,
.008024,.009289,
.007413,.009583,
.006761,.009767,
.006087,.009834,
.00604,.00983,
.00053,.00984,
.00053,.00748,
-.0099,.00749,
-.00992,-.00747,
.00051,-.00748,
0.0*
%
%ADD321MACRO321*%
%AMMACRO318*
4,1,5,.00591,-.01772,
.00591,.01772,
0.0,.01772,
-.00591,.01181,
-.00591,-.01772,
.00591,-.01772,
0.0*
%
%ADD318MACRO318*%
%AMMACRO261*
4,1,32,-.06201,-.01575,
-.0502,-.01575,
-.0502,.00197,
-.04035,.00197,
-.04035,-.01575,
-.03248,-.01575,
-.03248,.00197,
-.02461,.00197,
-.02461,-.01575,
-.01673,-.01575,
-.01673,.00197,
-.00886,.00197,
-.00886,-.01575,
-.00098,-.01575,
-.00098,.00197,
.00689,.00197,
.00689,-.01575,
.01476,-.01575,
.01476,.00197,
.02264,.00197,
.02264,-.01575,
.03051,-.01575,
.03051,.00197,
.03839,.00197,
.03839,-.01575,
.04626,-.01575,
.04626,.00197,
.05413,.00197,
.05413,-.01575,
.06201,-.01575,
.06201,.01575,
-.06201,.01575,
-.06201,-.01575,
0.0*
%
%ADD261MACRO261*%
%ADD30O,.111X.062*%
%ADD297R,.017X.1*%
%AMMACRO259*
4,1,5,-.10039,-.10039,
-.10039,.08858,
-.08858,.10039,
.10039,.10039,
.10039,-.10039,
-.10039,-.10039,
0.0*
%
%ADD259MACRO259*%
%AMMACRO187*
4,1,5,-.01772,-.00591,
.01772,-.00591,
.01772,0.0,
.01181,.00591,
-.01772,.00591,
-.01772,-.00591,
0.0*
%
%ADD187MACRO187*%
%AMMACRO63*
4,1,8,.06299,-.02953,
.06299,.02953,
-.06299,.02953,
-.06299,-.02953,
-.01968,-.02953,
-.01968,.01771,
.01968,.01771,
.01968,-.02953,
.06299,-.02953,
0.0*
%
%ADD63MACRO63*%
%AMMACRO278*
21,1,.04,.071,0.0,0.0,135.*%
%ADD278MACRO278*%
%AMMACRO151*
21,1,.015,.004,0.0,0.0,135.*
1,1,.015,.001414,.001414*
1,1,.015,-.001414,-.001414*%
%ADD151MACRO151*%
%ADD92R,.17X.024*%
%AMMACRO320*
4,1,28,-.00052,-.00748,
-.00052,-.00984,
-.00603,-.00983,
-.006705,-.009775,
-.007359,-.0096,
-.007973,-.009313,
-.008528,-.008925,
-.009007,-.008446,
-.009395,-.007891,
-.009682,-.007277,
-.009857,-.006622,
-.009916,-.005948,
-.00992,-.0059,
-.0099,.00592,
-.009852,.006595,
-.009684,.007251,
-.009404,.007868,
-.009021,.008427,
-.008546,.008911,
-.007996,.009305,
-.007384,.009598,
-.006732,.00978,
-.006058,.009845,
-.00601,.00985,
-.0005,.00984,
-.0005,.00748,
.00993,.00747,
.00991,-.00749,
-.00052,-.00748,
0.0*
%
%ADD320MACRO320*%
%AMMACRO312*
4,1,32,-.05512,-.01181,
-.04331,-.01181,
-.04331,.00098,
-.03543,.00098,
-.03543,-.01181,
-.02362,-.01181,
-.02362,.00098,
-.01575,.00098,
-.01575,-.01181,
-.00394,-.01181,
-.00394,.00098,
.00394,.00098,
.00394,-.01181,
.01575,-.01181,
.01575,.00098,
.02362,.00098,
.02362,-.01181,
.03543,-.01181,
.03543,.00098,
.04331,.00098,
.04331,-.01181,
.05512,-.01181,
.05512,.00098,
.06299,.00098,
.06299,-.01181,
.0748,-.01181,
.0748,.01181,
-.0748,.01181,
-.0748,-.01181,
-.06299,-.01181,
-.06299,.00098,
-.05512,.00098,
-.05512,-.01181,
0.0*
%
%ADD312MACRO312*%
%ADD203R,.11X.049*%
%ADD198R,.126X.06*%
%ADD124R,.024X.17*%
%AMMACRO101*
4,1,44,.01181,-.00295,
.01181,.00295,
.01178,.003292,
.011692,.003623,
.011548,.003934,
.011351,.004215,
.011109,.004458,
.010828,.004655,
.010517,.004801,
.010186,.00489,
.009845,.00492,
.00984,.00492,
-.00984,.00492,
-.010182,.00489,
-.010513,.004802,
-.010824,.004658,
-.011105,.004461,
-.011348,.004219,
-.011545,.003938,
-.011691,.003627,
-.01178,.003296,
-.01181,.002955,
-.01181,.00295,
-.01181,-.00295,
-.01178,-.003292,
-.011692,-.003623,
-.011548,-.003934,
-.011351,-.004215,
-.011109,-.004458,
-.010828,-.004655,
-.010517,-.004801,
-.010186,-.00489,
-.009845,-.00492,
-.00984,-.00492,
.00984,-.00492,
.010182,-.00489,
.010513,-.004802,
.010824,-.004658,
.011105,-.004461,
.011348,-.004219,
.011545,-.003938,
.011691,-.003627,
.01178,-.003296,
.01181,-.002955,
.01181,-.00295,
0.0*
%
%ADD101MACRO101*%
%ADD304R,.06X.126*%
%ADD256R,.022X.007*%
%ADD11C,.02*%
%ADD288C,.012*%
%ADD265R,.0041X.016*%
%ADD255R,.007X.022*%
%ADD188R,.032X.007*%
%ADD19C,.03*%
%ADD266R,.095X.111*%
%ADD264R,.007X.032*%
%ADD236O,.137X.064*%
%ADD86R,.016X.0041*%
%ADD80R,.024X.007*%
%ADD42C,.04*%
%AMMACRO245*
4,1,8,-.09252,.09055,
-.09252,.0315,
-.08268,.0315,
-.08268,-.09055,
.08268,-.09055,
.08268,.0315,
.09252,.0315,
.09252,.09055,
-.09252,.09055,
0.0*
%
%ADD245MACRO245*%
%ADD204C,.041*%
%ADD119R,.008X.014*%
%ADD79R,.007X.024*%
%ADD35R,.109X.036*%
%ADD308R,.119X.063*%
%ADD289C,.015*%
%ADD209R,.015X.009*%
%ADD170R,.026X.007*%
%ADD104C,.06*%
%ADD98R,.024X.009*%
%ADD254R,.063X.119*%
%ADD210R,.009X.015*%
%ADD174C,.061*%
%ADD169R,.007X.026*%
%AMMACRO121*
4,1,6,-.03,.08661,
-.03,-.01752,
-.00244,-.01752,
-.00244,-.08661,
.03,-.08661,
.03,.08661,
-.03,.08661,
0.0*
%
%ADD121MACRO121*%
%ADD109C,.016*%
%ADD96R,.009X.024*%
%AMMACRO78*
4,1,8,-.037,.005,
.005,.005,
.005,.014,
.037,.014,
.037,-.014,
.005,-.014,
.005,-.005,
-.037,-.005,
-.037,.005,
0.0*
%
%ADD78MACRO78*%
%AMMACRO70*
4,1,21,-.0035,-.0085,
-.0035,.012,
.0035,.012,
.0035,-.0085,
.003447,-.009108,
.003289,-.009697,
.003031,-.01025,
.002681,-.01075,
.00225,-.011181,
.00175,-.011531,
.001197,-.011789,
.000608,-.011947,
0.0,-.012,
-.000608,-.011947,
-.001197,-.011789,
-.00175,-.011531,
-.00225,-.011181,
-.002681,-.01075,
-.003031,-.01025,
-.003289,-.009697,
-.003447,-.009108,
-.0035,-.0085,
0.0*
%
%ADD70MACRO70*%
%ADD68R,.126X.048*%
%AMMACRO49*
4,1,8,.005,.037,
.005,-.005,
.014,-.005,
.014,-.037,
-.014,-.037,
-.014,-.005,
-.005,-.005,
-.005,.037,
.005,.037,
0.0*
%
%ADD49MACRO49*%
%AMMACRO46*
4,1,21,.0085,-.0035,
-.012,-.0035,
-.012,.0035,
.0085,.0035,
.009108,.003447,
.009697,.003289,
.01025,.003031,
.01075,.002681,
.011181,.00225,
.011531,.00175,
.011789,.001197,
.011947,.000608,
.012,0.0,
.011947,-.000608,
.011789,-.001197,
.011531,-.00175,
.011181,-.00225,
.01075,-.002681,
.01025,-.003031,
.009697,-.003289,
.009108,-.003447,
.0085,-.0035,
0.0*
%
%ADD46MACRO46*%
%ADD161C,.026*%
%ADD153C,.017*%
%ADD89C,.062*%
%ADD33C,.044*%
%ADD298R,.017X.185*%
%ADD232C,.036*%
%ADD21C,.018*%
%ADD202C,.046*%
%ADD189R,.13X.0848*%
%AMMACRO167*
21,1,.016,.0041,0.0,0.0,45.322*%
%ADD167MACRO167*%
%ADD32C,.064*%
%ADD200C,.065*%
%ADD146R,.178X.054*%
%ADD127C,.03017*%
%ADD82R,.0848X.13*%
%ADD217R,.032X.032*%
%ADD15C,.039*%
%ADD324C,.085*%
%ADD159R,.185X.085*%
%ADD105R,.06X.06*%
%ADD94C,.0193*%
%AMMACRO250*
4,1,8,-.0425,-.078,
.0425,-.078,
.0425,.078,
-.0425,.078,
-.0425,.0236,
-.0145,.0236,
-.0145,-.0236,
-.0425,-.0236,
-.0425,-.078,
0.0*
%
%ADD250MACRO250*%
%ADD180R,.061X.061*%
%ADD194R,.166X.079*%
%ADD91R,.062X.062*%
%ADD29C,.0177*%
%ADD145R,.178X.095*%
%ADD125R,.079X.166*%
%ADD323C,.0395*%
%ADD272R,.064X.064*%
%AMMACRO99*
4,1,44,.05118,-.04921,
.05118,.04921,
.051151,.049552,
.051062,.049883,
.050918,.050194,
.050721,.050475,
.050479,.050718,
.050199,.050915,
.049888,.05106,
.049557,.05115,
.049215,.05118,
.04921,.05118,
-.04921,.05118,
-.049552,.051151,
-.049883,.051062,
-.050194,.050918,
-.050475,.050721,
-.050718,.050479,
-.050915,.050199,
-.05106,.049888,
-.05115,.049557,
-.05118,.049215,
-.05118,.04921,
-.05118,-.04921,
-.051151,-.049552,
-.051062,-.049883,
-.050918,-.050194,
-.050721,-.050475,
-.050479,-.050718,
-.050199,-.050915,
-.049888,-.05106,
-.049557,-.05115,
-.049215,-.05118,
-.04921,-.05118,
.04921,-.05118,
.049552,-.051151,
.049883,-.051062,
.050194,-.050918,
.050475,-.050721,
.050718,-.050479,
.050915,-.050199,
.05106,-.049888,
.05115,-.049557,
.05118,-.049215,
.05118,-.04921,
0.0*
%
%ADD99MACRO99*%
%ADD128R,.03017X.03017*%
%AMMACRO313*
4,1,24,.01051,-.04391,
.01188,-.04527,
.03394,-.04527,
.03394,-.03346,
.02016,-.03348,
.02016,-.02559,
.03394,-.02559,
.03394,-.01379,
.02016,-.0138,
.02016,-.0059,
.03394,-.00592,
.03394,.00591,
.02016,.00589,
.02016,.01378,
.03394,.01378,
.03394,.0256,
.02016,.02557,
.02016,.03347,
.03394,.03347,
.03394,.04527,
.01188,.04527,
.00913,.04255,
-.03394,.04255,
-.03394,-.04391,
.01051,-.04391,
0.0*
%
%ADD313MACRO313*%
%ADD322C,.0785*%
%ADD138R,.067X.067*%
%AMMACRO287*
4,1,28,-.00566,.00492,
-.00733,.00659,
-.01122,.00269,
-.011659,.002174,
-.011998,.001588,
-.01223,.000951,
-.012348,.000284,
-.012348,-.000393,
-.012231,-.001061,
-.012,-.001697,
-.011661,-.002284,
-.011226,-.002803,
-.01119,-.00284,
-.00284,-.01119,
-.002326,-.011631,
-.001744,-.011978,
-.00111,-.012217,
-.000444,-.012343,
.000233,-.012352,
.000902,-.012243,
.001541,-.012019,
.002132,-.011688,
.002656,-.011259,
.00269,-.01122,
.00659,-.00733,
.00492,-.00566,
.0123,.00172,
.00172,.0123,
-.00566,.00492,
0.0*
%
%ADD287MACRO287*%
%AMMACRO23*
4,1,28,-.00748,-.00052,
-.00984,-.00052,
-.00984,-.00603,
-.009782,-.006705,
-.009607,-.007359,
-.009321,-.007974,
-.008933,-.008529,
-.008455,-.009009,
-.0079,-.009398,
-.007286,-.009685,
-.006632,-.009861,
-.005957,-.00992,
-.00591,-.00992,
.00591,-.00992,
.006585,-.009869,
.007242,-.009701,
.007859,-.009421,
.008418,-.009039,
.008903,-.008565,
.009297,-.008015,
.009591,-.007404,
.009773,-.006751,
.00984,-.006077,
.00984,-.00603,
.00984,-.00052,
.00748,-.00052,
.00748,.00991,
-.00748,.00991,
-.00748,-.00052,
0.0*
%
%ADD23MACRO23*%
%ADD225C,.06574*%
%AMMACRO137*
4,1,5,.00492,.01673,
-.00492,.01673,
-.00492,-.01673,
.00098,-.01673,
.00492,-.0128,
.00492,.01673,
0.0*
%
%ADD137MACRO137*%
%ADD126C,.03568*%
%AMMACRO60*
4,1,5,.01378,.00098,
.01378,-.00492,
-.01378,-.00492,
-.01378,.00492,
.00984,.00492,
.01378,.00098,
0.0*
%
%ADD60MACRO60*%
%AMMACRO56*
4,1,5,.00098,-.01378,
-.00492,-.01378,
-.00492,.01378,
.00492,.01378,
.00492,-.00984,
.00098,-.01378,
0.0*
%
%ADD56MACRO56*%
%AMMACRO18*
4,1,28,-.00052,.00748,
-.00052,.00984,
-.00603,.00984,
-.006705,.009782,
-.007359,.009607,
-.007974,.009321,
-.008529,.008933,
-.009009,.008455,
-.009398,.0079,
-.009685,.007286,
-.009861,.006632,
-.00992,.005957,
-.00992,.00591,
-.00992,-.00591,
-.009869,-.006585,
-.009701,-.007242,
-.009421,-.007859,
-.009039,-.008418,
-.008565,-.008903,
-.008015,-.009297,
-.007404,-.009591,
-.006751,-.009773,
-.006077,-.00984,
-.00603,-.00984,
-.00052,-.00984,
-.00052,-.00748,
.00991,-.00748,
.00991,.00748,
-.00052,.00748,
0.0*
%
%ADD18MACRO18*%
%AMMACRO302*
4,1,5,.03378,-.03452,
.03378,.02664,
.02591,.03452,
-.03378,.03452,
-.03378,-.03452,
.03378,-.03452,
0.0*
%
%ADD302MACRO302*%
%AMMACRO286*
4,1,28,-.00493,.00565,
-.0066,.00732,
-.0027,.01121,
-.002185,.011649,
-.001599,.011989,
-.000962,.012222,
-.000295,.01234,
.000382,.012342,
.001049,.012225,
.001686,.011994,
.002273,.011657,
.002793,.011222,
.00283,.01119,
.01119,.00283,
.011629,.002313,
.011974,.00173,
.012212,.001096,
.012337,.00043,
.012344,-.000247,
.012234,-.000915,
.012009,-.001554,
.011677,-.002145,
.011247,-.002668,
.01121,-.0027,
.00732,-.0066,
.00565,-.00493,
-.00173,-.0123,
-.0123,-.00173,
-.00493,.00565,
0.0*
%
%ADD286MACRO286*%
%AMMACRO24*
4,1,28,-.00748,.00051,
-.00984,.00051,
-.00984,.00602,
-.009782,.006695,
-.009607,.007349,
-.009321,.007964,
-.008933,.008519,
-.008455,.008998,
-.0079,.009388,
-.007287,.009675,
-.006632,.009851,
-.005958,.00991,
-.00591,.00991,
.00591,.00991,
.006585,.009859,
.007242,.009691,
.007859,.009411,
.008418,.009029,
.008903,.008555,
.009297,.008005,
.00959,.007394,
.009773,.006742,
.00984,.006068,
.00984,.00602,
.00984,.00051,
.00748,.00051,
.00748,-.00992,
-.00748,-.00992,
-.00748,.00051,
0.0*
%
%ADD24MACRO24*%
%AMMACRO55*
4,1,5,-.00098,-.01378,
.00492,-.01378,
.00492,.01378,
-.00492,.01378,
-.00492,-.00984,
-.00098,-.01378,
0.0*
%
%ADD55MACRO55*%
%AMMACRO54*
4,1,5,.01378,-.00098,
.01378,.00492,
-.01378,.00492,
-.01378,-.00492,
.00984,-.00492,
.01378,-.00098,
0.0*
%
%ADD54MACRO54*%
%AMMACRO22*
4,1,28,.00051,.00748,
.00051,.00984,
.00602,.00984,
.006695,.009782,
.007349,.009607,
.007964,.009321,
.008519,.008933,
.008998,.008455,
.009388,.0079,
.009675,.007287,
.009851,.006632,
.00991,.005958,
.00991,.00591,
.00991,-.00591,
.009859,-.006585,
.009691,-.007242,
.009411,-.007859,
.009029,-.008418,
.008555,-.008903,
.008005,-.009297,
.007394,-.00959,
.006742,-.009773,
.006068,-.00984,
.00602,-.00984,
.00051,-.00984,
.00051,-.00748,
-.00992,-.00748,
-.00992,.00748,
.00051,.00748,
0.0*
%
%ADD22MACRO22*%
%ADD243R,.06574X.06574*%
%AMMACRO136*
4,1,8,-.01821,.0246,
.01821,.0246,
.01821,.01476,
-.00837,.01476,
-.00837,-.01477,
.01821,-.01477,
.01821,-.02461,
-.01821,-.02461,
-.01821,.0246,
0.0*
%
%ADD136MACRO136*%
%AMMACRO64*
4,1,13,-.012,.00002,
-.011943,.000627,
-.011782,.001216,
-.011521,.001767,
-.011168,.002265,
-.010734,.002694,
-.010233,.003041,
-.009678,.003296,
-.009088,.00345,
-.0085,.0035,
.012,.0035,
.012,-.0035,
-.00848,-.0035,
-.012,.00002,
0.0*
%
%ADD64MACRO64*%
%AMMACRO67*
4,1,13,.00002,.012,
.000627,.011943,
.001216,.011782,
.001767,.011521,
.002265,.011168,
.002694,.010734,
.003041,.010233,
.003296,.009678,
.00345,.009088,
.0035,.0085,
.0035,-.012,
-.0035,-.012,
-.0035,.00848,
.00002,.012,
0.0*
%
%ADD67MACRO67*%
%AMMACRO93*
4,1,6,-.1063,-.04134,
-.1063,.01378,
-.03543,.01378,
-.03543,.04134,
.1063,.04134,
.1063,-.04134,
-.1063,-.04134,
0.0*
%
%ADD93MACRO93*%
%AMMACRO300*
4,1,6,-.04134,.1063,
.01378,.1063,
.01378,.03543,
.04134,.03543,
.04134,-.1063,
-.04134,-.1063,
-.04134,.1063,
0.0*
%
%ADD300MACRO300*%
%AMMACRO72*
4,1,13,-.00849,.0035,
.012,.0035,
.012,-.0035,
-.0085,-.0035,
-.009108,-.003447,
-.009697,-.003289,
-.01025,-.003031,
-.01075,-.002681,
-.011181,-.00225,
-.011531,-.00175,
-.011789,-.001197,
-.011947,-.000608,
-.012,-.00001,
-.00849,.0035,
0.0*
%
%ADD72MACRO72*%
%AMMACRO65*
4,1,13,.0035,.00849,
.0035,-.012,
-.0035,-.012,
-.0035,.0085,
-.003447,.009108,
-.003289,.009697,
-.003031,.01025,
-.002681,.01075,
-.00225,.011181,
-.00175,.011531,
-.001197,.011789,
-.000608,.011947,
-.00001,.012,
.0035,.00849,
0.0*
%
%ADD65MACRO65*%
%ADD290O,.013X.01*%
%ADD291O,.01X.013*%
%ADD249R,.02X.01*%
%ADD309R,.13X.13*%
%AMMACRO263*
4,1,5,-.00591,.01772,
-.00591,-.01772,
0.0,-.01772,
.00591,-.01181,
.00591,.01772,
-.00591,.01772,
0.0*
%
%ADD263MACRO263*%
%AMMACRO239*
4,1,5,-.05512,-.05512,
.04134,-.05512,
.05512,-.04134,
.05512,.05512,
-.05512,.05512,
-.05512,-.05512,
0.0*
%
%ADD239MACRO239*%
%ADD230R,.02X.011*%
%ADD207R,.02X.012*%
%ADD114R,.022X.01*%
%ADD252R,.05X.01*%
%ADD238O,.255X.2*%
%ADD231R,.021X.012*%
%ADD223R,.014X.01*%
%ADD129R,.032X.01*%
%ADD115R,.01X.022*%
%ADD315R,.023X.011*%
%ADD224R,.015X.01*%
%ADD222R,.01X.014*%
%ADD181R,.032X.011*%
%ADD131R,.01X.05*%
%ADD130R,.01X.032*%
%ADD317R,.011X.023*%
%ADD314R,.024X.011*%
%ADD221R,.01X.015*%
%ADD186R,.032X.012*%
%ADD59R,.052X.01*%
%AMMACRO319*
4,1,32,.06201,.01575,
.0502,.01575,
.0502,-.00197,
.04035,-.00197,
.04035,.01575,
.03248,.01575,
.03248,-.00197,
.02461,-.00197,
.02461,.01575,
.01673,.01575,
.01673,-.00197,
.00886,-.00197,
.00886,.01575,
.00098,.01575,
.00098,-.00197,
-.00689,-.00197,
-.00689,.01575,
-.01476,.01575,
-.01476,-.00197,
-.02264,-.00197,
-.02264,.01575,
-.03051,.01575,
-.03051,-.00197,
-.03839,-.00197,
-.03839,.01575,
-.04626,.01575,
-.04626,-.00197,
-.05413,-.00197,
-.05413,.01575,
-.06201,.01575,
-.06201,-.01575,
.06201,-.01575,
.06201,.01575,
0.0*
%
%ADD319MACRO319*%
%ADD316R,.011X.024*%
%ADD262R,.012X.032*%
%ADD156R,.032X.022*%
%ADD118R,.126X.122*%
%ADD84R,.02X.016*%
%ADD44R,.05X.04*%
%ADD34R,.015X.012*%
%ADD12R,.034X.02*%
%ADD301R,.032X.04*%
%ADD205R,.012X.015*%
%AMMACRO184*
4,1,32,.01575,-.06201,
.01575,-.0502,
-.00197,-.0502,
-.00197,-.04035,
.01575,-.04035,
.01575,-.03248,
-.00197,-.03248,
-.00197,-.02461,
.01575,-.02461,
.01575,-.01673,
-.00197,-.01673,
-.00197,-.00886,
.01575,-.00886,
.01575,-.00098,
-.00197,-.00098,
-.00197,.00689,
.01575,.00689,
.01575,.01476,
-.00197,.01476,
-.00197,.02264,
.01575,.02264,
.01575,.03051,
-.00197,.03051,
-.00197,.03839,
.01575,.03839,
.01575,.04626,
-.00197,.04626,
-.00197,.05413,
.01575,.05413,
.01575,.06201,
-.01575,.06201,
-.01575,-.06201,
.01575,-.06201,
0.0*
%
%ADD184MACRO184*%
%ADD148R,.022X.032*%
%AMMACRO100*
4,1,44,.00295,.01181,
-.00295,.01181,
-.003292,.01178,
-.003623,.011692,
-.003934,.011548,
-.004215,.011351,
-.004458,.011109,
-.004655,.010828,
-.004801,.010517,
-.00489,.010186,
-.00492,.009845,
-.00492,.00984,
-.00492,-.00984,
-.00489,-.010182,
-.004802,-.010513,
-.004658,-.010824,
-.004461,-.011105,
-.004219,-.011348,
-.003938,-.011545,
-.003627,-.011691,
-.003296,-.01178,
-.002955,-.01181,
-.00295,-.01181,
.00295,-.01181,
.003292,-.01178,
.003623,-.011692,
.003934,-.011548,
.004215,-.011351,
.004458,-.011109,
.004655,-.010828,
.004801,-.010517,
.00489,-.010186,
.00492,-.009845,
.00492,-.00984,
.00492,.00984,
.00489,.010182,
.004802,.010513,
.004658,.010824,
.004461,.011105,
.004219,.011348,
.003938,.011545,
.003627,.011691,
.003296,.01178,
.002955,.01181,
.00295,.01181,
0.0*
%
%ADD100MACRO100*%
%ADD83R,.02X.017*%
%ADD75R,.04X.05*%
%ADD57R,.036X.01*%
%ADD296R,.09X.011*%
%ADD258R,.018X.011*%
%ADD237R,.05X.015*%
%ADD214R,.028X.01*%
%ADD201R,.063X.011*%
%ADD179R,.04X.015*%
%ADD160R,.017X.02*%
%ADD28R,.02X.018*%
%ADD274R,.042X.024*%
%ADD257R,.011X.018*%
%ADD149R,.024X.024*%
%ADD135R,.01X.028*%
%ADD123R,.063X.012*%
%ADD95R,.018X.012*%
%ADD90R,.166X.13*%
%AMMACRO77*
21,1,.016,.0041,0.0,0.0,135.*%
%ADD77MACRO77*%
%ADD74R,.018X.02*%
%AMMACRO61*
4,1,8,-.06299,.02953,
-.06299,-.02953,
.06299,-.02953,
.06299,.02953,
.01968,.02953,
.01968,-.01771,
-.01968,-.01771,
-.01968,.02953,
-.06299,.02953,
0.0*
%
%ADD61MACRO61*%
%ADD25R,.029X.01*%
%AMMACRO305*
4,1,8,.09055,.09252,
.0315,.09252,
.0315,.08268,
-.09055,.08268,
-.09055,-.08268,
.0315,-.08268,
.0315,-.09252,
.09055,-.09252,
.09055,.09252,
0.0*
%
%ADD305MACRO305*%
%ADD268R,.05X.035*%
%ADD247R,.27X.126*%
%ADD211R,.024X.042*%
%ADD196R,.063X.04*%
%ADD182R,.024X.024*%
%ADD172R,.052X.024*%
%ADD168R,.044X.014*%
%AMMACRO154*
21,1,.015,.004,0.0,0.0,45.*
1,1,.015,.001414,-.001414*
1,1,.015,-.001414,.001414*%
%ADD154MACRO154*%
%ADD152O,.019X.015*%
%ADD150R,.024X.016*%
%ADD116R,.012X.018*%
%ADD36R,.01X.029*%
%ADD276C,.122*%
%ADD275R,.014X.044*%
%ADD228R,.044X.024*%
%ADD191R,.036X.032*%
%ADD183R,.016X.024*%
%ADD162R,.024X.052*%
%ADD157O,.015X.019*%
%ADD76R,.063X.014*%
%ADD48R,.024X.017*%
%ADD20R,.036X.04*%
%ADD13R,.034X.016*%
%ADD299R,.052X.061*%
%ADD294R,.059X.01*%
%AMMACRO279*
21,1,.028,.032,0.0,0.0,45.*%
%ADD279MACRO279*%
%ADD267R,.024X.044*%
%AMMACRO215*
4,1,8,.01476,-.01771,
.01476,.01772,
-.01476,.01772,
-.01476,-.01771,
-.00492,-.01771,
-.00492,.00394,
.00492,.00394,
.00492,-.01771,
.01476,-.01771,
0.0*
%
%ADD215MACRO215*%
%ADD197R,.032X.036*%
%ADD195R,.044X.016*%
%ADD192R,.054X.024*%
%ADD176R,.017X.024*%
%ADD158R,.056X.04*%
%AMMACRO133*
4,1,8,.01771,.01476,
-.01772,.01476,
-.01772,-.01476,
.01771,-.01476,
.01771,-.00492,
-.00394,-.00492,
-.00394,.00492,
.01771,.00492,
.01771,.01476,
0.0*
%
%ADD133MACRO133*%
%ADD85R,.063X.015*%
%ADD43R,.032X.028*%
%ADD241R,.056X.05*%
%ADD218R,.048X.04*%
%ADD193R,.054X.016*%
%ADD178R,.04X.056*%
%ADD163R,.046X.024*%
%ADD155R,.052X.018*%
%ADD88R,.056X.014*%
%ADD62R,.016X.044*%
%ADD50R,.028X.032*%
%ADD40R,.024X.054*%
%ADD199R,.014X.056*%
%ADD102R,.024X.028*%
%ADD39R,.016X.054*%
%AMMACRO38*
4,1,40,.02165,-.00984,
.02165,.00984,
.021621,.010182,
.021532,.010513,
.021388,.010824,
.021192,.011105,
.02095,.011348,
.020669,.011545,
.020359,.01169,
.020028,.01178,
.01969,.01181,
-.01969,.01181,
-.020031,.011779,
-.020362,.011689,
-.020673,.011543,
-.020953,.011345,
-.021194,.011102,
-.02139,.01082,
-.021534,.010509,
-.021621,.010178,
-.02165,.00984,
-.02165,-.00984,
-.021621,-.010182,
-.021532,-.010513,
-.021388,-.010824,
-.021192,-.011105,
-.02095,-.011348,
-.020669,-.011545,
-.020359,-.01169,
-.020028,-.01178,
-.01969,-.01181,
.01969,-.01181,
.020031,-.011779,
.020362,-.011689,
.020673,-.011543,
.020953,-.011345,
.021194,-.011102,
.02139,-.01082,
.021534,-.010509,
.021621,-.010178,
.02165,-.00984,
0.0*
%
%ADD38MACRO38*%
%ADD14C,.125*%
%ADD277R,.044X.054*%
%ADD269R,.024X.065*%
%ADD229R,.058X.014*%
%ADD165R,.049X.014*%
%ADD164R,.046X.017*%
%ADD147C,.315*%
%ADD142C,.135*%
%ADD140R,.056X.052*%
%ADD113R,.06X.057*%
%ADD260R,.079X.012*%
%ADD234R,.022X.068*%
%ADD227R,.048X.025*%
%ADD220C,.217*%
%ADD212R,.052X.056*%
%ADD208R,.063X.046*%
%ADD166R,.059X.014*%
%ADD144R,.038X.026*%
%ADD107R,.091X.081*%
%ADD106R,.036X.063*%
%ADD41R,.015X.057*%
%ADD306R,.046X.028*%
%ADD295R,.026X.038*%
%ADD185R,.012X.079*%
%ADD175R,.014X.059*%
%ADD141R,.066X.017*%
%ADD111R,.081X.091*%
%AMMACRO307*
4,1,8,.037,-.005,
-.005,-.005,
-.005,-.014,
-.037,-.014,
-.037,.014,
-.005,.014,
-.005,.005,
.037,.005,
.037,-.005,
0.0*
%
%ADD307MACRO307*%
%ADD246R,.028X.046*%
%AMMACRO73*
4,1,21,-.0085,.0035,
.012,.0035,
.012,-.0035,
-.0085,-.0035,
-.009108,-.003447,
-.009697,-.003289,
-.01025,-.003031,
-.01075,-.002681,
-.011181,-.00225,
-.011531,-.00175,
-.011789,-.001197,
-.011947,-.000608,
-.012,0.0,
-.011947,.000608,
-.011789,.001197,
-.011531,.00175,
-.011181,.00225,
-.01075,.002681,
-.01025,.003031,
-.009697,.003289,
-.009108,.003447,
-.0085,.0035,
0.0*
%
%ADD73MACRO73*%
%ADD37R,.14X.14*%
%AMMACRO311*
4,1,30,.08089,-.09065,
.08227,-.09203,
.10433,-.09203,
.10433,-.08022,
.08309,-.08022,
.08171,-.07884,
.02464,-.07884,
.02464,.02608,
.06988,.02609,
.06988,.09203,
-.06988,.09203,
-.06988,.01427,
-.04035,.01427,
-.04035,-.02116,
-.10433,-.02117,
-.10433,-.03298,
-.09055,-.03298,
-.09055,-.04085,
-.10433,-.04084,
-.10433,-.05261,
-.09055,-.05266,
-.09055,-.06053,
-.10433,-.06054,
-.10433,-.07237,
-.09055,-.07237,
-.09055,-.08022,
-.10433,-.08022,
-.10433,-.09203,
-.08227,-.09203,
-.08089,-.09065,
.08089,-.09065,
0.0*
%
%ADD311MACRO311*%
%AMMACRO303*
4,1,6,.03,-.08661,
.03,.01752,
.00244,.01752,
.00244,.08661,
-.03,.08661,
-.03,-.08661,
.03,-.08661,
0.0*
%
%ADD303MACRO303*%
%ADD271R,.059X.017*%
%AMMACRO87*
4,1,8,-.005,-.037,
-.005,.005,
-.014,.005,
-.014,.037,
.014,.037,
.014,.005,
.005,.005,
.005,-.037,
-.005,-.037,
0.0*
%
%ADD87MACRO87*%
%AMMACRO66*
4,1,21,.0035,.0085,
.0035,-.012,
-.0035,-.012,
-.0035,.0085,
-.003447,.009108,
-.003289,.009697,
-.003031,.01025,
-.002681,.01075,
-.00225,.011181,
-.00175,.011531,
-.001197,.011789,
-.000608,.011947,
0.0,.012,
.000608,.011947,
.001197,.011789,
.00175,.011531,
.00225,.011181,
.002681,.01075,
.003031,.01025,
.003289,.009697,
.003447,.009108,
.0035,.0085,
0.0*
%
%ADD66MACRO66*%
%ADD310R,.197X.128*%
%ADD292R,.056X.048*%
%ADD233C,.158*%
%ADD177R,.124X.124*%
%ADD143C,.009*%
%ADD213R,.134X.134*%
%ADD120R,.024X.089*%
%ADD103R,.099X.042*%
%ADD190R,.069X.046*%
%ADD132C,.178*%
%ADD108R,.042X.099*%
%ADD81R,.144X.144*%
%ADD10C,.394*%
%ADD235R,.166X.197*%
%ADD226R,.059X.048*%
%ADD244R,.048X.059*%
%ADD31R,.059X.02047*%
%ADD242R,.189X.186*%
%ADD171R,.174X.174*%
%AMMACRO206*
4,1,8,.0425,.078,
-.0425,.078,
-.0425,-.078,
.0425,-.078,
.0425,-.0236,
.0145,-.0236,
.0145,.0236,
.0425,.0236,
.0425,.078,
0.0*
%
%ADD206MACRO206*%
%ADD110R,.077X.069*%
%AMMACRO285*
4,1,28,.00492,.00566,
.00659,.00733,
.00269,.01122,
.002174,.011659,
.001588,.011998,
.000951,.01223,
.000284,.012348,
-.000393,.012348,
-.001061,.012231,
-.001697,.012,
-.002284,.011661,
-.002803,.011226,
-.00284,.01119,
-.01119,.00284,
-.011631,.002326,
-.011978,.001744,
-.012217,.00111,
-.012343,.000444,
-.012352,-.000233,
-.012243,-.000902,
-.012019,-.001541,
-.011688,-.002132,
-.011259,-.002656,
-.01122,-.00269,
-.00733,-.00659,
-.00566,-.00492,
.00172,-.0123,
.0123,-.00172,
.00492,.00566,
0.0*
%
%ADD285MACRO285*%
%AMMACRO283*
4,1,28,-.00492,-.00566,
-.00659,-.00733,
-.00269,-.01122,
-.002174,-.011659,
-.001588,-.011998,
-.000951,-.01223,
-.000284,-.012348,
.000393,-.012348,
.001061,-.012231,
.001697,-.012,
.002284,-.011661,
.002803,-.011226,
.00284,-.01119,
.01119,-.00284,
.011631,-.002326,
.011978,-.001744,
.012217,-.00111,
.012343,-.000444,
.012352,.000233,
.012243,.000902,
.012019,.001541,
.011688,.002132,
.011259,.002656,
.01122,.00269,
.00733,.00659,
.00566,.00492,
-.00172,.0123,
-.0123,.00172,
-.00492,-.00566,
0.0*
%
%ADD283MACRO283*%
%AMMACRO281*
4,1,28,.00566,-.00492,
.00733,-.00659,
.01122,-.00269,
.011659,-.002174,
.011998,-.001588,
.01223,-.000951,
.012348,-.000284,
.012348,.000393,
.012231,.001061,
.012,.001697,
.011661,.002284,
.011226,.002803,
.01119,.00284,
.00284,.01119,
.002326,.011631,
.001744,.011978,
.00111,.012217,
.000444,.012343,
-.000233,.012352,
-.000902,.012243,
-.001541,.012019,
-.002132,.011688,
-.002656,.011259,
-.00269,.01122,
-.00659,.00733,
-.00492,.00566,
-.0123,-.00172,
-.00172,-.0123,
.00566,-.00492,
0.0*
%
%ADD281MACRO281*%
%ADD97R,.069X.077*%
%AMMACRO27*
4,1,28,.00748,.00052,
.00984,.00052,
.00984,.00603,
.009782,.006705,
.009607,.007359,
.009321,.007974,
.008933,.008529,
.008455,.009009,
.0079,.009398,
.007286,.009685,
.006632,.009861,
.005957,.00992,
.00591,.00992,
-.00591,.00992,
-.006585,.009869,
-.007242,.009701,
-.007859,.009421,
-.008418,.009039,
-.008903,.008565,
-.009297,.008015,
-.009591,.007404,
-.009773,.006751,
-.00984,.006077,
-.00984,.00603,
-.00984,.00052,
-.00748,.00052,
-.00748,-.00991,
.00748,-.00991,
.00748,.00052,
0.0*
%
%ADD27MACRO27*%
%AMMACRO17*
4,1,28,.00052,-.00748,
.00052,-.00984,
.00603,-.00984,
.006705,-.009782,
.007359,-.009607,
.007974,-.009321,
.008529,-.008933,
.009009,-.008455,
.009398,-.0079,
.009685,-.007286,
.009861,-.006632,
.00992,-.005957,
.00992,-.00591,
.00992,.00591,
.009869,.006585,
.009701,.007242,
.009421,.007859,
.009039,.008418,
.008565,.008903,
.008015,.009297,
.007404,.009591,
.006751,.009773,
.006077,.00984,
.00603,.00984,
.00052,.00984,
.00052,.00748,
-.00991,.00748,
-.00991,-.00748,
.00052,-.00748,
0.0*
%
%ADD17MACRO17*%
%AMMACRO293*
21,1,.016,.0041,0.0,0.0,134.695*%
%ADD293MACRO293*%
%ADD139R,.099X.067*%
%ADD248R,.067X.099*%
%AMMACRO112*
4,1,5,-.03378,.03452,
-.03378,-.02664,
-.02591,-.03452,
.03378,-.03452,
.03378,.03452,
-.03378,.03452,
0.0*
%
%ADD112MACRO112*%
%AMMACRO240*
4,1,5,.04823,-.03445,
.04823,.04823,
-.04823,.04823,
-.04823,-.04823,
.03445,-.04823,
.04823,-.03445,
0.0*
%
%ADD240MACRO240*%
%AMMACRO284*
4,1,28,.00565,.00493,
.00732,.0066,
.01121,.0027,
.011649,.002185,
.011989,.001599,
.012222,.000962,
.01234,.000295,
.012342,-.000382,
.012225,-.001049,
.011994,-.001686,
.011657,-.002273,
.011222,-.002793,
.01119,-.00283,
.00283,-.01119,
.002313,-.011629,
.00173,-.011974,
.001096,-.012212,
.00043,-.012337,
-.000247,-.012344,
-.000915,-.012234,
-.001554,-.012009,
-.002145,-.011677,
-.002668,-.011247,
-.0027,-.01121,
-.0066,-.00732,
-.00493,-.00565,
-.0123,.00173,
-.00173,.0123,
.00565,.00493,
0.0*
%
%ADD284MACRO284*%
%AMMACRO282*
4,1,28,-.00565,-.00493,
-.00732,-.0066,
-.01121,-.0027,
-.011649,-.002185,
-.011989,-.001599,
-.012222,-.000962,
-.01234,-.000295,
-.012342,.000382,
-.012225,.001049,
-.011994,.001686,
-.011657,.002273,
-.011222,.002793,
-.01119,.00283,
-.00283,.01119,
-.002313,.011629,
-.00173,.011974,
-.001096,.012212,
-.00043,.012337,
.000247,.012344,
.000915,.012234,
.001554,.012009,
.002145,.011677,
.002668,.011247,
.0027,.01121,
.0066,.00732,
.00493,.00565,
.0123,-.00173,
.00173,-.0123,
-.00565,-.00493,
0.0*
%
%ADD282MACRO282*%
%AMMACRO280*
4,1,28,.00493,-.00565,
.0066,-.00732,
.0027,-.01121,
.002185,-.011649,
.001599,-.011989,
.000962,-.012222,
.000295,-.01234,
-.000382,-.012342,
-.001049,-.012225,
-.001686,-.011994,
-.002273,-.011657,
-.002793,-.011222,
-.00283,-.01119,
-.01119,-.00283,
-.011629,-.002313,
-.011974,-.00173,
-.012212,-.001096,
-.012337,-.00043,
-.012344,.000247,
-.012234,.000915,
-.012009,.001554,
-.011677,.002145,
-.011247,.002668,
-.01121,.0027,
-.00732,.0066,
-.00565,.00493,
.00173,.0123,
.0123,.00173,
.00493,-.00565,
0.0*
%
%ADD280MACRO280*%
%AMMACRO253*
4,1,5,.01673,-.00492,
.01673,.00492,
-.01673,.00492,
-.01673,-.00098,
-.0128,-.00492,
.01673,-.00492,
0.0*
%
%ADD253MACRO253*%
%AMMACRO51*
4,1,5,-.01378,-.00098,
-.01378,.00492,
.01378,.00492,
.01378,-.00492,
-.00984,-.00492,
-.01378,-.00098,
0.0*
%
%ADD51MACRO51*%
%AMMACRO26*
4,1,28,.00748,-.00051,
.00984,-.00051,
.00984,-.00602,
.009782,-.006695,
.009607,-.007349,
.009321,-.007964,
.008933,-.008519,
.008455,-.008998,
.0079,-.009388,
.007287,-.009675,
.006632,-.009851,
.005958,-.00991,
.00591,-.00991,
-.00591,-.00991,
-.006585,-.009859,
-.007242,-.009691,
-.007859,-.009411,
-.008418,-.009029,
-.008903,-.008555,
-.009297,-.008005,
-.00959,-.007394,
-.009773,-.006742,
-.00984,-.006068,
-.00984,-.00602,
-.00984,-.00051,
-.00748,-.00051,
-.00748,.00992,
.00748,.00992,
.00748,-.00051,
0.0*
%
%ADD26MACRO26*%
%AMMACRO16*
4,1,28,-.00051,-.00748,
-.00051,-.00984,
-.00602,-.00984,
-.006695,-.009782,
-.007349,-.009607,
-.007964,-.009321,
-.008519,-.008933,
-.008998,-.008455,
-.009388,-.0079,
-.009675,-.007287,
-.009851,-.006632,
-.00991,-.005958,
-.00991,-.00591,
-.00991,.00591,
-.009859,.006585,
-.009691,.007242,
-.009411,.007859,
-.009029,.008418,
-.008555,.008903,
-.008005,.009297,
-.007394,.00959,
-.006742,.009773,
-.006068,.00984,
-.00602,.00984,
-.00051,.00984,
-.00051,.00748,
.00992,.00748,
.00992,-.00748,
-.00051,-.00748,
0.0*
%
%ADD16MACRO16*%
%AMMACRO270*
4,1,13,.02756,.11516,
.02756,-.02744,
.025101,-.031058,
.023307,-.035049,
.022233,-.03929,
.021912,-.043653,
.022354,-.048006,
.023545,-.052216,
.025449,-.056155,
.02756,-.05917,
.02756,-.11516,
-.02756,-.11516,
-.02756,.11516,
.02756,.11516,
0.0*
%
%ADD270MACRO270*%
%AMMACRO53*
4,1,5,-.00098,.01378,
.00492,.01378,
.00492,-.01378,
-.00492,-.01378,
-.00492,.00984,
-.00098,.01378,
0.0*
%
%ADD53MACRO53*%
%AMMACRO71*
4,1,13,-.00002,-.012,
-.000627,-.011943,
-.001216,-.011782,
-.001767,-.011521,
-.002265,-.011168,
-.002694,-.010734,
-.003041,-.010233,
-.003296,-.009678,
-.00345,-.009088,
-.0035,-.0085,
-.0035,.012,
.0035,.012,
.0035,-.00848,
-.00002,-.012,
0.0*
%
%ADD71MACRO71*%
%AMMACRO47*
4,1,13,.012,-.00002,
.011943,-.000627,
.011782,-.001216,
.011521,-.001767,
.011168,-.002265,
.010734,-.002694,
.010233,-.003041,
.009678,-.003296,
.009088,-.00345,
.0085,-.0035,
-.012,-.0035,
-.012,.0035,
.00848,.0035,
.012,-.00002,
0.0*
%
%ADD47MACRO47*%
%AMMACRO117*
4,1,6,.04134,-.1063,
-.01378,-.1063,
-.01378,-.03543,
-.04134,-.03543,
-.04134,.1063,
.04134,.1063,
.04134,-.1063,
0.0*
%
%ADD117MACRO117*%
%AMMACRO58*
4,1,5,-.01378,.00098,
-.01378,-.00492,
.01378,-.00492,
.01378,.00492,
-.00984,.00492,
-.01378,.00098,
0.0*
%
%ADD58MACRO58*%
%AMMACRO273*
4,1,13,.02756,.11516,
.02756,-.11516,
-.02756,-.11516,
-.02756,-.05917,
-.025101,-.055552,
-.023307,-.051561,
-.022233,-.04732,
-.021912,-.042957,
-.022354,-.038604,
-.023545,-.034394,
-.025449,-.030455,
-.02756,-.02744,
-.02756,.11516,
.02756,.11516,
0.0*
%
%ADD273MACRO273*%
%AMMACRO251*
4,1,8,.0246,.01821,
.0246,-.01821,
.01476,-.01821,
.01476,.00837,
-.01477,.00837,
-.01477,-.01821,
-.02461,-.01821,
-.02461,.01821,
.0246,.01821,
0.0*
%
%ADD251MACRO251*%
%AMMACRO134*
4,1,9,.01181,.01476,
-.01771,.01476,
-.01771,.00492,
.00394,.00492,
.00394,-.00492,
-.01771,-.00492,
-.01771,-.01476,
.01772,-.01476,
.01772,.00886,
.01181,.01476,
0.0*
%
%ADD134MACRO134*%
%AMMACRO52*
4,1,5,.00098,.01378,
-.00492,.01378,
-.00492,-.01378,
.00492,-.01378,
.00492,.00984,
.00098,.01378,
0.0*
%
%ADD52MACRO52*%
%AMMACRO216*
4,1,9,.01476,-.01181,
.01476,.01771,
.00492,.01771,
.00492,-.00394,
-.00492,-.00394,
-.00492,.01771,
-.01476,.01771,
-.01476,-.01772,
.00886,-.01772,
.01476,-.01181,
0.0*
%
%ADD216MACRO216*%
%AMMACRO69*
4,1,13,-.0035,-.00849,
-.0035,.012,
.0035,.012,
.0035,-.0085,
.003447,-.009108,
.003289,-.009697,
.003031,-.01025,
.002681,-.01075,
.00225,-.011181,
.00175,-.011531,
.001197,-.011789,
.000608,-.011947,
.00001,-.012,
-.0035,-.00849,
0.0*
%
%ADD69MACRO69*%
%AMMACRO45*
4,1,13,.00849,-.0035,
-.012,-.0035,
-.012,.0035,
.0085,.0035,
.009108,.003447,
.009697,.003289,
.01025,.003031,
.01075,.002681,
.011181,.00225,
.011531,.00175,
.011789,.001197,
.011947,.000608,
.012,.00001,
.00849,-.0035,
0.0*
%
%ADD45MACRO45*%
%ADD325C,.01*%
%ADD326C,.013*%
%ADD327C,.014*%
%ADD328C,.025*%
%ADD329C,.004*%
%ADD330C,.005*%
%ADD331C,.00401*%
%ADD332C,.006*%
%ADD333C,.0042*%
%ADD334C,.0051*%
%ADD335C,.00601*%
%ADD336C,.00511*%
%ADD337C,.007*%
%ADD338C,.0052*%
%ADD339C,.0044*%
%ADD340C,.0071*%
%ADD341C,.0035*%
%ADD342C,.008*%
%ADD343C,.0045*%
%ADD344C,.00451*%
%ADD345C,.0048*%
%ADD346C,.0068*%
%ADD347C,.00349*%
%ADD348C,.0079*%
%ADD349C,.03004*%
%ADD350C,.04004*%
%ADD357C,.07002*%
%ADD352C,.03006*%
%ADD351C,.07004*%
%ADD362C,.07006*%
%ADD354C,.07204*%
%ADD361C,.02804*%
%ADD353C,.03444*%
%ADD356C,.06804*%
%ADD360C,.30104*%
%ADD363C,.1622*%
%ADD355C,.1751*%
%ADD358C,.2582*%
%ADD359C,.198*%
G75*
%LPD*%
G75*
G36*
G01X2010Y68314D02*
X2637Y68531D01*
X2725Y68419D01*
G03X2758Y68377I24784J19439D01*
G03X3939Y66957I24797J19423D01*
G01X3959Y66934D01*
X4006Y66828D01*
Y54252D01*
G03X7874Y50384I3868J0D01*
G01X43711D01*
G02X55590Y38504I-1J-11880D01*
G01Y15533D01*
X55513Y15383D01*
G03X54044Y12480I2134J-2903D01*
G03X55482Y9600I3603J0D01*
G01X55509Y9579D01*
X55590Y9421D01*
Y4000D01*
X317654D01*
Y9415D01*
X317736Y9574D01*
X317772Y9602D01*
G03Y15352I-2169J2875D01*
G01X317736Y15380D01*
X317654Y15539D01*
Y38504D01*
G02X329535Y50384I11881J-1D01*
G01X488593D01*
G02X500472Y38504I-1J-11880D01*
G01Y36225D01*
G03X498937Y33564I2055J-2958D01*
G01X498933Y33512D01*
X498810Y33329D01*
X498723Y33308D01*
G02X498475Y33502I-48J194D01*
G01Y38504D01*
G03X488591Y48388I-9884J0D01*
G01X329535D01*
G03X319651Y38504I0J-9884D01*
G01Y4830D01*
X319660D01*
Y3937D01*
G02X317724Y2001I-1936J0D01*
G01X55520D01*
G02X53584Y3937I0J1936D01*
G01Y4830D01*
X53593D01*
Y38504D01*
G03X43709Y48388I-9884J0D01*
G01X7874D01*
G02X2010Y54252I0J5864D01*
G01Y68314D01*
G37*
G36*
G01X2145Y107229D02*
G02X2010Y107418I65J189D01*
G01Y305794D01*
G02X3727Y309940I5864J0D01*
G01X6989Y313202D01*
G03X9884Y320190I-6988J6989D01*
G01Y622304D01*
G02X10054Y622502I200J0D01*
G01X10518Y622573D01*
X10643Y622495D01*
X10665Y622424D01*
G03X11865Y619232I30041J9472D01*
G02X11882Y619152I-183J-81D01*
G01Y320190D01*
G02X10083Y313906I-11880J2D01*
G02X10055Y313871I-169J107D01*
G01X5877Y309692D01*
G03X5519Y308966I888J-889D01*
G01X5515Y308933D01*
X5486Y308875D01*
X5139Y308528D01*
G03X4008Y305796I2736J-2733D01*
G01Y166318D01*
Y163868D01*
Y162293D01*
Y159843D01*
Y158141D01*
Y155435D01*
Y153937D01*
Y151487D01*
Y150041D01*
Y147119D01*
Y145934D01*
Y143012D01*
Y141966D01*
Y138476D01*
Y108787D01*
G02X3958Y108654I-200J-1D01*
G03X2725Y107171I23592J-20869D01*
G01X2686Y107121D01*
X2564Y107084D01*
X2145Y107229D01*
G37*
G36*
G01X9884Y641476D02*
Y756610D01*
X10264Y756990D01*
X11650D01*
X11882Y756758D01*
Y694306D01*
Y644628D01*
G02X11865Y644548I-200J1D01*
G03X10665Y641356I28841J-12664D01*
G01X10643Y641285D01*
X10518Y641207D01*
X10054Y641278D01*
G02X9884Y641476I30J198D01*
G37*
G36*
G01Y783081D02*
Y1359311D01*
G02X10054Y1359509I200J0D01*
G01X10518Y1359580D01*
X10643Y1359502D01*
X10665Y1359431D01*
G03X11865Y1356239I30041J9472D01*
G02X11882Y1356159I-183J-81D01*
G01Y789628D01*
Y773094D01*
X11540Y772752D01*
X10230D01*
X9884Y773098D01*
Y783081D01*
G37*
G36*
G01X10054Y1378285D02*
G02X9884Y1378483I30J198D01*
G01Y1588078D01*
G02X11601Y1592224I5864J0D01*
G01X24705Y1605328D01*
G03X27601Y1612316I-6987J6990D01*
G01Y1693048D01*
G02X27727Y1693233I200J-1D01*
G01X28130Y1693394D01*
X28249Y1693367D01*
X28292Y1693322D01*
G03X29536Y1692078I22886J21642D01*
G02X29598Y1691932I-138J-145D01*
G01Y1612316D01*
G02X26117Y1603916I-11880J2D01*
G01X13013Y1590812D01*
G03X11882Y1588079I2736J-2733D01*
G01Y1381635D01*
G02X11865Y1381555I-200J1D01*
G03X10665Y1378363I28841J-12664D01*
G01X10643Y1378292D01*
X10518Y1378214D01*
X10054Y1378285D01*
G37*
G36*
G01X26774Y195148D02*
G03I-720J0D01*
G37*
G36*
G01X26472Y203274D02*
G03I-720J0D01*
G37*
G36*
G01X25474Y220220D02*
G03I-720J0D01*
G37*
G36*
G01X25534Y236472D02*
G03I-720J0D01*
G37*
G36*
G01X85932Y1320865D02*
X148347D01*
X154557Y1314655D01*
X265207D01*
X267000Y1312862D01*
Y1264362D01*
X263771Y1261133D01*
X253095D01*
X253064Y1261144D01*
G03X252657Y1261212I-408J-1189D01*
G01X251247D01*
G03X250840Y1261144I1J-1257D01*
G01X250809Y1261133D01*
X247374D01*
X244006Y1264501D01*
X234221D01*
X230817Y1261097D01*
X220925D01*
G03X218395I-1265J-605D01*
G01X218053D01*
X214684Y1264466D01*
X204225D01*
X200821Y1261062D01*
X187490D01*
X184122Y1264430D01*
X174512D01*
X171180Y1261098D01*
X158167D01*
X154834Y1264431D01*
X145581D01*
X142318Y1261168D01*
X128242D01*
X124979Y1264431D01*
X114593D01*
X111331Y1261169D01*
X97609D01*
X94312Y1264466D01*
X85376D01*
X81972Y1261062D01*
X69280D01*
X65912Y1264430D01*
X54920D01*
X51658Y1261168D01*
X39604D01*
X36271Y1264501D01*
X19960D01*
X16344Y1268117D01*
Y1309872D01*
X18412Y1311940D01*
X54762D01*
G03X58792I2015J2224D01*
G01X67772D01*
X75976Y1320144D01*
X82928D01*
Y1311831D01*
G03X83128Y1311082I1503J0D01*
G01Y1309631D01*
G03X83630Y1309130I501J0D01*
G01X85230D01*
G03X85732Y1309631I0J502D01*
G01Y1311082D01*
G03X85932Y1311831I-1303J749D01*
G01Y1320865D01*
G37*
G36*
G01X36320Y227380D02*
G03I-720J0D01*
G37*
G36*
G01X45902Y426310D02*
G03I-720J0D01*
G37*
G36*
G01X45754Y449106D02*
G03I-720J0D01*
G37*
G36*
G01X59099Y69340D02*
G03I-720J0D01*
G37*
G36*
G01X61099Y66844D02*
G03I-720J0D01*
G37*
G36*
G01Y71836D02*
G03I-720J0D01*
G37*
G36*
G01X61412Y87118D02*
G03I-720J0D01*
G37*
G36*
G01X48338Y413113D02*
G03I-720J0D01*
G37*
G36*
G01X48339Y421155D02*
G03I-720J0D01*
G37*
G36*
G01X50858Y426310D02*
G03I-720J0D01*
G37*
G36*
G01X61113D02*
G03I-720J0D01*
G37*
G36*
G01X50710Y449106D02*
G03I-720J0D01*
G37*
G36*
G01X68017Y766745D02*
X70167D01*
X72739Y764173D01*
X72641Y764035D01*
G03X72363Y763164I1224J-871D01*
G03X73865Y761662I1502J0D01*
G03X74736Y761940I0J1502D01*
G01X74874Y762038D01*
X75298Y761614D01*
X91842D01*
X91891Y761485D01*
G03X94699I1404J534D01*
G01X94748Y761614D01*
X131194D01*
G02X131567Y761069I0J-400D01*
G03X131465Y760525I1400J-544D01*
G03X134469I1502J0D01*
G03X134367Y761069I-1502J0D01*
G02X134740Y761614I373J145D01*
G01X233638D01*
X235225Y760027D01*
Y743857D01*
X238810Y740272D01*
X262680D01*
X270030Y747622D01*
X272681D01*
X272798Y747739D01*
X273048Y747489D01*
X272971Y747356D01*
G03X272768Y746602I1299J-754D01*
G03X274270Y745100I1502J0D01*
G03X275403Y745616I0J1502D01*
G02X275987Y745637I302J-263D01*
G03X277046Y745200I1059J1065D01*
G03Y748204I0J1502D01*
G03X275913Y747688I0J-1502D01*
G02X275329Y747667I-302J263D01*
G03X274270Y748104I-1059J-1065D01*
G03X274154Y748100I-6J-1502D01*
G02X273840Y748781I-31J399D01*
G01X280853Y755794D01*
X288262D01*
X292418Y751638D01*
X355746D01*
X361888Y745496D01*
Y729679D01*
X360487Y728278D01*
X360448Y728263D01*
G03X359662Y727564I542J-1401D01*
G01X359606Y727457D01*
X354136D01*
Y727832D01*
X354164Y727880D01*
G03X354381Y728657I-1285J778D01*
G03X352879Y730159I-1502J0D01*
G03X351593Y729434I0J-1503D01*
G02X350968Y729358I-342J207D01*
G01X349748Y730578D01*
X349869Y730719D01*
G03X350232Y731698I-1139J979D01*
G03X349404Y733041I-1503J0D01*
G02Y733755I179J357D01*
G03X350232Y735098I-675J1343D01*
G03X347228I-1502J0D01*
G03X348056Y733755I1503J0D01*
G02Y733041I-179J-357D01*
G03X347228Y731698I675J-1343D01*
G03X347380Y731039I1502J-1D01*
G02X347021Y730463I-359J-176D01*
G01X343393D01*
X339799Y726869D01*
X333132D01*
X332217Y727784D01*
Y731705D01*
X329488Y734434D01*
X327008D01*
X326680Y734106D01*
X326635Y734091D01*
G03X325605Y732665I472J-1426D01*
G03X325645Y732320I1502J-1D01*
G01X325650Y732297D01*
Y719415D01*
G03X325897Y718604I1457J1D01*
G01Y635879D01*
X325771Y635753D01*
Y625344D01*
X319519Y619092D01*
X297660D01*
X296630Y620122D01*
Y628235D01*
X296799Y628262D01*
G03X298906Y630732I-394J2470D01*
G03X298798Y631460I-2501J1D01*
G01X298763Y631575D01*
X307037Y639849D01*
Y683335D01*
X281060Y709312D01*
X174460D01*
X173460Y710312D01*
Y729805D01*
X170040Y733225D01*
X57997D01*
Y737151D01*
G02X58629Y737476I400J-1D01*
G03X59500Y737198I871J1224D01*
G03Y740202I0J1502D01*
G03X58629Y739924I0J-1502D01*
G02X57997Y740249I-232J326D01*
G01Y752261D01*
G02X58452Y752657I400J0D01*
G03X58658Y752643I205J1488D01*
G03Y755647I0J1502D01*
G03X58452Y755633I-1J-1502D01*
G02X57997Y756029I-55J396D01*
G01Y756725D01*
X68017Y766745D01*
G37*
G36*
G01X47485Y1663165D02*
G03I-491J0D01*
G37*
G36*
G01X74811Y23978D02*
G03I-720J0D01*
G37*
G36*
G01X72811Y25974D02*
G03I-720J0D01*
G37*
G36*
G01X68055Y69340D02*
G03I-720J0D01*
G37*
G36*
G01X66055Y66844D02*
G03I-720J0D01*
G37*
G36*
G01Y71836D02*
G03I-720J0D01*
G37*
G36*
G01X66368Y87118D02*
G03I-720J0D01*
G37*
G36*
G01X72099Y72844D02*
G03I-720J0D01*
G37*
G36*
G01Y77836D02*
G03I-720J0D01*
G37*
G36*
G01X77055Y72844D02*
G03I-720J0D01*
G37*
G36*
G01Y77836D02*
G03I-720J0D01*
G37*
G36*
G01X70099Y75340D02*
G03I-720J0D01*
G37*
G36*
G01X63553Y410047D02*
G03I-720J0D01*
G37*
G36*
G01X63528Y418425D02*
G03I-720J0D01*
G37*
G36*
G01X66069Y426310D02*
G03I-720J0D01*
G37*
G36*
G01X71610Y446062D02*
X72310Y446762D01*
X76610D01*
X77910Y445462D01*
Y440062D01*
X77210Y439362D01*
X72010D01*
X71610Y439762D01*
Y446062D01*
G37*
G36*
G01X66981Y710843D02*
X83213D01*
X85168Y708888D01*
X85773D01*
X85879Y708782D01*
X90880D01*
X90999Y708663D01*
Y707941D01*
X90920Y707862D01*
X82500D01*
X79400Y704762D01*
X76200D01*
X73600Y702162D01*
Y682450D01*
X75199Y680851D01*
X102239D01*
X143571D01*
X145682Y682962D01*
X162872D01*
X169891Y689982D01*
Y698553D01*
X171872Y700534D01*
X207500D01*
X208100Y699934D01*
Y688985D01*
X207900Y688785D01*
X202577D01*
X202200Y689162D01*
Y694795D01*
X201500Y695495D01*
X189233D01*
X188605Y694867D01*
Y668967D01*
X189929Y667643D01*
X197060D01*
X199031Y665672D01*
X214514D01*
X215284Y664902D01*
Y651442D01*
X207130D01*
X206951Y651622D01*
X206892Y651681D01*
Y656730D01*
G03X206833Y656872I-200J0D01*
G01X206049Y657656D01*
G03X205907Y657715I-142J-141D01*
G01X202302D01*
X201317Y658700D01*
G03X201175Y658759I-142J-141D01*
G01X195147D01*
X190420Y654032D01*
Y637200D01*
X194900Y632720D01*
X213979D01*
X215284Y631415D01*
Y617587D01*
G02X215228Y617448I-200J0D01*
G01X207126D01*
X206892Y617681D01*
Y622730D01*
G03X206833Y622872I-200J0D01*
G01X206049Y623656D01*
G03X205907Y623715I-142J-141D01*
G01X202302D01*
X201317Y624700D01*
G03X201175Y624759I-142J-141D01*
G01X195950D01*
X190420Y619229D01*
Y603500D01*
X195200Y598720D01*
X213979D01*
X215284Y597415D01*
Y583587D01*
G02X215237Y583458I-200J0D01*
G01X207116D01*
X206892Y583681D01*
Y588730D01*
G03X206833Y588872I-200J0D01*
G01X206049Y589656D01*
G03X205907Y589715I-142J-141D01*
G01X202302D01*
X201317Y590700D01*
G03X201175Y590759I-142J-141D01*
G01X173195D01*
X173176Y590778D01*
X156134D01*
X154359Y592553D01*
Y666881D01*
X145538Y675702D01*
X68600D01*
X65200Y679102D01*
Y709062D01*
X66981Y710843D01*
G37*
G36*
G01X86264Y721221D02*
X88705D01*
X89605Y720321D01*
Y716209D01*
X90415Y715399D01*
Y712429D01*
X89835Y711849D01*
X62878D01*
X62150Y712577D01*
Y720367D01*
X63004Y721221D01*
X83926D01*
G03X86264I1169J943D01*
G37*
G36*
G01X379425Y1448134D02*
G03X379366Y1447992I141J-142D01*
G01Y1420446D01*
X387397Y1412415D01*
Y1397997D01*
X387092Y1397692D01*
X343312D01*
X342926Y1398078D01*
X342911Y1398125D01*
G03X322500Y1413190I-20411J-6295D01*
G01X296372D01*
X296260Y1413302D01*
X258230D01*
X256380Y1415152D01*
Y1431052D01*
X227570Y1459862D01*
X172500D01*
X166703Y1454065D01*
Y1451426D01*
X166674Y1451378D01*
G03X166644Y1451273I170J-105D01*
G01Y1434586D01*
X166642Y1434584D01*
Y1421280D01*
X165677Y1420315D01*
X139340D01*
X128798Y1409774D01*
Y1331560D01*
X127689Y1330451D01*
X97059D01*
X97000Y1330392D01*
X85932D01*
Y1333091D01*
G03X85766Y1333777I-1502J0D01*
G01X85755Y1333798D01*
X85732Y1333890D01*
Y1335291D01*
G03X85232Y1335792I-501J0D01*
G01X83630D01*
G03X83128Y1335291I0J-502D01*
G01Y1333890D01*
X83105Y1333798D01*
X83094Y1333777D01*
G03X82928Y1333091I1336J-686D01*
G01Y1330392D01*
X67950D01*
X66680Y1331662D01*
Y1351013D01*
X66715Y1351126D01*
X66732Y1351151D01*
G03X72206Y1368897I-26024J17745D01*
G03X66732Y1386643I-31498J1D01*
G01X66715Y1386668D01*
X66680Y1386781D01*
Y1421799D01*
X62760Y1425719D01*
Y1493742D01*
X65780Y1496762D01*
X87345D01*
X87583Y1496165D01*
X87485Y1496072D01*
G03X87017Y1494982I1035J-1090D01*
G03X90023I1503J0D01*
G03X89555Y1496072I-1503J0D01*
G01X89457Y1496165D01*
X89695Y1496762D01*
X141560D01*
X142506Y1497708D01*
X142507D01*
X146646Y1501846D01*
X652840D01*
X680261Y1496635D01*
X683196Y1493700D01*
Y1424232D01*
X679282Y1420318D01*
X668200D01*
X617855Y1470663D01*
X402037D01*
G03X401895Y1470604I0J-200D01*
G01X379425Y1448134D01*
G37*
G36*
G01X80003Y1535715D02*
Y1537085D01*
X79223Y1537865D01*
X76373D01*
X76283Y1537955D01*
Y1538255D01*
X76363Y1538335D01*
X79153D01*
X79673Y1538855D01*
Y1540505D01*
X80093Y1540925D01*
X82653D01*
X83643Y1541915D01*
Y1544025D01*
X83733Y1544115D01*
X84083D01*
X84173Y1544025D01*
Y1541785D01*
X84963Y1540995D01*
X87663D01*
X88373Y1541705D01*
Y1544015D01*
X88483Y1544125D01*
X88833D01*
X88913Y1544045D01*
Y1541685D01*
X89493Y1541105D01*
X92493D01*
X93213Y1540385D01*
Y1539105D01*
X93923Y1538395D01*
X96093D01*
X96243Y1538245D01*
Y1537915D01*
X96123Y1537795D01*
X94003D01*
X93423Y1537215D01*
Y1535375D01*
X92963Y1534915D01*
X89543D01*
X88913Y1534285D01*
Y1532165D01*
X88783Y1532035D01*
X86943D01*
X86793Y1532185D01*
Y1534475D01*
X86333Y1534935D01*
X84823D01*
X84223Y1534335D01*
Y1532235D01*
X84063Y1532075D01*
X83753D01*
X83593Y1532235D01*
Y1534595D01*
X83263Y1534925D01*
X80793D01*
X80003Y1535715D01*
G37*
G36*
G01X67464Y1598324D02*
G03I-558J0D01*
G37*
G36*
G01Y1603280D02*
G03I-558J0D01*
G37*
G36*
G01X73544Y1738108D02*
X373307D01*
G02X373493Y1737984I1J-200D01*
G01X373656Y1737584D01*
X373631Y1737466D01*
X373588Y1737423D01*
G03X372387Y1736176I22078J-22466D01*
G02X372239Y1736110I-149J134D01*
G01X345740D01*
X345709Y1736121D01*
G03X345079Y1736222I-629J-1909D01*
G03X344449Y1736121I-1J-2010D01*
G01X344418Y1736110D01*
X329992D01*
X329961Y1736121D01*
G03X329331Y1736222I-629J-1909D01*
G03X328701Y1736121I-1J-2010D01*
G01X328670Y1736110D01*
X314244D01*
X314213Y1736121D01*
G03X313583Y1736222I-629J-1909D01*
G03X312953Y1736121I-1J-2010D01*
G01X312922Y1736110D01*
X299693D01*
X299640Y1736126D01*
X299615Y1736142D01*
G03X299344Y1736222I-272J-421D01*
G01X296326D01*
G03X296055Y1736142I1J-501D01*
G01X296030Y1736126D01*
X295977Y1736110D01*
X278811D01*
X278780Y1736121D01*
G03X278150Y1736222I-629J-1909D01*
G03X277520Y1736121I-1J-2010D01*
G01X277489Y1736110D01*
X263063D01*
X263032Y1736121D01*
G03X262402Y1736222I-629J-1909D01*
G03X261772Y1736121I-1J-2010D01*
G01X261741Y1736110D01*
X247315D01*
X247284Y1736121D01*
G03X246654Y1736222I-629J-1909D01*
G03X246024Y1736121I-1J-2010D01*
G01X245993Y1736110D01*
X232764D01*
X232711Y1736126D01*
X232686Y1736142D01*
G03X232414Y1736222I-272J-421D01*
G01X229398D01*
G03X229126Y1736142I0J-501D01*
G01X229101Y1736126D01*
X229048Y1736110D01*
X74612D01*
G02X74464Y1736176I1J200D01*
G03X73263Y1737423I-23279J-21219D01*
G01X73220Y1737466D01*
X73195Y1737584D01*
X73358Y1737984D01*
G02X73544Y1738108I185J-76D01*
G37*
G36*
G01D02*
X373307D01*
G02X373493Y1737984I1J-200D01*
G01X373656Y1737584D01*
X373631Y1737466D01*
X373588Y1737423D01*
G03X372387Y1736176I22078J-22466D01*
G02X372239Y1736110I-149J134D01*
G01X345740D01*
X345709Y1736121D01*
G03X345079Y1736222I-629J-1909D01*
G03X344449Y1736121I-1J-2010D01*
G01X344418Y1736110D01*
X329992D01*
X329961Y1736121D01*
G03X329331Y1736222I-629J-1909D01*
G03X328701Y1736121I-1J-2010D01*
G01X328670Y1736110D01*
X314244D01*
X314213Y1736121D01*
G03X313583Y1736222I-629J-1909D01*
G03X312953Y1736121I-1J-2010D01*
G01X312922Y1736110D01*
X299693D01*
X299640Y1736126D01*
X299615Y1736142D01*
G03X299344Y1736222I-272J-421D01*
G01X296326D01*
G03X296055Y1736142I1J-501D01*
G01X296030Y1736126D01*
X295977Y1736110D01*
X278811D01*
X278780Y1736121D01*
G03X278150Y1736222I-629J-1909D01*
G03X277520Y1736121I-1J-2010D01*
G01X277489Y1736110D01*
X263063D01*
X263032Y1736121D01*
G03X262402Y1736222I-629J-1909D01*
G03X261772Y1736121I-1J-2010D01*
G01X261741Y1736110D01*
X247315D01*
X247284Y1736121D01*
G03X246654Y1736222I-629J-1909D01*
G03X246024Y1736121I-1J-2010D01*
G01X245993Y1736110D01*
X232764D01*
X232711Y1736126D01*
X232686Y1736142D01*
G03X232414Y1736222I-272J-421D01*
G01X229398D01*
G03X229126Y1736142I0J-501D01*
G01X229101Y1736126D01*
X229048Y1736110D01*
X74612D01*
G02X74464Y1736176I1J200D01*
G03X73263Y1737423I-23279J-21219D01*
G01X73220Y1737466D01*
X73195Y1737584D01*
X73358Y1737984D01*
G02X73544Y1738108I185J-76D01*
G37*
G36*
G01X81916Y17042D02*
G03I-720J0D01*
G37*
G36*
G01Y22034D02*
G03I-720J0D01*
G37*
G36*
G01X86872Y17042D02*
G03I-720J0D01*
G37*
G36*
G01Y22034D02*
G03I-720J0D01*
G37*
G36*
G01X79916Y19538D02*
G03I-720J0D01*
G37*
G36*
G01X88872D02*
G03I-720J0D01*
G37*
G36*
G01X94089D02*
G03I-720J0D01*
G37*
G36*
G01X79767Y23978D02*
G03I-720J0D01*
G37*
G36*
G01X88984D02*
G03I-720J0D01*
G37*
G36*
G01X93940D02*
G03I-720J0D01*
G37*
G36*
G01X86984Y25974D02*
G03I-720J0D01*
G37*
G36*
G01X81767D02*
G03I-720J0D01*
G37*
G36*
G01X81099Y69340D02*
G03I-720J0D01*
G37*
G36*
G01X90055D02*
G03I-720J0D01*
G37*
G36*
G01X83099Y66844D02*
G03I-720J0D01*
G37*
G36*
G01X88055D02*
G03I-720J0D01*
G37*
G36*
G01X83099Y71836D02*
G03I-720J0D01*
G37*
G36*
G01X88055D02*
G03I-720J0D01*
G37*
G36*
G01X79055Y75340D02*
G03I-720J0D01*
G37*
G36*
G01X92099D02*
G03I-720J0D01*
G37*
G36*
G01X94099Y72844D02*
G03I-720J0D01*
G37*
G36*
G01Y77836D02*
G03I-720J0D01*
G37*
G36*
G01X80396Y443983D02*
X82457D01*
G03X82961Y443754I863J1229D01*
G01X83015Y443740D01*
X83596Y443159D01*
Y439781D01*
G03Y437257I813J-1262D01*
G01Y435783D01*
X84496Y434883D01*
X95596D01*
X100696Y429783D01*
X108896D01*
X108996Y429683D01*
Y428683D01*
X108896Y428583D01*
X102796D01*
X102196Y427983D01*
X95996D01*
X95096Y427083D01*
X90496D01*
X90196Y427383D01*
Y429983D01*
X89596Y430583D01*
X80696D01*
X79896Y431383D01*
Y443483D01*
X80396Y443983D01*
G37*
G36*
G01X81180Y655672D02*
G03I-720J0D01*
G37*
G36*
G01X91400Y704074D02*
X91500Y704174D01*
X92400D01*
X92500Y704074D01*
Y701162D01*
X93200Y700462D01*
X95061D01*
X95692Y699831D01*
X95694Y699751D01*
G03X96163Y698654I1601J36D01*
G01X96820Y697996D01*
Y695562D01*
X96520Y695262D01*
X94652D01*
X93420Y696494D01*
X91125D01*
X90743Y696876D01*
Y699586D01*
X91400Y700242D01*
Y702178D01*
X91410Y702208D01*
G03X91482Y702670I-1429J459D01*
G03X91410Y703132I-1501J3D01*
G01X91400Y703162D01*
Y704074D01*
G37*
G36*
G01X93543Y704930D02*
X95870D01*
X96144Y704656D01*
Y702704D01*
X94904Y701464D01*
X94126D01*
X93502Y702088D01*
Y704489D01*
X93402Y704589D01*
G02X93543Y704930I141J141D01*
G37*
G36*
G01X91515Y712821D02*
Y715949D01*
X90640Y716824D01*
X90565Y716899D01*
Y723244D01*
X90825Y723504D01*
X92385D01*
X92665Y723224D01*
Y719649D01*
Y716157D01*
X92430Y715922D01*
Y713094D01*
X92060Y712724D01*
X91612D01*
X91515Y712821D01*
G37*
G36*
G01X112035Y700464D02*
X103263D01*
X102993Y700734D01*
Y706016D01*
Y710089D01*
X102220Y710862D01*
X99320D01*
X98321Y709863D01*
X86189D01*
X85836Y710216D01*
Y710673D01*
X86006Y710843D01*
X96020D01*
Y710862D01*
X98020Y712862D01*
Y715662D01*
X98620Y716262D01*
X110278D01*
X114460D01*
X115060Y715662D01*
Y700912D01*
X114612Y700464D01*
X112035D01*
G37*
G36*
G01X96089Y17042D02*
G03I-720J0D01*
G37*
G36*
G01Y22034D02*
G03I-720J0D01*
G37*
G36*
G01X101045Y17042D02*
G03I-720J0D01*
G37*
G36*
G01Y22034D02*
G03I-720J0D01*
G37*
G36*
G01X110262Y17042D02*
G03I-720J0D01*
G37*
G36*
G01Y22034D02*
G03I-720J0D01*
G37*
G36*
G01X103045Y19538D02*
G03I-720J0D01*
G37*
G36*
G01X108262D02*
G03I-720J0D01*
G37*
G36*
G01X95940Y25974D02*
G03I-720J0D01*
G37*
G36*
G01X103157Y23978D02*
G03I-720J0D01*
G37*
G36*
G01X108113D02*
G03I-720J0D01*
G37*
G36*
G01X101157Y25974D02*
G03I-720J0D01*
G37*
G36*
G01X110113D02*
G03I-720J0D01*
G37*
G36*
G01X103099Y69340D02*
G03I-720J0D01*
G37*
G36*
G01X105099Y66844D02*
G03I-720J0D01*
G37*
G36*
G01X110055D02*
G03I-720J0D01*
G37*
G36*
G01X105099Y71836D02*
G03I-720J0D01*
G37*
G36*
G01X110055D02*
G03I-720J0D01*
G37*
G36*
G01X99055Y72844D02*
G03I-720J0D01*
G37*
G36*
G01Y77836D02*
G03I-720J0D01*
G37*
G36*
G01X101055Y75340D02*
G03I-720J0D01*
G37*
G36*
G01X100220Y407462D02*
X100620Y407862D01*
X105520D01*
X106320Y407062D01*
Y399862D01*
X105820Y399362D01*
X101420D01*
X100220Y400562D01*
Y407462D01*
G37*
G36*
G01X98260Y641547D02*
Y642139D01*
X98310Y642189D01*
X101509D01*
Y656126D01*
X101709Y656326D01*
X116109D01*
X116309Y656126D01*
Y643790D01*
X116335Y643764D01*
X119454D01*
X119558Y643660D01*
Y641581D01*
X119466Y641489D01*
X116249D01*
X116209Y641529D01*
X101681D01*
X101680Y641528D01*
Y641489D01*
X98318D01*
X98260Y641547D01*
G37*
G36*
G01X115218Y17042D02*
G03I-720J0D01*
G37*
G36*
G01Y22034D02*
G03I-720J0D01*
G37*
G36*
G01X124436Y17042D02*
G03I-720J0D01*
G37*
G36*
G01Y22034D02*
G03I-720J0D01*
G37*
G36*
G01X117218Y19538D02*
G03I-720J0D01*
G37*
G36*
G01X122436D02*
G03I-720J0D01*
G37*
G36*
G01X122287Y23978D02*
G03I-720J0D01*
G37*
G36*
G01X117331D02*
G03I-720J0D01*
G37*
G36*
G01X115331Y25974D02*
G03I-720J0D01*
G37*
G36*
G01X124287D02*
G03I-720J0D01*
G37*
G36*
G01X112055Y69340D02*
G03I-720J0D01*
G37*
G36*
G01X125099D02*
G03I-720J0D01*
G37*
G36*
G01X127099Y66844D02*
G03I-720J0D01*
G37*
G36*
G01Y71836D02*
G03I-720J0D01*
G37*
G36*
G01X116099Y72844D02*
G03I-720J0D01*
G37*
G36*
G01Y77836D02*
G03I-720J0D01*
G37*
G36*
G01X121055Y72844D02*
G03I-720J0D01*
G37*
G36*
G01Y77836D02*
G03I-720J0D01*
G37*
G36*
G01X123055Y75340D02*
G03I-720J0D01*
G37*
G36*
G01X114099D02*
G03I-720J0D01*
G37*
G36*
G01X118491Y493320D02*
X112702D01*
X112464Y493558D01*
Y495266D01*
X112733Y495535D01*
Y497275D01*
X114723Y499265D01*
Y502748D01*
X115614Y503639D01*
X117887D01*
X117950Y503576D01*
Y496087D01*
X118766Y495271D01*
Y493595D01*
X118491Y493320D01*
G37*
G36*
G01X133425Y517768D02*
X119025D01*
X118993Y517736D01*
Y503165D01*
X119025Y503133D01*
X119190Y502968D01*
X133425D01*
X133625Y503168D01*
Y517568D01*
X133425Y517768D01*
G37*
G36*
G01X119560Y655697D02*
Y664042D01*
X118672Y664930D01*
X112928D01*
X112602Y664604D01*
Y661476D01*
X113286Y660792D01*
X116739D01*
X117130Y660401D01*
Y655710D01*
X117325Y655515D01*
X119378D01*
X119560Y655697D01*
G37*
G36*
G01X128420Y731037D02*
X168874D01*
X171442Y728468D01*
Y708619D01*
X170369Y707546D01*
X168545Y705722D01*
X160600D01*
X159740Y706582D01*
Y708072D01*
Y722982D01*
X158345Y724377D01*
X156954D01*
X145520D01*
X144527Y723384D01*
Y687117D01*
X144156Y686746D01*
X143153D01*
X142220D01*
X130851D01*
X126336D01*
X124874Y688208D01*
Y692723D01*
Y727491D01*
X128420Y731037D01*
G37*
G36*
G01X137680Y1005732D02*
Y995932D01*
X120400D01*
Y1005732D01*
X137680D01*
G37*
G36*
G01X117746Y1730422D02*
G03I-491J0D01*
G37*
G36*
G01X129392Y17042D02*
G03I-720J0D01*
G37*
G36*
G01Y22034D02*
G03I-720J0D01*
G37*
G36*
G01X131392Y19538D02*
G03I-720J0D01*
G37*
G36*
G01X134055Y69340D02*
G03I-720J0D01*
G37*
G36*
G01X132055Y66844D02*
G03I-720J0D01*
G37*
G36*
G01Y71836D02*
G03I-720J0D01*
G37*
G36*
G01X138099Y72844D02*
G03I-720J0D01*
G37*
G36*
G01Y77836D02*
G03I-720J0D01*
G37*
G36*
G01X143055Y72844D02*
G03I-720J0D01*
G37*
G36*
G01Y77836D02*
G03I-720J0D01*
G37*
G36*
G01X136099Y75340D02*
G03I-720J0D01*
G37*
G36*
G01X137021Y179095D02*
G03I-720J0D01*
G37*
G36*
G01X144060Y204622D02*
G03I-720J0D01*
G37*
G36*
G01X127926Y480216D02*
G03I-720J0D01*
G37*
G36*
G01X134490Y1355932D02*
X223130D01*
X223967Y1355095D01*
Y1328574D01*
G03X223287Y1326895I1821J-1715D01*
G01X223286Y1326859D01*
G03X223382Y1326174I2502J1D01*
G01X223409Y1326078D01*
X223157Y1325744D01*
G02X222997Y1325665I-159J121D01*
G01X220670D01*
G03X220528Y1325606I0J-200D01*
G01X219487Y1324565D01*
X134747D01*
X133220Y1326092D01*
Y1354662D01*
X134490Y1355932D01*
G37*
G36*
G01X224420Y1433442D02*
X247570D01*
X252280Y1428732D01*
Y1359022D01*
X250411Y1357153D01*
X234405D01*
X138919D01*
X134169D01*
X133140Y1358182D01*
Y1388602D01*
X134389Y1389851D01*
X139833D01*
X145887D01*
X146697Y1390661D01*
X151967D01*
X153659Y1388969D01*
X159743D01*
X159898Y1389124D01*
X159980Y1389206D01*
Y1392634D01*
Y1392752D01*
X159760Y1392972D01*
X156690D01*
X156310Y1393352D01*
X154310D01*
X154190Y1393472D01*
Y1394162D01*
X154270Y1394242D01*
X155931D01*
X156217Y1394528D01*
X156499Y1394810D01*
X156558Y1394952D01*
Y1398270D01*
X156499Y1398412D01*
X156417Y1398494D01*
X156275Y1398553D01*
X153241D01*
X153099Y1398612D01*
X153088Y1398623D01*
X153058Y1398696D01*
Y1399486D01*
X153117Y1399628D01*
X153128Y1399639D01*
X153201Y1399669D01*
X156275D01*
X156417Y1399728D01*
X156499Y1399810D01*
X156558Y1399952D01*
Y1400686D01*
X156617Y1400828D01*
X156699Y1400910D01*
X156841Y1400969D01*
X163475D01*
X163617Y1400910D01*
X163799Y1400728D01*
G02X163841Y1400667I-141J-142D01*
G01Y1392164D01*
X164239Y1391766D01*
X164303Y1391702D01*
X173510D01*
X173574Y1391766D01*
X178155D01*
X178166Y1391756D01*
X178173Y1391763D01*
X183191D01*
X183912Y1392484D01*
Y1401626D01*
X181818Y1403720D01*
Y1412488D01*
X184235Y1414905D01*
X186469D01*
X186706Y1414668D01*
Y1405299D01*
X186102Y1404695D01*
Y1391334D01*
X186712Y1390724D01*
X189848D01*
X191603Y1388969D01*
X197886D01*
X197947D01*
X198100Y1389122D01*
Y1392842D01*
X198020Y1392922D01*
X194132D01*
X193960Y1393094D01*
X193712Y1393342D01*
X192440D01*
X192330Y1393452D01*
Y1394132D01*
X192450Y1394252D01*
X194084D01*
X194360Y1394528D01*
X194642Y1394810D01*
X194701Y1394952D01*
Y1398270D01*
X194642Y1398412D01*
X194560Y1398494D01*
X194418Y1398553D01*
X191384D01*
X191242Y1398612D01*
X191231Y1398623D01*
X191201Y1398696D01*
Y1399486D01*
X191260Y1399628D01*
X191271Y1399639D01*
X191344Y1399669D01*
X194418D01*
X194560Y1399728D01*
X194642Y1399810D01*
X194701Y1399952D01*
Y1400686D01*
X194760Y1400828D01*
X194842Y1400910D01*
X194984Y1400969D01*
X201618D01*
X201760Y1400910D01*
X201942Y1400728D01*
G02X201984Y1400667I-141J-142D01*
G01Y1392164D01*
X202382Y1391766D01*
X202476Y1391672D01*
X211610D01*
X211704Y1391766D01*
X216298D01*
X216309Y1391756D01*
X216316Y1391763D01*
X222215D01*
X222997Y1392545D01*
Y1432019D01*
X224420Y1433442D01*
G37*
G36*
G01X139571Y1731398D02*
G03I-491J0D01*
G37*
G36*
G01X160302Y17042D02*
G03I-720J0D01*
G37*
G36*
G01Y22034D02*
G03I-720J0D01*
G37*
G36*
G01X158302Y19538D02*
G03I-720J0D01*
G37*
G36*
G01X153197Y23978D02*
G03I-720J0D01*
G37*
G36*
G01X158153D02*
G03I-720J0D01*
G37*
G36*
G01X151197Y25974D02*
G03I-720J0D01*
G37*
G36*
G01X160153D02*
G03I-720J0D01*
G37*
G36*
G01X147099Y69340D02*
G03I-720J0D01*
G37*
G36*
G01X156055D02*
G03I-720J0D01*
G37*
G36*
G01X149099Y66844D02*
G03I-720J0D01*
G37*
G36*
G01X154055D02*
G03I-720J0D01*
G37*
G36*
G01X149099Y71836D02*
G03I-720J0D01*
G37*
G36*
G01X154055D02*
G03I-720J0D01*
G37*
G36*
G01X159303Y75340D02*
G03I-720J0D01*
G37*
G36*
G01X145055D02*
G03I-720J0D01*
G37*
G36*
G01X148621Y188852D02*
G03I-720J0D01*
G37*
G36*
G01X159845Y448664D02*
G03I-720J0D01*
G37*
G36*
G01X145725Y722924D02*
X156818D01*
X157650Y722092D01*
Y691457D01*
X152939Y686746D01*
X145920D01*
X145528Y687138D01*
Y722728D01*
X145725Y722924D01*
G37*
G36*
G01X220617Y1323808D02*
X223574D01*
X223737Y1323645D01*
Y1316275D01*
X223247Y1315785D01*
X155737D01*
X153637Y1317885D01*
Y1322818D01*
X154041Y1323221D01*
X156165D01*
G02X156504Y1322609I0J-400D01*
G03X155972Y1320753I2970J-1856D01*
G03X162976I3502J0D01*
G03X162444Y1322609I-3502J0D01*
G02X162783Y1323221I339J212D01*
G01X180523D01*
G02X180863Y1322612I-1J-400D01*
G03X180345Y1320778I2984J-1833D01*
G03X187349I3502J0D01*
G03X186831Y1322612I-3502J1D01*
G02X187171Y1323221I341J209D01*
G01X204923D01*
G02X205263Y1322612I-1J-400D01*
G03X204745Y1320778I2984J-1833D01*
G03X211749I3502J0D01*
G03X211231Y1322612I-3502J1D01*
G02X211571Y1323221I341J209D01*
G01X220030D01*
X220617Y1323808D01*
G37*
G36*
G01X152415Y1550043D02*
X162044D01*
X162354Y1549733D01*
Y1540456D01*
X161816Y1539918D01*
X152766D01*
X152301Y1540383D01*
Y1543118D01*
X151868Y1543551D01*
X148928D01*
X148731Y1543748D01*
Y1544275D01*
X148916Y1544460D01*
X152034D01*
X152239Y1544665D01*
Y1549867D01*
X152415Y1550043D01*
G37*
G36*
G01X145345Y1702389D02*
G03I-491J0D01*
G37*
G36*
G01X155294Y1708532D02*
G03I-491J0D01*
G37*
G36*
G01X165258Y17042D02*
G03I-720J0D01*
G37*
G36*
G01Y22034D02*
G03I-720J0D01*
G37*
G36*
G01X174475Y17042D02*
G03I-720J0D01*
G37*
G36*
G01Y22034D02*
G03I-720J0D01*
G37*
G36*
G01X167258Y19538D02*
G03I-720J0D01*
G37*
G36*
G01X172475D02*
G03I-720J0D01*
G37*
G36*
G01X167370Y23978D02*
G03I-720J0D01*
G37*
G36*
G01X172326D02*
G03I-720J0D01*
G37*
G36*
G01X165370Y25974D02*
G03I-720J0D01*
G37*
G36*
G01X174326D02*
G03I-720J0D01*
G37*
G36*
G01X170303Y69340D02*
G03I-720J0D01*
G37*
G36*
G01X172303Y66844D02*
G03I-720J0D01*
G37*
G36*
G01Y71836D02*
G03I-720J0D01*
G37*
G36*
G01X166259Y72844D02*
G03I-720J0D01*
G37*
G36*
G01X161303D02*
G03I-720J0D01*
G37*
G36*
G01Y77836D02*
G03I-720J0D01*
G37*
G36*
G01X166259D02*
G03I-720J0D01*
G37*
G36*
G01X168259Y75340D02*
G03I-720J0D01*
G37*
G36*
G01X163251Y405073D02*
X163328Y405150D01*
X170378D01*
X178458Y413230D01*
Y417553D01*
X179436Y418531D01*
X182935D01*
X183656Y417810D01*
Y408187D01*
X181906Y406437D01*
Y404096D01*
X181417Y403607D01*
X163380D01*
X163251Y403736D01*
Y405073D01*
G37*
G36*
G01D02*
X163328Y405150D01*
X170378D01*
X178458Y413230D01*
Y417553D01*
X179436Y418531D01*
X182935D01*
X183656Y417810D01*
Y408187D01*
X181906Y406437D01*
Y404096D01*
X181417Y403607D01*
X163380D01*
X163251Y403736D01*
Y405073D01*
G37*
G36*
G01X176360Y453779D02*
G03I-720J0D01*
G37*
G36*
G01X163470Y512502D02*
G03I-720J0D01*
G37*
G36*
G01X169053Y572039D02*
Y579280D01*
X169057Y579284D01*
Y580298D01*
X169669Y580910D01*
X191003D01*
X191615Y580298D01*
Y579284D01*
X191619Y579280D01*
Y572039D01*
X191039Y571460D01*
X169633D01*
X169053Y572039D01*
G37*
G36*
G01X173628Y1441685D02*
X212500D01*
X213911Y1440274D01*
Y1432719D01*
X215847Y1430783D01*
X221066D01*
X221807Y1430042D01*
Y1393257D01*
X221327Y1392777D01*
X203479D01*
X203393Y1392785D01*
X203341Y1392841D01*
X203205Y1392977D01*
Y1401145D01*
G02X203312Y1401176I107J-169D01*
G01X208494D01*
G03X208636Y1401235I0J200D01*
G01X209178Y1401777D01*
G03X209237Y1401919I-141J142D01*
G01Y1404405D01*
X209271Y1404487D01*
G03X209286Y1404563I-185J76D01*
G01Y1414303D01*
G03X209227Y1414445I-200J0D01*
G01X207656Y1416016D01*
G03X207514Y1416075I-142J-141D01*
G01X183959D01*
G03X183817Y1416016I0J-200D01*
G01X180921Y1413120D01*
G03X180862Y1412978I141J-142D01*
G01Y1403223D01*
G03X180921Y1403081I200J0D01*
G01X182773Y1401229D01*
X182831Y1401170D01*
Y1392977D01*
X182631Y1392777D01*
X165032D01*
Y1400933D01*
X165210Y1401111D01*
X165269Y1401169D01*
X170531D01*
G03X170673Y1401228I0J200D01*
G01X171072Y1401627D01*
G03X171131Y1401769I-141J142D01*
G01Y1402145D01*
X171132Y1402155D01*
Y1404519D01*
G03X171124Y1404627I-799J-5D01*
G01X171110Y1404726D01*
X172586Y1406203D01*
G03X172645Y1406345I-141J142D01*
G01Y1440703D01*
X173569Y1441627D01*
X173628Y1441685D01*
G37*
G36*
G01X167152Y1721211D02*
G03I-491J0D01*
G37*
G36*
G01X179431Y17042D02*
G03I-720J0D01*
G37*
G36*
G01Y22034D02*
G03I-720J0D01*
G37*
G36*
G01X181431Y19538D02*
G03I-720J0D01*
G37*
G36*
G01X177259Y66844D02*
G03I-720J0D01*
G37*
G36*
G01X192303Y69340D02*
G03I-720J0D01*
G37*
G36*
G01X179259D02*
G03I-720J0D01*
G37*
G36*
G01X177259Y71836D02*
G03I-720J0D01*
G37*
G36*
G01X183303Y72844D02*
G03I-720J0D01*
G37*
G36*
G01Y77836D02*
G03I-720J0D01*
G37*
G36*
G01X188259Y72844D02*
G03I-720J0D01*
G37*
G36*
G01Y77836D02*
G03I-720J0D01*
G37*
G36*
G01X190259Y75340D02*
G03I-720J0D01*
G37*
G36*
G01X181303D02*
G03I-720J0D01*
G37*
G36*
G01X185210Y402203D02*
G03I-720J0D01*
G37*
G36*
G01X185620Y413262D02*
X193328D01*
G02X193690Y412692I0J-400D01*
G03X193548Y412055I1360J-637D01*
G03X194947Y410557I1502J0D01*
G02X195320Y410157I-27J-399D01*
G01Y408262D01*
X194420Y407362D01*
X186220D01*
X185420Y408162D01*
Y413062D01*
X185620Y413262D01*
G37*
G36*
G01X200216Y427362D02*
X201870D01*
X202560Y426672D01*
Y419893D01*
X201819Y419152D01*
X192240D01*
X190690Y417602D01*
Y415362D01*
X190460Y415132D01*
X185223D01*
X185031Y415324D01*
Y418964D01*
X183980Y420015D01*
Y423622D01*
X184212Y423854D01*
X184335Y423805D01*
G03X184971Y423682I635J1578D01*
G01X187371D01*
G03X189072Y425382I0J1701D01*
G01X189073Y425465D01*
X190970Y427362D01*
X197878D01*
G03X200216I1169J1263D01*
G37*
G36*
G01X192025Y430216D02*
G03I-720J0D01*
G37*
G36*
G01X188941Y454048D02*
G03I-720J0D01*
G37*
G36*
G01X184867Y447078D02*
G03I-720J0D01*
G37*
G36*
G01X183200Y706662D02*
X241700D01*
X243500Y704862D01*
Y672862D01*
X247700Y668662D01*
Y562662D01*
X246500Y561462D01*
X218700D01*
X217300Y562862D01*
Y570192D01*
X219400Y572292D01*
Y578362D01*
X219300Y578462D01*
X216200D01*
X214900Y577162D01*
Y575662D01*
X214720Y575482D01*
Y572606D01*
X213840D01*
Y575122D01*
X213700Y575262D01*
X209600D01*
X209400Y575062D01*
Y571662D01*
X209200Y571462D01*
X208600D01*
X208500Y571562D01*
Y575062D01*
X208300Y575262D01*
X207700D01*
X207300Y575662D01*
Y581762D01*
X207600Y582062D01*
X215700D01*
X216500Y582862D01*
Y598262D01*
X217400Y599162D01*
Y603462D01*
X219300Y605362D01*
Y612362D01*
X219100Y612562D01*
X216400D01*
X215000Y611162D01*
Y609362D01*
X214700Y609062D01*
Y606602D01*
X213830D01*
Y608832D01*
X213400Y609262D01*
X209800D01*
X209400Y608862D01*
Y605662D01*
X209200Y605462D01*
X208700D01*
X208500Y605662D01*
Y608802D01*
X208040Y609262D01*
X207600D01*
X207300Y609562D01*
Y615762D01*
X207500Y615962D01*
X215400D01*
X216600Y617162D01*
Y631462D01*
X217400Y632262D01*
Y638063D01*
X219400Y640063D01*
Y646262D01*
X219000Y646662D01*
X216000D01*
X214900Y645562D01*
Y643662D01*
X214700Y643462D01*
Y640606D01*
X213800D01*
Y643062D01*
X213600Y643262D01*
X209600D01*
X209400Y643062D01*
Y639662D01*
X209100Y639362D01*
X208700D01*
X208500Y639562D01*
Y643062D01*
X208300Y643262D01*
X207500D01*
X207200Y643562D01*
Y649462D01*
X207800Y650062D01*
X215400D01*
X216600Y651262D01*
Y670362D01*
X213700Y673262D01*
Y676662D01*
X213100Y677262D01*
Y684162D01*
X213000Y684262D01*
X209900D01*
X208800Y683162D01*
Y680862D01*
X208500Y680562D01*
X203000D01*
X202100Y681462D01*
Y687062D01*
X202500Y687462D01*
X209700D01*
X210300Y688062D01*
Y700162D01*
X208800Y701662D01*
X183200D01*
X182700Y702162D01*
Y706162D01*
X183200Y706662D01*
G37*
G36*
G01X188839Y1580678D02*
G03I-720J0D01*
G37*
G36*
G01Y1575686D02*
G03I-720J0D01*
G37*
G36*
G01Y1592590D02*
G03I-720J0D01*
G37*
G36*
G01Y1587598D02*
G03I-720J0D01*
G37*
G36*
G01X184313Y1720517D02*
G03I-491J0D01*
G37*
G36*
G01X204436Y17042D02*
G03I-720J0D01*
G37*
G36*
G01Y22034D02*
G03I-720J0D01*
G37*
G36*
G01X202436Y19538D02*
G03I-720J0D01*
G37*
G36*
G01X202287Y23978D02*
G03I-720J0D01*
G37*
G36*
G01X197331D02*
G03I-720J0D01*
G37*
G36*
G01X195331Y25974D02*
G03I-720J0D01*
G37*
G36*
G01X204287D02*
G03I-720J0D01*
G37*
G36*
G01X201259Y69340D02*
G03I-720J0D01*
G37*
G36*
G01X194303Y66844D02*
G03I-720J0D01*
G37*
G36*
G01X199259D02*
G03I-720J0D01*
G37*
G36*
G01X194303Y71836D02*
G03I-720J0D01*
G37*
G36*
G01X199259D02*
G03I-720J0D01*
G37*
G36*
G01X205437Y72844D02*
G03I-720J0D01*
G37*
G36*
G01Y77836D02*
G03I-720J0D01*
G37*
G36*
G01X203437Y75340D02*
G03I-720J0D01*
G37*
G36*
G01X199767Y428626D02*
G03I-720J0D01*
G37*
G36*
G01X196935Y447565D02*
G03I-720J0D01*
G37*
G36*
G01X193795Y1580678D02*
G03I-720J0D01*
G37*
G36*
G01Y1575686D02*
G03I-720J0D01*
G37*
G36*
G01X200899D02*
G03I-720J0D01*
G37*
G36*
G01X205855D02*
G03I-720J0D01*
G37*
G36*
G01X200899Y1580678D02*
G03I-720J0D01*
G37*
G36*
G01X205855D02*
G03I-720J0D01*
G37*
G36*
G01X193795Y1592590D02*
G03I-720J0D01*
G37*
G36*
G01Y1587598D02*
G03I-720J0D01*
G37*
G36*
G01X200899Y1592590D02*
G03I-720J0D01*
G37*
G36*
G01X205855D02*
G03I-720J0D01*
G37*
G36*
G01X200899Y1587598D02*
G03I-720J0D01*
G37*
G36*
G01X205855D02*
G03I-720J0D01*
G37*
G36*
G01X199095Y1599884D02*
G03I-720J0D01*
G37*
G36*
G01X194139D02*
G03I-720J0D01*
G37*
G36*
G01X206199D02*
G03I-720J0D01*
G37*
G36*
G01X194139Y1616788D02*
G03I-720J0D01*
G37*
G36*
G01Y1611796D02*
G03I-720J0D01*
G37*
G36*
G01X199095D02*
G03I-720J0D01*
G37*
G36*
G01X194139Y1604876D02*
G03I-720J0D01*
G37*
G36*
G01X199095D02*
G03I-720J0D01*
G37*
G36*
G01Y1616788D02*
G03I-720J0D01*
G37*
G36*
G01X206199Y1611796D02*
G03I-720J0D01*
G37*
G36*
G01Y1604876D02*
G03I-720J0D01*
G37*
G36*
G01Y1616788D02*
G03I-720J0D01*
G37*
G36*
G01X207720Y1631181D02*
G03I-491J0D01*
G37*
G36*
G01X193901Y1711606D02*
G03I-491J0D01*
G37*
G36*
G01X206073Y1700867D02*
G03I-491J0D01*
G37*
G36*
G01X193020Y1728947D02*
G03I-491J0D01*
G37*
G36*
G01X209392Y17042D02*
G03I-720J0D01*
G37*
G36*
G01Y22034D02*
G03I-720J0D01*
G37*
G36*
G01X218609Y17042D02*
G03I-720J0D01*
G37*
G36*
G01Y22034D02*
G03I-720J0D01*
G37*
G36*
G01X223565Y17042D02*
G03I-720J0D01*
G37*
G36*
G01Y22034D02*
G03I-720J0D01*
G37*
G36*
G01X211392Y19538D02*
G03I-720J0D01*
G37*
G36*
G01X216609D02*
G03I-720J0D01*
G37*
G36*
G01X209504Y25974D02*
G03I-720J0D01*
G37*
G36*
G01X216460Y23978D02*
G03I-720J0D01*
G37*
G36*
G01X211504D02*
G03I-720J0D01*
G37*
G36*
G01X218460Y25974D02*
G03I-720J0D01*
G37*
G36*
G01X216437Y66844D02*
G03I-720J0D01*
G37*
G36*
G01X221393D02*
G03I-720J0D01*
G37*
G36*
G01X214437Y69340D02*
G03I-720J0D01*
G37*
G36*
G01X223393D02*
G03I-720J0D01*
G37*
G36*
G01X216437Y71836D02*
G03I-720J0D01*
G37*
G36*
G01X221393D02*
G03I-720J0D01*
G37*
G36*
G01X210393Y72844D02*
G03I-720J0D01*
G37*
G36*
G01Y77836D02*
G03I-720J0D01*
G37*
G36*
G01X212393Y75340D02*
G03I-720J0D01*
G37*
G36*
G01X225437D02*
G03I-720J0D01*
G37*
G36*
G01X224050Y426467D02*
G03I-720J0D01*
G37*
G36*
G01X221594Y442079D02*
G03I-720J0D01*
G37*
G36*
G01X221563Y430004D02*
G03I-720J0D01*
G37*
G36*
G01X212959Y1580678D02*
G03I-720J0D01*
G37*
G36*
G01X217915D02*
G03I-720J0D01*
G37*
G36*
G01Y1575686D02*
G03I-720J0D01*
G37*
G36*
G01X212959D02*
G03I-720J0D01*
G37*
G36*
G01X225019D02*
G03I-720J0D01*
G37*
G36*
G01Y1580678D02*
G03I-720J0D01*
G37*
G36*
G01X212959Y1587598D02*
G03I-720J0D01*
G37*
G36*
G01X217915D02*
G03I-720J0D01*
G37*
G36*
G01X212959Y1592590D02*
G03I-720J0D01*
G37*
G36*
G01X217915D02*
G03I-720J0D01*
G37*
G36*
G01X225019Y1587598D02*
G03I-720J0D01*
G37*
G36*
G01Y1592590D02*
G03I-720J0D01*
G37*
G36*
G01X211155Y1599884D02*
G03I-720J0D01*
G37*
G36*
G01X223215D02*
G03I-720J0D01*
G37*
G36*
G01X218259D02*
G03I-720J0D01*
G37*
G36*
G01X211155Y1611796D02*
G03I-720J0D01*
G37*
G36*
G01Y1604876D02*
G03I-720J0D01*
G37*
G36*
G01Y1616788D02*
G03I-720J0D01*
G37*
G36*
G01X223215D02*
G03I-720J0D01*
G37*
G36*
G01X218259D02*
G03I-720J0D01*
G37*
G36*
G01X223215Y1604876D02*
G03I-720J0D01*
G37*
G36*
G01Y1611796D02*
G03I-720J0D01*
G37*
G36*
G01X218259Y1604876D02*
G03I-720J0D01*
G37*
G36*
G01Y1611796D02*
G03I-720J0D01*
G37*
G36*
G01X213175Y1720307D02*
G03I-491J0D01*
G37*
G36*
G01X225565Y19538D02*
G03I-720J0D01*
G37*
G36*
G01X227437Y72844D02*
G03I-720J0D01*
G37*
G36*
G01Y77836D02*
G03I-720J0D01*
G37*
G36*
G01X232393Y72844D02*
G03I-720J0D01*
G37*
G36*
G01Y77836D02*
G03I-720J0D01*
G37*
G36*
G01X234393Y75340D02*
G03I-720J0D01*
G37*
G36*
G01X238259Y174266D02*
G03I-720J0D01*
G37*
G36*
G01X229975Y1575686D02*
G03I-720J0D01*
G37*
G36*
G01Y1580678D02*
G03I-720J0D01*
G37*
G36*
G01X237079D02*
G03I-720J0D01*
G37*
G36*
G01Y1575686D02*
G03I-720J0D01*
G37*
G36*
G01X229975Y1587598D02*
G03I-720J0D01*
G37*
G36*
G01Y1592590D02*
G03I-720J0D01*
G37*
G36*
G01X237079D02*
G03I-720J0D01*
G37*
G36*
G01Y1587598D02*
G03I-720J0D01*
G37*
G36*
G01X230319Y1599884D02*
G03I-720J0D01*
G37*
G36*
G01X235275D02*
G03I-720J0D01*
G37*
G36*
G01X230319Y1604876D02*
G03I-720J0D01*
G37*
G36*
G01Y1611796D02*
G03I-720J0D01*
G37*
G36*
G01X235275Y1604876D02*
G03I-720J0D01*
G37*
G36*
G01Y1611796D02*
G03I-720J0D01*
G37*
G36*
G01X230319Y1616788D02*
G03I-720J0D01*
G37*
G36*
G01X235275D02*
G03I-720J0D01*
G37*
G36*
G01X244210Y23002D02*
G03I-720J0D01*
G37*
G36*
G01X247100Y36760D02*
X260380D01*
X260720Y36420D01*
Y35572D01*
X261650Y34642D01*
Y26432D01*
X261350Y26132D01*
X249540D01*
X246680Y28992D01*
Y36340D01*
X247100Y36760D01*
G37*
G36*
G01X260007Y105883D02*
X260037Y105913D01*
X274807D01*
X274847Y105873D01*
Y97933D01*
X277277Y95503D01*
X286857D01*
X289357Y93003D01*
Y68403D01*
X292157Y65603D01*
X305857D01*
X311927Y71673D01*
Y75574D01*
X311931Y75593D01*
G03X311961Y75892I-1472J299D01*
G03X311931Y76191I-1502J0D01*
G01X311927Y76210D01*
Y84663D01*
X312167Y84903D01*
X312637D01*
X312887Y84653D01*
Y77353D01*
X313607Y76633D01*
X315177D01*
X315877Y77333D01*
Y82703D01*
X316097Y82923D01*
X316667D01*
X316857Y82733D01*
Y77993D01*
X317957Y76893D01*
Y53721D01*
X304615D01*
X304587Y53730D01*
G03X303984Y53847I-870J-2873D01*
G03X301310Y55484I-2674J-1365D01*
G03X299131Y54547I0J-3002D01*
G03X298550Y54604I-582J-2945D01*
G03X297450Y54395I1J-3002D01*
G03X295524Y55094I-1926J-2304D01*
G03X294161Y54767I0J-3002D01*
G03X292590Y55738I-1571J-785D01*
G03X291379Y55255I-1J-1756D01*
G02X290788Y55299I-276J289D01*
G03X289400Y55978I-1387J-1077D01*
G03X287644Y54222I0J-1756D01*
G01Y54136D01*
G02X287345Y53962I-200J0D01*
G03X286500Y54184I-846J-1500D01*
G03X285326Y53721I1J-1722D01*
G01X277479D01*
X267091Y43333D01*
X267007Y43334D01*
X266990D01*
G03X265488Y41832I0J-1502D01*
G01Y41815D01*
X265489Y41731D01*
X264678Y40920D01*
X254153D01*
G03X254050Y40924I-110J-1498D01*
G03X253947Y40920I7J-1502D01*
G01X247762D01*
X246820Y41862D01*
Y50185D01*
X249797Y53162D01*
X259810D01*
X261130Y54482D01*
Y66752D01*
X260020Y67862D01*
Y82762D01*
X260220Y82962D01*
Y85970D01*
X260007Y86183D01*
Y105883D01*
G37*
G36*
G01X246920Y81862D02*
X256120D01*
X257620Y80362D01*
Y67762D01*
X259520Y65862D01*
Y55762D01*
X258920Y55162D01*
X255720D01*
X255120Y55762D01*
Y65962D01*
X251387Y69695D01*
X251380Y69767D01*
G03X249885Y71125I-1495J-144D01*
G03X248639Y70462I0J-1502D01*
G01X245620D01*
X244720Y71362D01*
Y79662D01*
X246920Y81862D01*
G37*
G36*
G01X257657Y105893D02*
X259006D01*
Y86442D01*
X258957Y86393D01*
X256157D01*
X255557Y86993D01*
Y99560D01*
X257357Y101360D01*
Y105593D01*
X257657Y105893D01*
G37*
G36*
G01X250397Y105643D02*
X252897D01*
X253497Y105043D01*
Y96343D01*
X252997Y95843D01*
X250097D01*
X249898Y96042D01*
Y105144D01*
X250397Y105643D01*
G37*
G36*
G01X247997Y90343D02*
X246097Y92243D01*
Y105443D01*
X246297Y105643D01*
X248797D01*
X248897Y105543D01*
Y94943D01*
X249697Y94143D01*
X253097D01*
X253397Y93843D01*
Y90843D01*
X252897Y90343D01*
X247997D01*
G37*
G36*
G01X246203Y117143D02*
X247797D01*
X248197Y116743D01*
Y110443D01*
X248097Y110343D01*
X244097D01*
X243397Y111043D01*
Y116011D01*
G03X244594Y116746I-1197J3291D01*
G01X244652Y116800D01*
X244940D01*
G03X246203Y117143I-1J2502D01*
G37*
G36*
G01X249570Y117112D02*
X258630D01*
X258990Y116752D01*
Y114162D01*
X258620Y113792D01*
X250160D01*
X249300Y114652D01*
Y116842D01*
X249570Y117112D01*
G37*
G36*
G01X249497Y135243D02*
X280197D01*
X281197Y134243D01*
Y126343D01*
X280597Y125743D01*
X277046D01*
Y126576D01*
X277282D01*
Y127630D01*
G03X277054Y128225I-890J0D01*
G01Y128767D01*
X277082Y128815D01*
G03X277299Y129592I-1285J778D01*
G03X274295I-1502J0D01*
G03X274512Y128815I1502J1D01*
G01X274540Y128767D01*
Y128225D01*
G03X274312Y127630I662J-595D01*
G01Y126576D01*
X274548D01*
Y125743D01*
X270797D01*
X270297Y126243D01*
Y128443D01*
X269197Y129543D01*
X263297D01*
X262697Y128943D01*
Y126443D01*
X262397Y126143D01*
X249277D01*
X248937Y126483D01*
Y134683D01*
X249497Y135243D01*
G37*
G36*
G01X250020Y510362D02*
G03I-720J0D01*
G37*
G36*
G01X254520Y515362D02*
G03I-720J0D01*
G37*
G36*
G01X250580Y518222D02*
G03I-720J0D01*
G37*
G36*
G01X286582Y629255D02*
G03X287483Y629556I-1J1502D01*
G01X288382D01*
G03X289033Y629272I652J606D01*
G01X290086D01*
X290301Y629361D01*
X291600Y628062D01*
Y619162D01*
X288000Y615562D01*
Y570915D01*
G03X287928Y570798I2094J-1369D01*
G01X287486D01*
Y571034D01*
X286433D01*
G03X285782Y570750I1J-890D01*
G01X285385D01*
X285334Y570785D01*
G03X284482Y571050I-852J-1237D01*
G03Y568046I0J-1502D01*
G03X285334Y568311I0J1502D01*
G01X285385Y568346D01*
X285782D01*
G03X286433Y568062I652J606D01*
G01X287486D01*
Y568298D01*
X287928D01*
G03X288000Y568181I2166J1252D01*
G01Y567390D01*
X287970Y567342D01*
G03X287594Y566022I2125J-1319D01*
G03X288000Y564655I2501J-1D01*
G01Y562162D01*
X287400Y561562D01*
X249200D01*
X248608Y562154D01*
X248702Y562247D01*
Y626725D01*
X254838Y632862D01*
X267342D01*
X271630Y637150D01*
X279500D01*
X283788Y632862D01*
X284358D01*
X284500Y632720D01*
X285908D01*
X285945Y632705D01*
G03X286250Y632614I637J1578D01*
G01X286411Y632418D01*
X286255Y632223D01*
G03X285080Y630757I327J-1466D01*
G03X286582Y629255I1502J0D01*
G37*
G36*
G01X260128Y670720D02*
X266068Y676660D01*
G02X266750Y676377I282J-283D01*
G01Y673160D01*
G03X267152Y672758I402J0D01*
G01X273352D01*
G03X273754Y673160I0J402D01*
G01Y678572D01*
X274611D01*
G02X274962Y677981I-1J-400D01*
G03X274524Y676260I3164J-1721D01*
G03X281728I3602J0D01*
G03X281290Y677981I-3602J0D01*
G02X281641Y678572I352J191D01*
G01X282890D01*
X289100Y672362D01*
Y635783D01*
X288925Y635762D01*
G03X288143Y634872I108J-884D01*
G01X288144D01*
Y633990D01*
X285130D01*
X283198Y635922D01*
X283228D01*
X280540Y638610D01*
X271260D01*
X268572Y635922D01*
X255872D01*
X252014Y632064D01*
X248771D01*
X248702Y632134D01*
Y669077D01*
X248518Y669260D01*
Y670086D01*
X249152Y670720D01*
X260128D01*
G37*
G36*
G01X245100Y707572D02*
X276500D01*
X279535Y704537D01*
G02X279140Y703870I-283J-283D01*
G03X278126Y704016I-1015J-3456D01*
G03X281728Y700414I0J-3602D01*
G03X281582Y701428I-3602J-1D01*
G02X282249Y701823I384J112D01*
G01X286181Y697891D01*
Y691591D01*
X286240Y691449D01*
Y687062D01*
X286840Y686462D01*
X288200D01*
X288648Y686014D01*
X288607Y685895D01*
G03X288468Y685071I2362J-822D01*
G03X288775Y683869I2501J-1D01*
G01X288800Y683824D01*
Y682674D01*
X286948Y680822D01*
X267172D01*
X259200Y672850D01*
X245500D01*
X244502Y673849D01*
Y705277D01*
X244500Y705278D01*
Y706972D01*
X245100Y707572D01*
G37*
G36*
G01X242035Y1580678D02*
G03I-720J0D01*
G37*
G36*
G01Y1575686D02*
G03I-720J0D01*
G37*
G36*
G01X249139D02*
G03I-720J0D01*
G37*
G36*
G01X254095D02*
G03I-720J0D01*
G37*
G36*
G01X249139Y1580678D02*
G03I-720J0D01*
G37*
G36*
G01X254095D02*
G03I-720J0D01*
G37*
G36*
G01X242035Y1592590D02*
G03I-720J0D01*
G37*
G36*
G01Y1587598D02*
G03I-720J0D01*
G37*
G36*
G01X249139D02*
G03I-720J0D01*
G37*
G36*
G01X254095D02*
G03I-720J0D01*
G37*
G36*
G01X249139Y1592590D02*
G03I-720J0D01*
G37*
G36*
G01X254095D02*
G03I-720J0D01*
G37*
G36*
G01X247335Y1599884D02*
G03I-720J0D01*
G37*
G36*
G01X242379D02*
G03I-720J0D01*
G37*
G36*
G01X254439D02*
G03I-720J0D01*
G37*
G36*
G01X242379Y1616788D02*
G03I-720J0D01*
G37*
G36*
G01X247335D02*
G03I-720J0D01*
G37*
G36*
G01Y1604876D02*
G03I-720J0D01*
G37*
G36*
G01X242379D02*
G03I-720J0D01*
G37*
G36*
G01X247335Y1611796D02*
G03I-720J0D01*
G37*
G36*
G01X242379D02*
G03I-720J0D01*
G37*
G36*
G01X254439Y1604876D02*
G03I-720J0D01*
G37*
G36*
G01Y1611796D02*
G03I-720J0D01*
G37*
G36*
G01Y1616788D02*
G03I-720J0D01*
G37*
G36*
G01X264000Y35312D02*
G03I-720J0D01*
G37*
G36*
G01X273320Y27182D02*
G03I-720J0D01*
G37*
G36*
G01X272320Y40162D02*
G03I-720J0D01*
G37*
G36*
G01X281983Y117043D02*
X309587D01*
X314917Y111713D01*
Y89616D01*
X314911Y89591D01*
G03X314862Y89212I1453J-380D01*
G03X314911Y88833I1502J1D01*
G01X314917Y88808D01*
Y83159D01*
X314876Y83118D01*
Y78302D01*
X314637Y78063D01*
X314187D01*
X313977Y78273D01*
Y84783D01*
X313888Y84872D01*
Y85068D01*
X313052Y85904D01*
X311752D01*
X311691Y85843D01*
X311677D01*
X310927Y85093D01*
Y85079D01*
X310926Y85078D01*
Y80232D01*
X310737Y80043D01*
X310117D01*
X309987Y80173D01*
Y89513D01*
X308929Y90571D01*
Y94711D01*
G03X309322Y95724I-1109J1013D01*
G03X308975Y96684I-1501J0D01*
G01X308929Y96740D01*
Y96953D01*
X308020Y97862D01*
X300420D01*
X295039Y103243D01*
X280297D01*
X276658Y106882D01*
X275254D01*
X275222Y106914D01*
X259926D01*
X259497Y107343D01*
Y112243D01*
X259856Y112602D01*
X277542D01*
X281983Y117043D01*
G37*
G36*
G01X280230Y219722D02*
X287320D01*
X288340Y218702D01*
Y205642D01*
X285800Y203102D01*
X267800D01*
X267770Y203072D01*
X266980Y203862D01*
Y208162D01*
X267880Y209062D01*
X281760D01*
X282130Y209432D01*
Y209747D01*
X282153Y209790D01*
G03X282257Y210213I-786J418D01*
G01X282256D01*
Y211391D01*
X282257D01*
G03X282153Y211814I-890J5D01*
G01X282130Y211857D01*
Y213592D01*
X280080Y215642D01*
Y219572D01*
X280230Y219722D01*
G37*
G36*
G01X266660Y229022D02*
X266645Y229007D01*
Y227137D01*
X267530Y226252D01*
X270260D01*
X270860Y225652D01*
Y223602D01*
X270700Y223442D01*
X260420D01*
X259500Y224362D01*
Y228362D01*
X260410Y229272D01*
X266410D01*
X266660Y229022D01*
G37*
G36*
G01X297430Y249742D02*
X309940D01*
X311760Y247922D01*
Y238669D01*
X311920Y238509D01*
X312085D01*
Y224809D01*
X312521Y224373D01*
X312457Y224244D01*
G03X312247Y223352I1792J-893D01*
G03X314249Y221350I2002J0D01*
G03X314314Y221351I2J2002D01*
G01X314400Y221354D01*
X316436Y219319D01*
G03X317324Y218950I889J887D01*
G01X317943D01*
X318155Y218739D01*
X331145D01*
X331385Y218499D01*
Y218029D01*
X331135Y217779D01*
X323835D01*
X323115Y217059D01*
Y215489D01*
X323815Y214789D01*
X329185D01*
X329405Y214569D01*
Y213999D01*
X329215Y213809D01*
X324475D01*
X323375Y212709D01*
X312820D01*
X311600Y211489D01*
Y200172D01*
X314040Y197732D01*
X322370D01*
X323950Y196152D01*
Y185662D01*
X324050Y185562D01*
Y182272D01*
X322020Y180242D01*
X304520D01*
X291000Y193762D01*
Y218472D01*
X286830Y222642D01*
X274520D01*
X274471Y222672D01*
G03X274208Y222746I-263J-430D01*
G01X273666D01*
X272620Y223792D01*
Y225802D01*
X273340Y226522D01*
X283310D01*
X284630Y227842D01*
Y230162D01*
X285140Y230672D01*
X289230D01*
X295450Y236892D01*
Y247762D01*
X297430Y249742D01*
G37*
G36*
G01X259466Y407842D02*
G03I-720J0D01*
G37*
G36*
G01X258154Y415896D02*
G03I-720J0D01*
G37*
G36*
G01X261527Y424403D02*
G03I-720J0D01*
G37*
G36*
G01X261199Y1580678D02*
G03I-720J0D01*
G37*
G36*
G01X266155D02*
G03I-720J0D01*
G37*
G36*
G01X261199Y1575592D02*
G03I-720J0D01*
G37*
G36*
G01X266155D02*
G03I-720J0D01*
G37*
G36*
G01X273259Y1575686D02*
G03I-720J0D01*
G37*
G36*
G01Y1580678D02*
G03I-720J0D01*
G37*
G36*
G01X261199Y1592590D02*
G03I-720J0D01*
G37*
G36*
G01X266155D02*
G03I-720J0D01*
G37*
G36*
G01X261199Y1587598D02*
G03I-720J0D01*
G37*
G36*
G01X266155D02*
G03I-720J0D01*
G37*
G36*
G01X273259D02*
G03I-720J0D01*
G37*
G36*
G01Y1592590D02*
G03I-720J0D01*
G37*
G36*
G01X259395Y1599884D02*
G03I-720J0D01*
G37*
G36*
G01X271455Y1599790D02*
G03I-720J0D01*
G37*
G36*
G01X266499D02*
G03I-720J0D01*
G37*
G36*
G01X259395Y1604876D02*
G03I-720J0D01*
G37*
G36*
G01Y1611796D02*
G03I-720J0D01*
G37*
G36*
G01Y1616788D02*
G03I-720J0D01*
G37*
G36*
G01X271455D02*
G03I-720J0D01*
G37*
G36*
G01X266499D02*
G03I-720J0D01*
G37*
G36*
G01X271455Y1611796D02*
G03I-720J0D01*
G37*
G36*
G01Y1604876D02*
G03I-720J0D01*
G37*
G36*
G01X266499D02*
G03I-720J0D01*
G37*
G36*
G01Y1611796D02*
G03I-720J0D01*
G37*
G36*
G01X286620Y23962D02*
G03I-720J0D01*
G37*
G36*
G01X287220Y52462D02*
G03I-720J0D01*
G37*
G36*
G01X277757Y101903D02*
X294779D01*
X299820Y96862D01*
X300004D01*
X300005Y96860D01*
X302821D01*
X303520Y96162D01*
Y90762D01*
X303261Y90503D01*
X295157D01*
X295022Y90368D01*
X294970Y90354D01*
G03X293855Y88903I387J-1451D01*
G03X294841Y87492I1503J0D01*
G01X294883Y87477D01*
X294957Y87403D01*
X295284D01*
G03X295357Y87401I78J1500D01*
G03X295430Y87403I-5J1502D01*
G01X296917D01*
X297347Y86973D01*
Y81473D01*
X297418Y81402D01*
Y81234D01*
X297586D01*
X297857Y80963D01*
X301445D01*
X301455Y80962D01*
G03X301600Y80955I145J1495D01*
G03X301745Y80962I0J1502D01*
G01X301755Y80963D01*
X307597D01*
X308027Y81393D01*
Y82653D01*
X308317Y82943D01*
X308647D01*
X308947Y82643D01*
Y80203D01*
X308787Y80043D01*
X305947D01*
X303277Y77373D01*
X297189D01*
X296647Y76831D01*
Y74373D01*
X296447Y74173D01*
X290887D01*
X290557Y74503D01*
Y93803D01*
X287857Y96503D01*
X287273D01*
X287272Y96504D01*
X277692D01*
X275857Y98339D01*
Y100003D01*
X277757Y101903D01*
G37*
G36*
G01X289857Y134103D02*
X336957D01*
Y53735D01*
X336753Y53531D01*
X320237D01*
X319857Y53911D01*
Y62603D01*
X322064Y64810D01*
X328020D01*
G03X329435Y65397I-1J2002D01*
G01X331372Y67334D01*
G03X331958Y68749I-1415J1415D01*
G01Y93803D01*
G03X331957Y93877I-2001J10D01*
G01Y96503D01*
X325888Y102572D01*
X317620D01*
X316157Y104035D01*
Y112303D01*
X310357Y118103D01*
X287957D01*
X287857Y118203D01*
Y132103D01*
X289857Y134103D01*
G37*
G36*
G01X281390Y249592D02*
X291440D01*
X292820Y248212D01*
Y236842D01*
X287980Y232002D01*
X285180D01*
X284851Y231674D01*
X284725D01*
X283628Y230577D01*
Y230450D01*
X283130Y229952D01*
Y229192D01*
X282470Y228532D01*
X281850D01*
X280480Y229902D01*
Y248682D01*
X281390Y249592D01*
G37*
G36*
G01X288020Y567379D02*
Y564665D01*
X287868Y564513D01*
X283110D01*
Y567531D01*
X287868D01*
X288020Y567379D01*
G37*
G36*
G01X277793Y1304556D02*
X326144D01*
G02X326285Y1304498I0J-200D01*
G01X328617Y1302166D01*
X328675Y1302107D01*
Y1289210D01*
G03X328734Y1289068I200J0D01*
G01X336147Y1281655D01*
G03X336289Y1281596I142J141D01*
G01X359176D01*
X359235Y1281538D01*
X372109Y1268664D01*
G03X372251Y1268605I142J141D01*
G01X489094D01*
G03X489236Y1268664I0J200D01*
G01X502422Y1281850D01*
X502481Y1281908D01*
X520617D01*
G03X520759Y1281967I0J200D01*
G01X521778Y1282986D01*
G03X521837Y1283128I-141J142D01*
G01Y1287106D01*
X521895Y1287165D01*
X529616Y1294886D01*
G03X529675Y1295028I-141J142D01*
G01Y1297877D01*
X529733Y1297936D01*
X536147Y1304350D01*
X536206Y1304408D01*
X569541D01*
X569548Y1304401D01*
X593500D01*
X593520Y1304382D01*
X597980D01*
X600000Y1302362D01*
Y1250562D01*
X538815Y1189377D01*
Y1145284D01*
G03X538852Y1145168I200J0D01*
G01X538889Y1145116D01*
Y1139750D01*
X538830Y1139691D01*
X538568Y1139429D01*
X538509Y1139370D01*
X530859D01*
X530800Y1139429D01*
X529901Y1140328D01*
X529955Y1140454D01*
G03X530063Y1140964I-1194J519D01*
G01Y1140985D01*
G03X528773Y1142275I-1302J-12D01*
G01X528760D01*
G03X528242Y1142167I1J-1302D01*
G01X528116Y1142113D01*
X527537Y1142692D01*
G03X527395Y1142751I-142J-141D01*
G01X472337D01*
G03X472195Y1142692I0J-200D01*
G01X471800Y1142297D01*
G03X471741Y1142155I141J-142D01*
G01Y1139089D01*
X471438Y1138774D01*
X471358Y1138770D01*
G03X471067Y1138724I56J-1301D01*
G01X471041Y1138717D01*
X470812D01*
Y1138963D01*
G03X470511Y1139778I-1251J1D01*
G01X470462Y1139834D01*
Y1140030D01*
X470516Y1140088D01*
G03X470863Y1140973I-955J885D01*
G03X468259I-1302J0D01*
G03X468606Y1140088I1302J0D01*
G01X468660Y1140030D01*
Y1139834D01*
X468611Y1139778D01*
G03X468310Y1138963I950J-814D01*
G01Y1138563D01*
G03X469561Y1137312I1251J0D01*
G03X469651Y1137315I3J1251D01*
G03X469742Y1137324I-78J1249D01*
G01X469813Y1137334D01*
X470154Y1137125D01*
X470177Y1137056D01*
G03X470388Y1136664I1235J412D01*
G01X470408Y1136639D01*
X470454Y1136512D01*
X470452Y1136387D01*
X470401Y1136258D01*
X470380Y1136233D01*
G03X470060Y1135359I1034J-874D01*
G03X471357Y1134008I1352J0D01*
G01X471437Y1134005D01*
X471741Y1133689D01*
Y1132680D01*
X471438Y1132365D01*
X471358Y1132361D01*
G03X470110Y1131060I54J-1301D01*
G03X470388Y1130255I1302J-1D01*
G01X470408Y1130230D01*
X470454Y1130103D01*
X470452Y1129978D01*
X470401Y1129849D01*
X470380Y1129824D01*
G03X470128Y1129374I1032J-874D01*
G01X470117Y1129341D01*
X470031Y1129230D01*
X469926Y1129165D01*
G02X469787Y1129138I-105J170D01*
G03X469562Y1129158I-227J-1282D01*
G03X468260Y1127856I0J-1302D01*
G03X468558Y1127027I1302J0D01*
G02X468604Y1126896I-154J-128D01*
G01X468601Y1126774D01*
X468551Y1126646D01*
X468530Y1126620D01*
G03X468267Y1126138I1030J-875D01*
G01X468245Y1126065D01*
X468180Y1126025D01*
X468021Y1125927D01*
X467936Y1125934D01*
X467928Y1125935D01*
G03X467712Y1125953I-216J-1284D01*
G03X466410Y1124651I0J-1302D01*
G03X466688Y1123846I1302J-1D01*
G01X466708Y1123821D01*
X466754Y1123694D01*
X466752Y1123569D01*
X466701Y1123440D01*
X466680Y1123415D01*
G03X466428Y1122965I1032J-874D01*
G01X466417Y1122932D01*
X466331Y1122821D01*
X466226Y1122756D01*
G02X466087Y1122729I-105J170D01*
G03X465862Y1122749I-227J-1282D01*
G03X464560Y1121447I0J-1302D01*
G03X464858Y1120618I1302J0D01*
G02X464904Y1120487I-154J-128D01*
G01X464901Y1120365D01*
X464851Y1120237D01*
X464830Y1120211D01*
G03X464509Y1119337I1031J-875D01*
G03X465861Y1117985I1352J0D01*
G01X465864D01*
G03X466131Y1118012I-2J1352D01*
G01X466141Y1118014D01*
X466227Y1118022D01*
X466457Y1117893D01*
G03X466688Y1117438I1254J350D01*
G01X466708Y1117412D01*
X466753Y1117287D01*
X466751Y1117160D01*
X466701Y1117032D01*
X466680Y1117007D01*
G03X466428Y1116557I1032J-874D01*
G01X466417Y1116524D01*
X466331Y1116413D01*
X466226Y1116348D01*
G02X466087Y1116321I-105J170D01*
G03X465862Y1116341I-227J-1282D01*
G03X464560Y1115039I0J-1302D01*
G03X464858Y1114210I1302J0D01*
G02X464904Y1114079I-154J-128D01*
G01X464901Y1113957D01*
X464851Y1113829D01*
X464830Y1113803D01*
G03X464567Y1113321I1030J-875D01*
G01X464545Y1113248D01*
X464480Y1113208D01*
X464321Y1113110D01*
X464236Y1113117D01*
X464228Y1113118D01*
G03X464012Y1113136I-216J-1284D01*
G03X462710Y1111834I0J-1302D01*
G03X462988Y1111029I1302J-1D01*
G01X463008Y1111004D01*
X463054Y1110877D01*
X463052Y1110752D01*
X463001Y1110623D01*
X462980Y1110598D01*
G03X462728Y1110148I1032J-874D01*
G01X462717Y1110115D01*
X462631Y1110004D01*
X462526Y1109939D01*
G02X462387Y1109912I-105J170D01*
G03X462162Y1109932I-227J-1282D01*
G03X460860Y1108630I0J-1302D01*
G03X461158Y1107801I1302J0D01*
G02X461204Y1107670I-154J-128D01*
G01X461201Y1107548D01*
X461151Y1107420D01*
X461130Y1107394D01*
G03X460877Y1106944I1030J-875D01*
G01X460866Y1106911D01*
X460780Y1106800D01*
X460621Y1106702D01*
X460536Y1106709D01*
X460528Y1106710D01*
G03X460312Y1106728I-216J-1284D01*
G03X459010Y1105426I0J-1302D01*
G03X459288Y1104621I1302J-1D01*
G01X459308Y1104596D01*
X459354Y1104469D01*
X459352Y1104344D01*
X459301Y1104214D01*
X459280Y1104189D01*
G03X459028Y1103738I1032J-873D01*
G01X459017Y1103706D01*
X458931Y1103595D01*
X458759Y1103488D01*
G03X458462Y1103523I-300J-1267D01*
G03X457160Y1102221I0J-1302D01*
G03X457458Y1101392I1302J0D01*
G02X457504Y1101261I-154J-128D01*
G01X457501Y1101139D01*
X457451Y1101011D01*
X457430Y1100985D01*
G03X457177Y1100535I1030J-875D01*
G01X457166Y1100502D01*
X457080Y1100391D01*
X456975Y1100326D01*
G02X456836Y1100299I-105J170D01*
G03X456611Y1100319I-227J-1282D01*
G03X455309Y1099017I0J-1302D01*
G03X455588Y1098212I1301J0D01*
G01X455608Y1098186D01*
X455653Y1098061D01*
X455651Y1097934D01*
X455601Y1097806D01*
X455580Y1097781D01*
G03X455328Y1097331I1032J-874D01*
G01X455317Y1097298D01*
X455231Y1097187D01*
X455126Y1097122D01*
G02X454987Y1097095I-105J170D01*
G03X454762Y1097115I-227J-1282D01*
G03X454537Y1097095I2J-1302D01*
G02X454398Y1097122I-34J197D01*
G01X454293Y1097187D01*
X454207Y1097298D01*
X454196Y1097331D01*
G03X453943Y1097781I-1283J-425D01*
G01X453922Y1097807D01*
X453872Y1097935D01*
X453869Y1098057D01*
G02X453915Y1098188I200J3D01*
G03X454213Y1099017I-1004J829D01*
G03X451609I-1302J0D01*
G03X451888Y1098212I1301J0D01*
G01X451908Y1098186D01*
X451953Y1098061D01*
X451951Y1097934D01*
X451901Y1097806D01*
X451880Y1097781D01*
G03X451628Y1097331I1032J-874D01*
G01X451617Y1097298D01*
X451531Y1097187D01*
X451426Y1097122D01*
G02X451287Y1097095I-105J170D01*
G03X451062Y1097115I-227J-1282D01*
G03X449760Y1095813I0J-1302D01*
G03X450058Y1094984I1302J0D01*
G02X450104Y1094853I-154J-128D01*
G01X450101Y1094731D01*
X450051Y1094603D01*
X450030Y1094577D01*
G03X449804Y1093204I1031J-875D01*
G03X450850Y1092368I1256J500D01*
G01X450882Y1092362D01*
X451001Y1092300D01*
X451134Y1092157D01*
Y1090901D01*
X451002Y1090756D01*
G02X450882Y1090693I-148J135D01*
G03X449760Y1089404I179J-1289D01*
G03X449954Y1088720I1303J0D01*
G01X450037Y1088585D01*
X448923Y1087471D01*
X448872Y1087457D01*
G03X447910Y1086200I340J-1257D01*
G03X448176Y1085411I1303J0D01*
G01X448217Y1085357D01*
Y1085045D01*
X448193Y1084980D01*
X448171Y1084952D01*
X448170Y1084951D01*
G03X447928Y1084512I1042J-861D01*
G01X447917Y1084480D01*
X447831Y1084369D01*
X447698Y1084287D01*
X447624Y1084270D01*
G03X447361Y1084297I-264J-1275D01*
G03X446059Y1082995I0J-1302D01*
G03X446337Y1082190I1302J-1D01*
G01X446357Y1082165D01*
X446403Y1082038D01*
X446401Y1081913D01*
X446350Y1081784D01*
X446329Y1081759D01*
G03X446009Y1080885I1034J-874D01*
G03X446939Y1079600I1353J0D01*
G01X447077Y1079555D01*
Y1077866D01*
X446941Y1077820D01*
G03X446059Y1076587I421J-1233D01*
G03X446337Y1075782I1302J-1D01*
G01X446357Y1075757D01*
X446403Y1075630D01*
X446401Y1075505D01*
X446350Y1075376D01*
X446329Y1075351D01*
G03X446009Y1074477I1034J-874D01*
G03X446939Y1073192I1353J0D01*
G01X447077Y1073147D01*
Y1071457D01*
X446941Y1071411D01*
G03X446059Y1070178I421J-1233D01*
G03X446337Y1069373I1302J-1D01*
G01X446357Y1069348D01*
X446403Y1069221D01*
X446401Y1069096D01*
X446350Y1068967D01*
X446329Y1068942D01*
G03X446009Y1068068I1034J-874D01*
G03X446939Y1066783I1353J0D01*
G01X447077Y1066738D01*
Y1065049D01*
X446941Y1065003D01*
G03X446059Y1063770I421J-1233D01*
G03X446337Y1062965I1302J-1D01*
G01X446357Y1062940D01*
X446403Y1062813D01*
X446401Y1062688D01*
X446350Y1062559D01*
X446329Y1062534D01*
G03X446009Y1061660I1034J-874D01*
G03X446939Y1060375I1353J0D01*
G01X447077Y1060330D01*
Y1058640D01*
X446941Y1058594D01*
G03X446059Y1057361I421J-1233D01*
G03X446337Y1056556I1302J-1D01*
G01X446357Y1056531D01*
X446403Y1056404D01*
X446401Y1056279D01*
X446350Y1056150D01*
X446329Y1056125D01*
G03X446009Y1055251I1034J-874D01*
G03X446939Y1053966I1353J0D01*
G01X447077Y1053921D01*
Y1052231D01*
X446941Y1052185D01*
G03X446059Y1050952I421J-1233D01*
G03X446337Y1050147I1302J-1D01*
G01X446357Y1050122D01*
X446403Y1049995D01*
X446401Y1049870D01*
X446350Y1049741D01*
X446329Y1049716D01*
G03X446009Y1048842I1034J-874D01*
G03X446960Y1047551I1352J0D01*
G01X447007Y1047536D01*
X448108Y1046435D01*
X448034Y1046302D01*
G03X447860Y1045639I1178J-663D01*
G03X449212Y1044287I1352J0D01*
G01X449213D01*
G03X449481Y1044314I-1J1352D01*
G01X449491Y1044316D01*
X449578Y1044324D01*
X449808Y1044193D01*
G03X450037Y1043739I1255J348D01*
G01X450057Y1043714D01*
X450103Y1043587D01*
X450101Y1043462D01*
X450050Y1043333D01*
X450029Y1043308D01*
G03X449709Y1042434I1034J-874D01*
G03X451061Y1041082I1352J0D01*
G01X451064D01*
G03X451331Y1041109I-2J1352D01*
G01X451341Y1041111D01*
X451427Y1041119D01*
X451657Y1040990D01*
G03X451888Y1040535I1254J350D01*
G01X451908Y1040509D01*
X451953Y1040384D01*
X451951Y1040257D01*
X451901Y1040129D01*
X451880Y1040104D01*
G03X451560Y1039230I1034J-874D01*
G03X452912Y1037878I1352J0D01*
G01X452915D01*
G03X453182Y1037905I-2J1352D01*
G01X453192Y1037907D01*
X453278Y1037915D01*
X453508Y1037786D01*
G03X454596Y1036845I1254J350D01*
G01X454770Y1036823D01*
Y1025895D01*
X454711Y1025836D01*
X453064Y1024189D01*
G03X453005Y1024047I141J-142D01*
G01Y1019453D01*
G03X453064Y1019311I200J0D01*
G01X453876Y1018499D01*
G03X454018Y1018440I142J141D01*
G01X471615D01*
X471674Y1018382D01*
X472072Y1017984D01*
X472130Y1017925D01*
Y1016056D01*
X471703Y1015747D01*
X471606Y1015778D01*
G03X471204Y1015842I-403J-1238D01*
G03X470326Y1015501I0J-1301D01*
G01X470298Y1015475D01*
X470227Y1015448D01*
X469840Y1015449D01*
X469782Y1015503D01*
G03X468895Y1015852I-887J-953D01*
G03X467889Y1015376I0J-1301D01*
G01X467829Y1015303D01*
X467332Y1015302D01*
X467272Y1015374D01*
G03X466272Y1015842I-1000J-834D01*
G03X465300Y1015406I0J-1301D01*
G01X464846D01*
G03X463874Y1015842I-972J-865D01*
G03Y1013238I0J-1302D01*
G03X464846Y1013674I0J1301D01*
G01X465300D01*
G03X466272Y1013238I972J865D01*
G03X467278Y1013714I0J1301D01*
G01X467338Y1013787D01*
X467835Y1013788D01*
X467895Y1013716D01*
G03X468895Y1013248I1000J834D01*
G03X469773Y1013589I0J1301D01*
G01X469801Y1013615D01*
X469872Y1013642D01*
X470259Y1013641D01*
X470317Y1013587D01*
G03X471204Y1013238I887J953D01*
G03X471606Y1013302I-1J1302D01*
G01X471703Y1013333D01*
X472130Y1013024D01*
Y1011155D01*
X472071Y1011096D01*
X471644Y1010669D01*
X471585Y1010610D01*
X454944D01*
G03X454443Y1010711I-503J-1201D01*
G03X453942Y1010610I2J-1302D01*
G01X453821D01*
G03X453679Y1010551I0J-200D01*
G01X453589Y1010462D01*
X453587D01*
X453124Y1009998D01*
X453090Y1009961D01*
G03X453035Y1009824I145J-138D01*
G01Y1004883D01*
G03X453094Y1004741I200J0D01*
G01X453766Y1004069D01*
G03X453908Y1004010I142J141D01*
G01X471764D01*
X471823Y1003952D01*
X472180Y1003595D01*
X472238Y1003536D01*
Y996399D01*
X472179Y996340D01*
X472028Y996189D01*
X471969Y996130D01*
X456115D01*
X456056Y996189D01*
X455694Y996551D01*
G03X455552Y996610I-142J-141D01*
G01X453838D01*
G03X453696Y996551I0J-200D01*
G01X453104Y995959D01*
G03X453045Y995817I141J-142D01*
G01Y991333D01*
G03X453104Y991191I200J0D01*
G01X454666Y989629D01*
G03X454808Y989570I142J141D01*
G01X471584D01*
X471643Y989512D01*
X472177Y988978D01*
X472235Y988919D01*
Y982580D01*
X472176Y982521D01*
X471534Y981879D01*
X471475Y981820D01*
X460805D01*
X460786Y981801D01*
X458271D01*
X457602Y982470D01*
X454586D01*
X454563Y982475D01*
G03X454263Y982511I-304J-1266D01*
G03X453963Y982475I4J-1302D01*
G01X453940Y982470D01*
X453638D01*
G03X453496Y982411I0J-200D01*
G01X452934Y981849D01*
G03X452875Y981707I141J-142D01*
G01Y978213D01*
G03X452934Y978071I200J0D01*
G01X455726Y975279D01*
G03X455868Y975220I142J141D01*
G01X467644D01*
X467703Y975162D01*
X467793Y975072D01*
X467851Y975013D01*
Y973214D01*
X467792Y973155D01*
X467234Y972597D01*
G03X467175Y972455I141J-142D01*
G01Y972228D01*
X466925D01*
X466881Y972251D01*
G03X466273Y972402I-609J-1151D01*
G01X466272D01*
G03X465370Y972039I0J-1302D01*
G01X465311Y971982D01*
X464865Y971990D01*
X464807Y972049D01*
G03X463875Y972442I-932J-909D01*
G01X463874D01*
G03Y969838I0J-1302D01*
G03X464776Y970201I0J1302D01*
G01X464835Y970258D01*
X465281Y970250D01*
X465339Y970191D01*
G03X466271Y969798I932J909D01*
G01X466272D01*
G03X466910Y969965I0J1302D01*
G01X467043Y970039D01*
X467759Y969323D01*
X467817Y969264D01*
Y968022D01*
X467815Y968020D01*
Y967520D01*
X467756Y967461D01*
X467624Y967329D01*
X467565Y967270D01*
X455046D01*
X455001Y967281D01*
X454979Y967291D01*
X454976Y967293D01*
G03X454393Y967431I-583J-1164D01*
G03X453810Y967293I0J-1302D01*
G01X453807Y967291D01*
X453785Y967281D01*
X453740Y967270D01*
X453608D01*
G03X453466Y967211I0J-200D01*
G01X453046Y966791D01*
G03X452987Y966649I141J-142D01*
G01Y962495D01*
G03X453046Y962353I200J0D01*
G01X454641Y960759D01*
G03X454783Y960700I142J141D01*
G01X471704D01*
X471763Y960642D01*
X472182Y960223D01*
X472240Y960164D01*
Y953765D01*
X472181Y953706D01*
X471414Y952939D01*
X471355Y952880D01*
X453578D01*
G03X453436Y952821I0J-200D01*
G01X453004Y952389D01*
G03X452945Y952247I141J-142D01*
G01Y946902D01*
G03X453004Y946760I200J0D01*
G01X453766Y945998D01*
G03X453907Y945940I141J142D01*
G01X453908D01*
X463654D01*
X463713Y945882D01*
X463797Y945798D01*
X463855Y945739D01*
Y943577D01*
X460050D01*
G03X459908Y943518I0J-200D01*
G01X454506Y938116D01*
X454447Y938057D01*
X451131D01*
X451097Y938069D01*
G03X450629Y938153I-469J-1268D01*
G01X450620D01*
G03X450360Y938126I9J-1352D01*
G01X450350Y938124D01*
X450262Y938116D01*
X450102Y938207D01*
X450013Y938315D01*
X450001Y938347D01*
G03X449783Y938726I-1222J-451D01*
G02X449737Y938857I154J128D01*
G01X449740Y938979D01*
X449790Y939107D01*
X449811Y939132D01*
G03X450131Y940006I-1034J874D01*
G03X448779Y941358I-1352J0D01*
G01X448776D01*
G03X448509Y941331I2J-1352D01*
G01X448499Y941329D01*
X448412Y941321D01*
X448252Y941412D01*
X448185Y941449D01*
X448161Y941522D01*
G03X447953Y941906I-1233J-419D01*
G01X447933Y941931D01*
X447887Y942058D01*
X447890Y942257D01*
X447939Y942313D01*
G03X448280Y943210I-1011J898D01*
G03X445576I-1352J0D01*
G03X445896Y942336I1354J0D01*
G01X445917Y942311D01*
X445968Y942182D01*
X445970Y942057D01*
X445924Y941930D01*
X445905Y941905D01*
G03X445697Y941522I1024J-804D01*
G01X445673Y941449D01*
X445606Y941412D01*
X445446Y941321D01*
X445359Y941329D01*
X445349Y941331D01*
G03X445082Y941358I-269J-1325D01*
G01X445079D01*
G03X443727Y940006I0J-1352D01*
G03X444047Y939132I1354J0D01*
G01X444068Y939107D01*
X444118Y938979D01*
X444121Y938857D01*
G02X444075Y938726I-200J-3D01*
G03X443857Y938347I1004J-830D01*
G01X443845Y938315D01*
X443756Y938207D01*
X443596Y938116D01*
X443508Y938124D01*
X443498Y938126D01*
G03X443273Y938152I-267J-1325D01*
G03X443228Y938153I-53J-1351D01*
G03X442959Y938126I0J-1352D01*
G01X442949Y938124D01*
X442862Y938116D01*
X442702Y938207D01*
X442613Y938316D01*
X442601Y938347D01*
G03X442383Y938726I-1222J-451D01*
G02X442337Y938857I154J128D01*
G01X442340Y938979D01*
X442390Y939107D01*
X442411Y939132D01*
G03X442731Y940006I-1034J874D01*
G03X440027I-1352J0D01*
G03X440347Y939132I1354J0D01*
G01X440368Y939107D01*
X440418Y938979D01*
X440421Y938857D01*
G02X440375Y938726I-200J-3D01*
G03X440157Y938347I1004J-830D01*
G01X440145Y938315D01*
X440056Y938207D01*
X439896Y938116D01*
X439808Y938124D01*
X439798Y938126D01*
G03X439573Y938152I-267J-1325D01*
G03X439528Y938153I-53J-1351D01*
G03X439259Y938126I0J-1352D01*
G01X439249Y938124D01*
X439162Y938116D01*
X439002Y938207D01*
X438913Y938316D01*
X438901Y938347D01*
G03X438683Y938726I-1222J-451D01*
G02X438637Y938857I154J128D01*
G01X438640Y938979D01*
X438690Y939107D01*
X438711Y939132D01*
G03X439031Y940006I-1034J874D01*
G03X436327I-1352J0D01*
G03X436647Y939132I1354J0D01*
G01X436668Y939107D01*
X436718Y938979D01*
X436721Y938857D01*
G02X436675Y938726I-200J-3D01*
G03X436457Y938347I1004J-830D01*
G01X436445Y938315D01*
X436356Y938207D01*
X436196Y938116D01*
X436108Y938124D01*
X436098Y938126D01*
G03X435829Y938153I-269J-1325D01*
G03X435560Y938126I0J-1352D01*
G01X435550Y938124D01*
X435462Y938116D01*
X435302Y938207D01*
X435213Y938315D01*
X435201Y938347D01*
G03X434983Y938726I-1222J-451D01*
G02X434937Y938857I154J128D01*
G01X434940Y938979D01*
X434990Y939107D01*
X435011Y939132D01*
G03X435331Y940006I-1034J874D01*
G03X432627I-1352J0D01*
G03X432947Y939132I1354J0D01*
G01X432968Y939107D01*
X433018Y938979D01*
X433021Y938857D01*
G02X432975Y938726I-200J-3D01*
G03X432757Y938347I1004J-830D01*
G01X432745Y938315D01*
X432656Y938207D01*
X432496Y938116D01*
X432408Y938124D01*
X432398Y938126D01*
G03X432173Y938152I-267J-1325D01*
G03X432128Y938153I-53J-1351D01*
G03X431859Y938126I0J-1352D01*
G01X431849Y938124D01*
X431762Y938116D01*
X431602Y938207D01*
X431513Y938316D01*
X431501Y938347D01*
G03X431283Y938726I-1222J-451D01*
G02X431237Y938857I154J128D01*
G01X431240Y938979D01*
X431290Y939107D01*
X431311Y939132D01*
G03X431631Y940006I-1034J874D01*
G03X428927I-1352J0D01*
G03X429247Y939132I1354J0D01*
G01X429268Y939107D01*
X429318Y938979D01*
X429321Y938857D01*
G02X429275Y938726I-200J-3D01*
G03X429105Y938460I1004J-829D01*
G01X429050Y938346D01*
X416118D01*
Y940123D01*
G03X416094Y940276I-502J0D01*
G01X416064Y940371D01*
X416356Y940792D01*
X416455Y940797D01*
G03X417273Y941138I-62J1301D01*
G01X417331Y941191D01*
X417758D01*
G03X418693Y940796I935J909D01*
G03Y943400I0J1302D01*
G03X417758Y943005I0J-1304D01*
G01X417328D01*
G03X415458I-935J-908D01*
G01X415028D01*
G03X414093Y943400I-935J-909D01*
G03X413877Y943382I0J-1302D01*
G01X413785Y943367D01*
X413411Y943684D01*
Y945515D01*
X413469Y945574D01*
X413647Y945752D01*
X413706Y945810D01*
X427612D01*
G03X427754Y945869I0J200D01*
G01X428206Y946321D01*
G03X428265Y946463I-141J142D01*
G01Y951687D01*
G03X428206Y951829I-200J0D01*
G01X427424Y952611D01*
G03X427282Y952670I-142J-141D01*
G01X423644D01*
Y952674D01*
X421146D01*
Y952670D01*
X419844D01*
Y952674D01*
X417346D01*
Y952670D01*
X415844D01*
Y952674D01*
X413346D01*
Y952670D01*
X412044D01*
Y952674D01*
X409546D01*
Y952670D01*
X408865D01*
X408806Y952729D01*
X408554Y952981D01*
X408495Y953040D01*
Y960239D01*
X408553Y960298D01*
X408817Y960562D01*
X408876Y960620D01*
X427632D01*
G03X427774Y960679I0J200D01*
G01X428386Y961291D01*
G03X428445Y961433I-141J142D01*
G01Y966547D01*
G03X428386Y966689I-200J0D01*
G01X427804Y967271D01*
G03X427662Y967330I-142J-141D01*
G01X413997D01*
X413938Y967389D01*
X413546Y967781D01*
X413487Y967840D01*
Y969507D01*
G02X413567Y969667I200J0D01*
G01X413903Y969918D01*
X413999Y969890D01*
G03X414365Y969837I368J1250D01*
G03X415256Y970189I0J1304D01*
G01X415283Y970215D01*
X415419Y970270D01*
X415701D01*
X415837Y970215D01*
X415864Y970189D01*
G03X416755Y969837I891J952D01*
G03Y972443I0J1303D01*
G03X415973Y972182I0J-1302D01*
G01X415147D01*
G03X413632Y972217I-782J-1041D01*
G01X413581Y972182D01*
X413320D01*
X413180Y972322D01*
Y974892D01*
X413408Y975120D01*
X427532D01*
G03X427674Y975179I0J200D01*
G01X428306Y975811D01*
G03X428365Y975953I-141J142D01*
G01Y981087D01*
G03X428306Y981229I-200J0D01*
G01X427884Y981651D01*
G03X427742Y981710I-142J-141D01*
G01X408934D01*
X408736Y981908D01*
X408564Y982081D01*
X408505Y982140D01*
Y988929D01*
X408563Y988988D01*
X409017Y989442D01*
X409076Y989500D01*
X427592D01*
G03X427734Y989559I0J200D01*
G01X428416Y990241D01*
G03X428475Y990383I-141J142D01*
G01Y995387D01*
G03X428416Y995529I-200J0D01*
G01X427924Y996021D01*
G03X427782Y996080I-142J-141D01*
G01X409065D01*
X409006Y996139D01*
X408604Y996541D01*
X408545Y996600D01*
Y1003099D01*
X408603Y1003158D01*
X409207Y1003762D01*
X409266Y1003820D01*
X427292D01*
G03X427434Y1003879I0J200D01*
G01X428446Y1004891D01*
G03X428505Y1005033I-141J142D01*
G01Y1009687D01*
G03X428446Y1009829I-200J0D01*
G01X427784Y1010491D01*
G03X427642Y1010550I-142J-141D01*
G01X417295D01*
X417236Y1010609D01*
X416873Y1010972D01*
X416814Y1011031D01*
Y1012972D01*
X417166Y1013257D01*
X417254Y1013277D01*
X417299Y1013268D01*
X417301D01*
G03X417575Y1013238I278J1272D01*
G03Y1015842I0J1302D01*
G03X417301Y1015812I4J-1302D01*
G01X417299D01*
X417254Y1015803D01*
X417166Y1015823D01*
X416814Y1016108D01*
Y1017556D01*
X416821Y1017564D01*
Y1017825D01*
X416879Y1017884D01*
X417107Y1018112D01*
X417166Y1018170D01*
X427672D01*
G03X427814Y1018229I0J200D01*
G01X428436Y1018851D01*
G03X428495Y1018993I-141J142D01*
G01Y1024007D01*
G03X428436Y1024149I-200J0D01*
G01X427554Y1025031D01*
G03X427412Y1025090I-142J-141D01*
G01X425625D01*
X425566Y1025149D01*
X424852Y1025863D01*
X424793Y1025922D01*
Y1029434D01*
G03X424734Y1029576I-200J0D01*
G01X421993Y1032317D01*
X421987Y1032400D01*
Y1036627D01*
X422045Y1036686D01*
X422984Y1037625D01*
X423043Y1037683D01*
X426003D01*
G03X426145Y1037742I0J200D01*
G01X426414Y1038011D01*
X426535Y1037965D01*
G03X427003Y1037878I477J1265D01*
G01X427023D01*
G03X428364Y1039219I-11J1352D01*
G01Y1039231D01*
G03X428277Y1039707I-1352J-1D01*
G01X428231Y1039828D01*
X428967Y1040564D01*
X429026Y1040622D01*
X429169D01*
G03X429311Y1040681I0J200D01*
G01X430398Y1041768D01*
G03X430457Y1041910I-141J142D01*
G01Y1043598D01*
X430515Y1043657D01*
X431262Y1044404D01*
X431293Y1044419D01*
G03X431931Y1045057I-582J1220D01*
G01X431946Y1045088D01*
X433450Y1046592D01*
G03X433509Y1046734I-141J142D01*
G01Y1047798D01*
X433561Y1047931D01*
X433583Y1047957D01*
G03X433913Y1048842I-1022J885D01*
G03X433894Y1049065I-1352J-3D01*
G01X433878Y1049167D01*
X435221Y1050510D01*
G03X435280Y1050652I-141J142D01*
G01Y1051010D01*
G03X435764Y1052047I-869J1037D01*
G03X435443Y1052921I-1352J-1D01*
G01X435422Y1052947D01*
X435372Y1053075D01*
X435369Y1053197D01*
G02X435415Y1053328I200J3D01*
G03X435713Y1054157I-1004J829D01*
G01Y1054158D01*
G03X435362Y1055047I-1302J0D01*
G01X435337Y1055073D01*
X435280Y1055212D01*
Y1057418D01*
G03X435764Y1058455I-869J1037D01*
G03X435443Y1059329I-1352J-1D01*
G01X435422Y1059355D01*
X435372Y1059483D01*
X435369Y1059605D01*
G02X435415Y1059736I200J3D01*
G03X435713Y1060565I-1004J829D01*
G01Y1060566D01*
G03X435362Y1061455I-1302J0D01*
G01X435337Y1061481D01*
X435280Y1061620D01*
Y1063827D01*
G03X435764Y1064864I-869J1037D01*
G03X435443Y1065738I-1352J-1D01*
G01X435422Y1065764D01*
X435372Y1065892D01*
X435369Y1066014D01*
G02X435415Y1066145I200J3D01*
G03X435713Y1066974I-1004J829D01*
G01Y1066975D01*
G03X435362Y1067864I-1302J0D01*
G01X435337Y1067890D01*
X435280Y1068029D01*
Y1070236D01*
G03X435764Y1071273I-869J1037D01*
G03X435443Y1072147I-1352J-1D01*
G01X435422Y1072173D01*
X435372Y1072301D01*
X435369Y1072423D01*
G02X435415Y1072554I200J3D01*
G03X435713Y1073383I-1004J829D01*
G01Y1073384D01*
G03X435362Y1074273I-1302J0D01*
G01X435337Y1074299D01*
X435280Y1074438D01*
Y1076644D01*
G03X435764Y1077681I-869J1037D01*
G03X435443Y1078555I-1352J-1D01*
G01X435422Y1078581D01*
X435372Y1078709D01*
X435369Y1078831D01*
G02X435415Y1078962I200J3D01*
G03X435713Y1079791I-1004J829D01*
G01Y1079792D01*
G03X435362Y1080681I-1302J0D01*
G01X435337Y1080707D01*
X435280Y1080846D01*
Y1083053D01*
G03X435764Y1084090I-869J1037D01*
G03X435443Y1084964I-1352J-1D01*
G01X435422Y1084990D01*
X435372Y1085118D01*
X435369Y1085240D01*
G02X435415Y1085371I200J3D01*
G03X435713Y1086200I-1004J829D01*
G01Y1086201D01*
G03X435362Y1087090I-1302J0D01*
G01X435337Y1087116D01*
X435280Y1087255D01*
Y1087490D01*
G03X435221Y1087632I-200J0D01*
G01X434286Y1088567D01*
X434477Y1089142D01*
X434600Y1089159D01*
G03X435764Y1090498I-188J1339D01*
G03X435443Y1091372I-1352J-1D01*
G01X435422Y1091398D01*
X435372Y1091526D01*
X435369Y1091648D01*
G02X435415Y1091779I200J3D01*
G03X435713Y1092608I-1004J829D01*
G03X434411Y1093910I-1302J0D01*
G03X434114Y1093875I3J-1302D01*
G01X433942Y1093982D01*
X433856Y1094093D01*
X433845Y1094125D01*
G03X433805Y1094233I-1287J-415D01*
G03X433759Y1094331I-1246J-525D01*
G01X433736Y1094374D01*
Y1095250D01*
X433753Y1095289D01*
G03Y1096337I-1193J524D01*
G01X433738Y1096370D01*
X433735Y1096402D01*
G03X433677Y1096523I-199J-21D01*
G01X433593Y1096607D01*
X433585Y1096617D01*
X433584Y1096618D01*
G03X433366Y1096836I-1023J-805D01*
G01X433365Y1096837D01*
X433355Y1096845D01*
X433116Y1097084D01*
G03X432974Y1097143I-142J-141D01*
G01X432384D01*
X432311Y1097113D01*
X432285Y1097087D01*
X432232Y1097073D01*
G03X431427Y1096454I329J-1260D01*
G01X431369Y1096352D01*
X430118D01*
X430059Y1096411D01*
X429962Y1096508D01*
X429951Y1096525D01*
G03X429574Y1096903I-1091J-711D01*
G01X429573D01*
X429555Y1096915D01*
X428186Y1098284D01*
X428164Y1098408D01*
X428191Y1098466D01*
G03X428313Y1099016I-1180J550D01*
G01Y1099017D01*
G03X428035Y1099821I-1302J0D01*
G01X428016Y1099846D01*
X427970Y1099972D01*
Y1101206D01*
G03X427911Y1101348I-200J0D01*
G01X424460Y1104799D01*
X424512Y1104923D01*
G03X424613Y1105426I-1202J503D01*
G03X424403Y1106136I-1303J1D01*
G01X424388Y1106159D01*
X424353Y1106271D01*
Y1108792D01*
X424393Y1108911D01*
X424410Y1108936D01*
G03X424664Y1109724I-1098J789D01*
G03X424393Y1110536I-1352J0D01*
G01X424353Y1110589D01*
Y1111051D01*
X424388Y1111101D01*
G03X424403Y1112544I-1078J733D01*
G01X424388Y1112567D01*
X424353Y1112679D01*
Y1114017D01*
G03X424294Y1114159I-200J0D01*
G01X423971Y1114482D01*
X424013Y1114973D01*
X424089Y1115027D01*
G03X424664Y1116133I-776J1106D01*
G03X424343Y1117007I-1352J-1D01*
G01X424322Y1117033D01*
X424272Y1117161D01*
X424269Y1117283D01*
G02X424315Y1117414I200J3D01*
G03X424613Y1118243I-1004J829D01*
G03X422009I-1302J0D01*
G03X422288Y1117438I1301J0D01*
G01X422308Y1117412D01*
X422353Y1117287D01*
X422351Y1117160D01*
X422301Y1117032D01*
X422280Y1117006D01*
G03X422028Y1116557I1031J-874D01*
G01X422017Y1116524D01*
X421931Y1116413D01*
X421826Y1116348D01*
G02X421687Y1116321I-105J170D01*
G03X421462Y1116341I-227J-1282D01*
G03X420726Y1116113I0J-1302D01*
G01X420702Y1116097D01*
X420586Y1116059D01*
X418777D01*
X418718Y1116118D01*
X418647Y1116189D01*
X418588Y1116248D01*
Y1117144D01*
G03X418529Y1117286I-200J0D01*
G01X417140Y1118675D01*
X417125Y1118714D01*
G03X416382Y1119457I-1214J-471D01*
G01X416343Y1119472D01*
X415129Y1120686D01*
X415201Y1120818D01*
Y1120819D01*
G03X415363Y1121447I-1140J629D01*
G03X415022Y1122325I-1301J0D01*
G02X414970Y1122459I148J135D01*
G01Y1124660D01*
X415027Y1124799D01*
X415051Y1124826D01*
G03X415027Y1126692I-990J920D01*
G01X414970Y1126750D01*
Y1126880D01*
X414997Y1126949D01*
X415022Y1126977D01*
X415023Y1126978D01*
G03X415022Y1128735I-960J878D01*
G02X414970Y1128869I148J135D01*
G01Y1131068D01*
X415026Y1131206D01*
X415051Y1131233D01*
G03X415413Y1132138I-990J921D01*
G01Y1132163D01*
G03X415356Y1132546I-1352J-6D01*
G01X415347Y1132574D01*
Y1134056D01*
X415349Y1134071D01*
G03X415364Y1134264I-1287J197D01*
G03X415349Y1134457I-1302J-4D01*
G01X415347Y1134472D01*
Y1134593D01*
X415317Y1134666D01*
X415292Y1134691D01*
G03X414489Y1135494I-1230J-427D01*
G01X413278Y1136705D01*
X413351Y1136837D01*
G03X413469Y1137128I-1139J631D01*
G01Y1137129D01*
X413489Y1137203D01*
X413833Y1137431D01*
X413908Y1137421D01*
G03X414876Y1137748I154J1142D01*
G03X415101Y1138065I-814J816D01*
G03X415214Y1138597I-1039J499D01*
G03X415154Y1138753I-203J12D01*
G01X415149Y1138758D01*
G03X414992Y1138811I-138J-149D01*
G03X414867Y1138753I18J-202D01*
G03X414812Y1138649I144J-143D01*
G01Y1138519D01*
X414811Y1138511D01*
G02X414604Y1138044I-750J53D01*
G01X414592Y1138032D01*
G02X413530I-531J531D01*
G02X413310Y1138558I532J531D01*
G01Y1138644D01*
G03X413276Y1138724I-199J-37D01*
G01X413248Y1138763D01*
X413205Y1138785D01*
G03X413142Y1138806I-95J-179D01*
G02X412973Y1139003I31J198D01*
G01Y1140287D01*
G03X412914Y1140429I-200J0D01*
G01X409637Y1143706D01*
G03X409495Y1143765I-142J-141D01*
G01X344015D01*
X343956Y1143824D01*
X341546Y1146233D01*
X341487Y1146292D01*
Y1190362D01*
X276300Y1255549D01*
Y1302980D01*
X276575Y1303255D01*
Y1303337D01*
X276633Y1303396D01*
X277793Y1304556D01*
G37*
G36*
G01X312366Y1359115D02*
X317458D01*
X317600Y1359056D01*
X317824Y1358832D01*
Y1351103D01*
X317839Y1351088D01*
Y1350251D01*
X318220Y1349870D01*
X327471D01*
Y1349912D01*
X332138D01*
X332149Y1349902D01*
X332156Y1349909D01*
X332848D01*
X333299Y1349458D01*
Y1326798D01*
X334088Y1326009D01*
X338078D01*
X339770Y1324317D01*
X339907D01*
Y1324316D01*
X346013D01*
Y1328083D01*
X345854Y1328242D01*
X342661D01*
Y1328618D01*
X342659D01*
X342529Y1328748D01*
X340304D01*
Y1329588D01*
X342529D01*
X342661Y1329720D01*
Y1330280D01*
X342669Y1330300D01*
Y1333618D01*
X342661Y1333638D01*
Y1333780D01*
X342657D01*
X342419Y1334018D01*
X340220D01*
Y1334891D01*
X342601D01*
X342661Y1334951D01*
Y1335280D01*
X342669Y1335300D01*
Y1336034D01*
X342728Y1336176D01*
X342810Y1336258D01*
X342922Y1336304D01*
X342989Y1336285D01*
G03X343690Y1336184I704J2401D01*
G03X344464Y1336307I-1J2502D01*
G01X344494Y1336317D01*
X349586D01*
X349728Y1336258D01*
X349952Y1336034D01*
Y1328305D01*
X349967Y1328290D01*
Y1327453D01*
X350348Y1327072D01*
X359599D01*
Y1327114D01*
X364266D01*
X364277Y1327104D01*
X364284Y1327111D01*
X364976D01*
X365427Y1326660D01*
Y1313187D01*
X366031Y1312583D01*
X370206D01*
X371898Y1310891D01*
X372035D01*
Y1310890D01*
X378141D01*
Y1314657D01*
X377982Y1314816D01*
X374789D01*
Y1315198D01*
X374689Y1315298D01*
X372400D01*
Y1316082D01*
X374583D01*
X374789Y1316288D01*
Y1316854D01*
X374797Y1316874D01*
Y1320192D01*
X374789Y1320212D01*
Y1320354D01*
X374775D01*
X374457Y1320672D01*
X372500D01*
X372432Y1320740D01*
Y1321284D01*
X372640Y1321492D01*
X374589D01*
X374789Y1321692D01*
Y1321854D01*
X374797Y1321874D01*
Y1322608D01*
X374856Y1322750D01*
X374938Y1322832D01*
X375050Y1322878D01*
X375117Y1322859D01*
G03X375818Y1322758I704J2401D01*
G03X376592Y1322881I-1J2502D01*
G01X376622Y1322891D01*
X381714D01*
X381856Y1322832D01*
X382080Y1322608D01*
Y1314879D01*
X382095Y1314864D01*
Y1314027D01*
X382476Y1313646D01*
X391727D01*
Y1313688D01*
X396394D01*
X396405Y1313678D01*
X396412Y1313685D01*
X397555D01*
X398657Y1312583D01*
X402334D01*
X404026Y1310891D01*
X404163D01*
Y1310890D01*
X410269D01*
Y1314657D01*
X410110Y1314816D01*
X406917D01*
Y1315208D01*
X406909D01*
X406819Y1315298D01*
X403987D01*
X403877Y1315408D01*
Y1315958D01*
X404087Y1316168D01*
X406779D01*
X406917Y1316306D01*
Y1316854D01*
X406925Y1316874D01*
Y1320192D01*
X406917Y1320212D01*
Y1320366D01*
X406903D01*
X406657Y1320612D01*
X403455D01*
X403395Y1320672D01*
Y1321395D01*
X403466Y1321466D01*
X406840D01*
X406917Y1321543D01*
Y1321854D01*
X406925Y1321874D01*
Y1322608D01*
X406984Y1322750D01*
X407066Y1322832D01*
X407178Y1322878D01*
X407245Y1322859D01*
G03X407946Y1322758I704J2401D01*
G03X408720Y1322881I-1J2502D01*
G01X408750Y1322891D01*
X413842D01*
X413984Y1322832D01*
X414208Y1322608D01*
Y1314879D01*
X414223Y1314864D01*
Y1314027D01*
X414604Y1313646D01*
X423855D01*
Y1313688D01*
X428522D01*
X428533Y1313678D01*
X428540Y1313685D01*
X429683D01*
X430785Y1312583D01*
X434462D01*
X436154Y1310891D01*
X436291D01*
Y1310890D01*
X442397D01*
Y1314657D01*
X442238Y1314816D01*
X439045D01*
Y1315198D01*
X438949Y1315294D01*
Y1315298D01*
X438939Y1315308D01*
X436650D01*
Y1316138D01*
X439009D01*
X439045Y1316174D01*
Y1316854D01*
X439053Y1316874D01*
Y1320192D01*
X439045Y1320212D01*
Y1320380D01*
X438869Y1320556D01*
Y1320560D01*
X438853Y1320576D01*
X436688D01*
Y1321482D01*
X438984D01*
X439045Y1321543D01*
Y1321854D01*
X439053Y1321874D01*
Y1322608D01*
X439112Y1322750D01*
X439194Y1322832D01*
X439306Y1322878D01*
X439373Y1322859D01*
G03X440074Y1322758I704J2401D01*
G03X440848Y1322881I-1J2502D01*
G01X440878Y1322891D01*
X445970D01*
X446112Y1322832D01*
X446336Y1322608D01*
Y1314879D01*
X446351Y1314864D01*
Y1314027D01*
X446732Y1313646D01*
X455983D01*
Y1313688D01*
X460650D01*
X460661Y1313678D01*
X460668Y1313685D01*
X461811D01*
X462913Y1312583D01*
X466590D01*
X468282Y1310891D01*
X468419D01*
Y1310890D01*
X474525D01*
Y1314657D01*
X474366Y1314816D01*
X471173D01*
Y1315158D01*
X471159D01*
X471019Y1315298D01*
X468800D01*
Y1316108D01*
X471059D01*
X471173Y1316222D01*
Y1316854D01*
X471181Y1316874D01*
Y1320192D01*
X471173Y1320212D01*
Y1320362D01*
X471160D01*
X470941Y1320581D01*
X468740D01*
Y1321478D01*
X471069D01*
X471173Y1321582D01*
Y1321854D01*
X471181Y1321874D01*
Y1322608D01*
X471240Y1322750D01*
X471322Y1322832D01*
X471434Y1322878D01*
X471501Y1322859D01*
G03X472202Y1322758I704J2401D01*
G03X472976Y1322881I-1J2502D01*
G01X473006Y1322891D01*
X478098D01*
X478240Y1322832D01*
X478464Y1322608D01*
Y1314879D01*
X478479Y1314864D01*
Y1314027D01*
X478860Y1313646D01*
X488111D01*
Y1313688D01*
X492778D01*
X492789Y1313678D01*
X492796Y1313685D01*
X493939D01*
X495101Y1314847D01*
Y1325539D01*
X495571Y1326009D01*
X498718D01*
X500410Y1324317D01*
X500547D01*
Y1324316D01*
X506653D01*
Y1328083D01*
X506494Y1328242D01*
X503301D01*
Y1328638D01*
X503209Y1328730D01*
Y1328738D01*
X503189Y1328758D01*
X500944D01*
Y1329558D01*
X503189D01*
X503301Y1329670D01*
Y1330280D01*
X503309Y1330300D01*
Y1333618D01*
X503301Y1333638D01*
X503012Y1333927D01*
Y1333928D01*
X502939Y1334001D01*
X500890D01*
Y1334904D01*
X503204D01*
X503301Y1335001D01*
Y1335280D01*
X503309Y1335300D01*
Y1336034D01*
X503368Y1336176D01*
X503450Y1336258D01*
X503562Y1336304D01*
X503629Y1336285D01*
G03X504330Y1336184I704J2401D01*
G03X505104Y1336307I-1J2502D01*
G01X505134Y1336317D01*
X510226D01*
X510368Y1336258D01*
X510592Y1336034D01*
Y1328305D01*
X510607Y1328290D01*
Y1327453D01*
X510988Y1327072D01*
X520239D01*
Y1327114D01*
X526397D01*
X527427Y1328144D01*
Y1348546D01*
X527688Y1348807D01*
X530846D01*
X532538Y1347115D01*
X532675D01*
Y1347114D01*
X538781D01*
Y1350881D01*
X538622Y1351040D01*
X535429D01*
Y1351348D01*
X535269Y1351508D01*
X533072D01*
Y1352328D01*
X535279D01*
X535429Y1352478D01*
Y1353078D01*
X535437Y1353098D01*
Y1356416D01*
X535429Y1356436D01*
X535412D01*
X535031Y1356817D01*
X531959D01*
X531876Y1356900D01*
Y1357577D01*
X531999Y1357700D01*
X535321D01*
X535429Y1357808D01*
Y1358078D01*
X535437Y1358098D01*
Y1358832D01*
X535496Y1358974D01*
X535578Y1359056D01*
X535690Y1359102D01*
X535757Y1359083D01*
G03X536458Y1358982I704J2401D01*
G03X537232Y1359105I-1J2502D01*
G01X537262Y1359115D01*
X542354D01*
X542496Y1359056D01*
X542720Y1358832D01*
Y1351103D01*
X542735Y1351088D01*
Y1350251D01*
X543116Y1349870D01*
X552367D01*
Y1349912D01*
X572980D01*
X574340Y1351272D01*
Y1362922D01*
X572250Y1365012D01*
X565040D01*
X564200Y1365852D01*
Y1377662D01*
X562320Y1379542D01*
X555150D01*
X555130Y1379562D01*
X515332D01*
X513873Y1378103D01*
X499636D01*
X498836Y1378903D01*
Y1416187D01*
X498916Y1416267D01*
Y1416298D01*
X499026Y1416408D01*
X511040D01*
X512417Y1417785D01*
Y1428260D01*
X508615Y1432062D01*
X528800D01*
X536002Y1439264D01*
X544000Y1431265D01*
X558297D01*
X560007Y1429555D01*
Y1424625D01*
X566550Y1418082D01*
X606690D01*
X608360Y1416412D01*
Y1332122D01*
X606520Y1330282D01*
X563740D01*
X562610Y1329152D01*
Y1326092D01*
X558096Y1321578D01*
X534254D01*
X532719Y1320044D01*
Y1315558D01*
X531069Y1313908D01*
X524809D01*
X522719Y1311818D01*
Y1302408D01*
X519127Y1298816D01*
X501651D01*
X500810Y1297975D01*
Y1297974D01*
X500723Y1297887D01*
Y1291912D01*
X499719Y1290908D01*
X491389D01*
X486089Y1285608D01*
X371519D01*
X370719Y1286408D01*
Y1296408D01*
X368311Y1298816D01*
X338811D01*
X337749Y1299878D01*
Y1318014D01*
X333757Y1322006D01*
X308127D01*
X307345Y1321224D01*
Y1315127D01*
X308096Y1314376D01*
X326204D01*
X328933Y1311647D01*
Y1307908D01*
X326583Y1305558D01*
X277584D01*
X276517Y1306625D01*
Y1346545D01*
X278779Y1348807D01*
X305950D01*
X307642Y1347115D01*
X307779D01*
Y1347114D01*
X313885D01*
Y1350881D01*
X313726Y1351040D01*
X310533D01*
Y1351218D01*
X310519D01*
X310249Y1351488D01*
X308160D01*
Y1352358D01*
X310319D01*
X310533Y1352572D01*
Y1353078D01*
X310541Y1353098D01*
Y1356416D01*
X310533Y1356436D01*
Y1356565D01*
X310531D01*
X310293Y1356803D01*
X307072D01*
X306989Y1356886D01*
Y1357641D01*
X307044Y1357696D01*
X310459D01*
X310533Y1357770D01*
Y1358078D01*
X310541Y1358098D01*
Y1358832D01*
X310600Y1358974D01*
X310682Y1359056D01*
X310794Y1359102D01*
X310861Y1359083D01*
G03X311562Y1358982I704J2401D01*
G03X312336Y1359105I-1J2502D01*
G01X312366Y1359115D01*
G37*
G36*
G01X278215Y1575686D02*
G03I-720J0D01*
G37*
G36*
G01Y1580678D02*
G03I-720J0D01*
G37*
G36*
G01X285319D02*
G03I-720J0D01*
G37*
G36*
G01X290275D02*
G03I-720J0D01*
G37*
G36*
G01Y1575686D02*
G03I-720J0D01*
G37*
G36*
G01X285319D02*
G03I-720J0D01*
G37*
G36*
G01X278215Y1587598D02*
G03I-720J0D01*
G37*
G36*
G01Y1592590D02*
G03I-720J0D01*
G37*
G36*
G01X285319D02*
G03I-720J0D01*
G37*
G36*
G01X290275D02*
G03I-720J0D01*
G37*
G36*
G01X285319Y1587598D02*
G03I-720J0D01*
G37*
G36*
G01X290275D02*
G03I-720J0D01*
G37*
G36*
G01X283515Y1599884D02*
G03I-720J0D01*
G37*
G36*
G01X278559D02*
G03I-720J0D01*
G37*
G36*
G01X283515Y1604876D02*
G03I-720J0D01*
G37*
G36*
G01Y1611796D02*
G03I-720J0D01*
G37*
G36*
G01X278559D02*
G03I-720J0D01*
G37*
G36*
G01Y1604876D02*
G03I-720J0D01*
G37*
G36*
G01X283515Y1616788D02*
G03I-720J0D01*
G37*
G36*
G01X278559D02*
G03I-720J0D01*
G37*
G36*
G01X292380Y21642D02*
G03I-720J0D01*
G37*
G36*
G01X322550Y178962D02*
X324020Y177492D01*
Y167182D01*
X321000Y164162D01*
X304600D01*
X302520Y166242D01*
Y177092D01*
X304390Y178962D01*
X322550D01*
G37*
G36*
G01X301896Y867031D02*
X301496Y867174D01*
Y867924D01*
X301896Y868067D01*
X302096D01*
Y867031D01*
X301896D01*
G37*
G36*
G01X304296Y864681D02*
X303896Y864824D01*
Y865574D01*
X304296Y865717D01*
X304496D01*
Y864681D01*
X304296D01*
G37*
G36*
G01X304696Y866891D02*
X305096Y866749D01*
Y865999D01*
X304696Y865857D01*
X304496D01*
Y866891D01*
X304696D01*
G37*
G36*
G01Y864541D02*
X305096Y864399D01*
Y863649D01*
X304696Y863507D01*
X304496D01*
Y864541D01*
X304696D01*
G37*
G36*
G01X304296Y867031D02*
X303896Y867174D01*
Y867924D01*
X304296Y868067D01*
X304496D01*
Y867031D01*
X304296D01*
G37*
G36*
G01X303496Y866891D02*
X303896Y866749D01*
Y865999D01*
X303496Y865857D01*
X303296D01*
Y866891D01*
X303496D01*
G37*
G36*
G01Y864541D02*
X303896Y864399D01*
Y863649D01*
X303496Y863507D01*
X303296D01*
Y864541D01*
X303496D01*
G37*
G36*
G01X303096Y867031D02*
X302696Y867174D01*
Y867924D01*
X303096Y868067D01*
X303296D01*
Y867031D01*
X303096D01*
G37*
G36*
G01X305496Y862331D02*
X305096Y862474D01*
Y863224D01*
X305496Y863367D01*
X305696D01*
Y862331D01*
X305496D01*
G37*
G36*
G01Y859981D02*
X305096Y860124D01*
Y860874D01*
X305496Y861017D01*
X305696D01*
Y859981D01*
X305496D01*
G37*
G36*
G01Y864681D02*
X305096Y864824D01*
Y865574D01*
X305496Y865717D01*
X305696D01*
Y864681D01*
X305496D01*
G37*
G36*
G01Y867031D02*
X305096Y867174D01*
Y867924D01*
X305496Y868067D01*
X305696D01*
Y867031D01*
X305496D01*
G37*
G36*
G01X301896Y871731D02*
X301496Y871874D01*
Y872624D01*
X301896Y872767D01*
X302096D01*
Y871731D01*
X301896D01*
G37*
G36*
G01Y874081D02*
X301496Y874224D01*
Y874974D01*
X301896Y875117D01*
X302096D01*
Y874081D01*
X301896D01*
G37*
G36*
G01Y876431D02*
X301496Y876574D01*
Y877324D01*
X301896Y877467D01*
X302096D01*
Y876431D01*
X301896D01*
G37*
G36*
G01Y878781D02*
X301496Y878924D01*
Y879674D01*
X301896Y879817D01*
X302096D01*
Y878781D01*
X301896D01*
G37*
G36*
G01Y869381D02*
X301496Y869524D01*
Y870274D01*
X301896Y870417D01*
X302096D01*
Y869381D01*
X301896D01*
G37*
G36*
G01X302296Y873941D02*
X302696Y873799D01*
Y873049D01*
X302296Y872907D01*
X302096D01*
Y873941D01*
X302296D01*
G37*
G36*
G01Y876291D02*
X302696Y876149D01*
Y875399D01*
X302296Y875257D01*
X302096D01*
Y876291D01*
X302296D01*
G37*
G36*
G01Y878641D02*
X302696Y878499D01*
Y877749D01*
X302296Y877607D01*
X302096D01*
Y878641D01*
X302296D01*
G37*
G36*
G01X304102Y883150D02*
X304284Y882766D01*
X303753Y882236D01*
X303370Y882418D01*
X303228Y882559D01*
X303960Y883291D01*
X304102Y883150D01*
G37*
G36*
G01X303918Y883532D02*
X303736Y883915D01*
X304266Y884446D01*
X304650Y884263D01*
X304791Y884122D01*
X304059Y883390D01*
X303918Y883532D01*
G37*
G36*
G01X305763Y884812D02*
X305945Y884428D01*
X305415Y883898D01*
X305031Y884080D01*
X304890Y884221D01*
X305622Y884953D01*
X305763Y884812D01*
G37*
G36*
G01X302296Y871591D02*
X302696Y871449D01*
Y870699D01*
X302296Y870557D01*
X302096D01*
Y871591D01*
X302296D01*
G37*
G36*
G01Y869241D02*
X302696Y869099D01*
Y868349D01*
X302296Y868207D01*
X302096D01*
Y869241D01*
X302296D01*
G37*
G36*
G01X304696Y871591D02*
X305096Y871449D01*
Y870699D01*
X304696Y870557D01*
X304496D01*
Y871591D01*
X304696D01*
G37*
G36*
G01X304296Y869381D02*
X303896Y869524D01*
Y870274D01*
X304296Y870417D01*
X304496D01*
Y869381D01*
X304296D01*
G37*
G36*
G01Y871731D02*
X303896Y871874D01*
Y872624D01*
X304296Y872767D01*
X304496D01*
Y871731D01*
X304296D01*
G37*
G36*
G01Y874081D02*
X303896Y874224D01*
Y874974D01*
X304296Y875117D01*
X304496D01*
Y874081D01*
X304296D01*
G37*
G36*
G01Y876431D02*
X303896Y876574D01*
Y877324D01*
X304296Y877467D01*
X304496D01*
Y876431D01*
X304296D01*
G37*
G36*
G01X304696Y873941D02*
X305096Y873799D01*
Y873049D01*
X304696Y872907D01*
X304496D01*
Y873941D01*
X304696D01*
G37*
G36*
G01Y876291D02*
X305096Y876149D01*
Y875399D01*
X304696Y875257D01*
X304496D01*
Y876291D01*
X304696D01*
G37*
G36*
G01Y878641D02*
X305096Y878499D01*
Y877749D01*
X304696Y877607D01*
X304496D01*
Y878641D01*
X304696D01*
G37*
G36*
G01X304296Y878781D02*
X303896Y878924D01*
Y879674D01*
X304296Y879817D01*
X304496D01*
Y878781D01*
X304296D01*
G37*
G36*
G01X305800Y881452D02*
X305982Y881068D01*
X305451Y880538D01*
X305068Y880720D01*
X304926Y880861D01*
X305658Y881593D01*
X305800Y881452D01*
G37*
G36*
G01X304696Y869241D02*
X305096Y869099D01*
Y868349D01*
X304696Y868207D01*
X304496D01*
Y869241D01*
X304696D01*
G37*
G36*
G01X303096Y871731D02*
X302696Y871874D01*
Y872624D01*
X303096Y872767D01*
X303296D01*
Y871731D01*
X303096D01*
G37*
G36*
G01Y874081D02*
X302696Y874224D01*
Y874974D01*
X303096Y875117D01*
X303296D01*
Y874081D01*
X303096D01*
G37*
G36*
G01Y876431D02*
X302696Y876574D01*
Y877324D01*
X303096Y877467D01*
X303296D01*
Y876431D01*
X303096D01*
G37*
G36*
G01X303496Y873941D02*
X303896Y873799D01*
Y873049D01*
X303496Y872907D01*
X303296D01*
Y873941D01*
X303496D01*
G37*
G36*
G01Y876291D02*
X303896Y876149D01*
Y875399D01*
X303496Y875257D01*
X303296D01*
Y876291D01*
X303496D01*
G37*
G36*
G01Y878641D02*
X303896Y878499D01*
Y877749D01*
X303496Y877607D01*
X303296D01*
Y878641D01*
X303496D01*
G37*
G36*
G01X303096Y878781D02*
X302696Y878924D01*
Y879674D01*
X303096Y879817D01*
X303296D01*
Y878781D01*
X303096D01*
G37*
G36*
G01X304767Y882683D02*
X304585Y883066D01*
X305115Y883597D01*
X305499Y883414D01*
X305640Y883273D01*
X304908Y882541D01*
X304767Y882683D01*
G37*
G36*
G01X304951Y882301D02*
X305133Y881917D01*
X304602Y881387D01*
X304219Y881569D01*
X304077Y881710D01*
X304809Y882442D01*
X304951Y882301D01*
G37*
G36*
G01X303096Y869381D02*
X302696Y869524D01*
Y870274D01*
X303096Y870417D01*
X303296D01*
Y869381D01*
X303096D01*
G37*
G36*
G01X303496Y871591D02*
X303896Y871449D01*
Y870699D01*
X303496Y870557D01*
X303296D01*
Y871591D01*
X303496D01*
G37*
G36*
G01Y869241D02*
X303896Y869099D01*
Y868349D01*
X303496Y868207D01*
X303296D01*
Y869241D01*
X303496D01*
G37*
G36*
G01X305496Y871731D02*
X305096Y871874D01*
Y872624D01*
X305496Y872767D01*
X305696D01*
Y871731D01*
X305496D01*
G37*
G36*
G01Y874081D02*
X305096Y874224D01*
Y874974D01*
X305496Y875117D01*
X305696D01*
Y874081D01*
X305496D01*
G37*
G36*
G01Y876431D02*
X305096Y876574D01*
Y877324D01*
X305496Y877467D01*
X305696D01*
Y876431D01*
X305496D01*
G37*
G36*
G01Y869381D02*
X305096Y869524D01*
Y870274D01*
X305496Y870417D01*
X305696D01*
Y869381D01*
X305496D01*
G37*
G36*
G01X306160Y970578D02*
X306018Y970178D01*
X305268D01*
X305125Y970578D01*
Y970778D01*
X306160D01*
Y970578D01*
G37*
G36*
G01Y968178D02*
X306018Y967778D01*
X305268D01*
X305125Y968178D01*
Y968378D01*
X306160D01*
Y968178D01*
G37*
G36*
G01X303950Y968578D02*
X304092Y968978D01*
X304842D01*
X304985Y968578D01*
Y968378D01*
X303950D01*
Y968578D01*
G37*
G36*
G01X306160Y971778D02*
X306018Y971378D01*
X305268D01*
X305125Y971778D01*
Y971978D01*
X306160D01*
Y971778D01*
G37*
G36*
G01Y969378D02*
X306018Y968978D01*
X305268D01*
X305125Y969378D01*
Y969578D01*
X306160D01*
Y969378D01*
G37*
G36*
G01X303950Y969778D02*
X304092Y970178D01*
X304842D01*
X304985Y969778D01*
Y969578D01*
X303950D01*
Y969778D01*
G37*
G36*
G01X306161Y1046584D02*
X305778Y1046402D01*
X305247Y1046932D01*
X305429Y1047316D01*
X305571Y1047457D01*
X306303Y1046725D01*
X306161Y1046584D01*
G37*
G36*
G01X304462Y1044885D02*
X304079Y1044703D01*
X303548Y1045233D01*
X303730Y1045617D01*
X303872Y1045758D01*
X304604Y1045026D01*
X304462Y1044885D01*
G37*
G36*
G01X303182Y1046730D02*
X303566Y1046912D01*
X304096Y1046382D01*
X303914Y1045998D01*
X303773Y1045857D01*
X303041Y1046589D01*
X303182Y1046730D01*
G37*
G36*
G01X302801Y1046547D02*
X302417Y1046364D01*
X301887Y1046895D01*
X302069Y1047278D01*
X302210Y1047420D01*
X302942Y1046688D01*
X302801Y1046547D01*
G37*
G36*
G01X306124Y1043223D02*
X305740Y1043041D01*
X305210Y1043571D01*
X305392Y1043955D01*
X305534Y1044096D01*
X306265Y1043365D01*
X306124Y1043223D01*
G37*
G36*
G01X304844Y1045069D02*
X305228Y1045251D01*
X305758Y1044720D01*
X305576Y1044337D01*
X305435Y1044195D01*
X304703Y1044927D01*
X304844Y1045069D01*
G37*
G36*
G01X305312Y1045734D02*
X304928Y1045552D01*
X304398Y1046083D01*
X304580Y1046466D01*
X304721Y1046608D01*
X305453Y1045876D01*
X305312Y1045734D01*
G37*
G36*
G01X304032Y1047580D02*
X304416Y1047762D01*
X304946Y1047232D01*
X304764Y1046848D01*
X304622Y1046707D01*
X303891Y1047438D01*
X304032Y1047580D01*
G37*
G36*
G01X301951Y1045697D02*
X301568Y1045515D01*
X301037Y1046045D01*
X301219Y1046429D01*
X301361Y1046570D01*
X302093Y1045838D01*
X301951Y1045697D01*
G37*
G36*
G01X300671Y1047543D02*
X301055Y1047725D01*
X301585Y1047194D01*
X301403Y1046811D01*
X301262Y1046669D01*
X300530Y1047401D01*
X300671Y1047543D01*
G37*
G36*
G01X305275Y1042374D02*
X304891Y1042192D01*
X304361Y1042722D01*
X304543Y1043105D01*
X304684Y1043247D01*
X305416Y1042515D01*
X305275Y1042374D01*
G37*
G36*
G01X303613Y1044035D02*
X303229Y1043853D01*
X302699Y1044384D01*
X302881Y1044767D01*
X303022Y1044909D01*
X303754Y1044177D01*
X303613Y1044035D01*
G37*
G36*
G01X303995Y1044219D02*
X304378Y1044401D01*
X304909Y1043871D01*
X304727Y1043487D01*
X304585Y1043346D01*
X303853Y1044078D01*
X303995Y1044219D01*
G37*
G36*
G01X302333Y1045881D02*
X302717Y1046063D01*
X303247Y1045533D01*
X303065Y1045149D01*
X302923Y1045008D01*
X302192Y1045739D01*
X302333Y1045881D01*
G37*
G36*
G01X306218Y1060113D02*
X305834Y1059931D01*
X305304Y1060461D01*
X305486Y1060845D01*
X305627Y1060986D01*
X306359Y1060254D01*
X306218Y1060113D01*
G37*
G36*
G01X304556Y1061774D02*
X304172Y1061592D01*
X303642Y1062123D01*
X303824Y1062506D01*
X303965Y1062648D01*
X304697Y1061916D01*
X304556Y1061774D01*
G37*
G36*
G01X304938Y1061958D02*
X305321Y1062140D01*
X305852Y1061610D01*
X305669Y1061226D01*
X305528Y1061085D01*
X304796Y1061817D01*
X304938Y1061958D01*
G37*
G36*
G01X303239Y1060260D02*
X303623Y1060442D01*
X304153Y1059911D01*
X303971Y1059528D01*
X303830Y1059386D01*
X303098Y1060118D01*
X303239Y1060260D01*
G37*
G36*
G01X304519Y1058414D02*
X304135Y1058232D01*
X303605Y1058762D01*
X303787Y1059146D01*
X303929Y1059287D01*
X304660Y1058556D01*
X304519Y1058414D01*
G37*
G36*
G01X304901Y1058598D02*
X305284Y1058780D01*
X305815Y1058250D01*
X305633Y1057866D01*
X305491Y1057725D01*
X304759Y1058457D01*
X304901Y1058598D01*
G37*
G36*
G01X306181Y1056752D02*
X305797Y1056570D01*
X305267Y1057101D01*
X305449Y1057484D01*
X305590Y1057626D01*
X306322Y1056894D01*
X306181Y1056752D01*
G37*
G36*
G01X305369Y1059264D02*
X304985Y1059082D01*
X304455Y1059612D01*
X304637Y1059996D01*
X304778Y1060137D01*
X305510Y1059405D01*
X305369Y1059264D01*
G37*
G36*
G01X304089Y1061109D02*
X304472Y1061291D01*
X305003Y1060761D01*
X304820Y1060377D01*
X304679Y1060236D01*
X303947Y1060968D01*
X304089Y1061109D01*
G37*
G36*
G01X303707Y1060925D02*
X303323Y1060743D01*
X302793Y1061274D01*
X302975Y1061657D01*
X303116Y1061799D01*
X303848Y1061067D01*
X303707Y1060925D01*
G37*
G36*
G01X305332Y1055903D02*
X304948Y1055721D01*
X304418Y1056252D01*
X304600Y1056635D01*
X304741Y1056777D01*
X305473Y1056045D01*
X305332Y1055903D01*
G37*
G36*
G01X304052Y1057749D02*
X304435Y1057931D01*
X304966Y1057401D01*
X304784Y1057017D01*
X304642Y1056876D01*
X303910Y1057608D01*
X304052Y1057749D01*
G37*
G36*
G01X301558Y1051753D02*
X301942Y1051935D01*
X302472Y1051405D01*
X302290Y1051021D01*
X302149Y1050879D01*
X301417Y1051611D01*
X301558Y1051753D01*
G37*
G36*
G01X303220Y1050091D02*
X303603Y1050273D01*
X304134Y1049743D01*
X303952Y1049359D01*
X303810Y1049218D01*
X303078Y1049950D01*
X303220Y1050091D01*
G37*
G36*
G01X302838Y1049907D02*
X302454Y1049725D01*
X301924Y1050255D01*
X302106Y1050639D01*
X302248Y1050780D01*
X302979Y1050049D01*
X302838Y1049907D01*
G37*
G36*
G01X304500Y1048246D02*
X304116Y1048063D01*
X303586Y1048594D01*
X303768Y1048977D01*
X303909Y1049119D01*
X304641Y1048387D01*
X304500Y1048246D01*
G37*
G36*
G01X304881Y1048429D02*
X305265Y1048611D01*
X305795Y1048081D01*
X305613Y1047697D01*
X305472Y1047556D01*
X304740Y1048288D01*
X304881Y1048429D01*
G37*
G36*
G01X301521Y1048392D02*
X301904Y1048574D01*
X302435Y1048044D01*
X302253Y1047660D01*
X302111Y1047519D01*
X301379Y1048251D01*
X301521Y1048392D01*
G37*
G36*
G01X301139Y1048208D02*
X300755Y1048026D01*
X300225Y1048556D01*
X300407Y1048940D01*
X300549Y1049081D01*
X301280Y1048350D01*
X301139Y1048208D01*
G37*
G36*
G01X301988Y1049058D02*
X301605Y1048876D01*
X301075Y1049406D01*
X301257Y1049790D01*
X301398Y1049931D01*
X302130Y1049199D01*
X301988Y1049058D01*
G37*
G36*
G01X303650Y1047396D02*
X303267Y1047214D01*
X302736Y1047744D01*
X302918Y1048128D01*
X303060Y1048269D01*
X303792Y1047537D01*
X303650Y1047396D01*
G37*
G36*
G01X302370Y1049242D02*
X302754Y1049424D01*
X303284Y1048893D01*
X303102Y1048510D01*
X302961Y1048368D01*
X302229Y1049100D01*
X302370Y1049242D01*
G37*
G36*
G01X301933Y1079039D02*
X301513Y1078976D01*
X301160Y1079638D01*
X301445Y1079952D01*
X301622Y1080046D01*
X302110Y1079133D01*
X301933Y1079039D01*
G37*
G36*
G01X304027Y1076641D02*
X303643Y1076458D01*
X303113Y1076989D01*
X303295Y1077372D01*
X303436Y1077514D01*
X304168Y1076782D01*
X304027Y1076641D01*
G37*
G36*
G01X304408Y1076824D02*
X304792Y1077006D01*
X305322Y1076476D01*
X305140Y1076093D01*
X304999Y1075951D01*
X304267Y1076683D01*
X304408Y1076824D01*
G37*
G36*
G01X305688Y1074979D02*
X305305Y1074797D01*
X304774Y1075327D01*
X304956Y1075711D01*
X305098Y1075852D01*
X305830Y1075120D01*
X305688Y1074979D01*
G37*
G36*
G01X299123Y1080043D02*
X299543Y1080106D01*
X299897Y1079444D01*
X299611Y1079130D01*
X299435Y1079036D01*
X298947Y1079949D01*
X299123Y1080043D01*
G37*
G36*
G01X301047Y1076787D02*
X301431Y1076969D01*
X301961Y1076438D01*
X301779Y1076055D01*
X301638Y1075913D01*
X300906Y1076645D01*
X301047Y1076787D01*
G37*
G36*
G01X299812Y1077905D02*
X299392Y1077842D01*
X299039Y1078504D01*
X299324Y1078818D01*
X299501Y1078912D01*
X299989Y1078000D01*
X299812Y1077905D01*
G37*
G36*
G01X302327Y1074941D02*
X301943Y1074759D01*
X301413Y1075289D01*
X301595Y1075673D01*
X301737Y1075814D01*
X302469Y1075082D01*
X302327Y1074941D01*
G37*
G36*
G01X302709Y1075125D02*
X303093Y1075307D01*
X303623Y1074777D01*
X303441Y1074393D01*
X303299Y1074252D01*
X302568Y1074983D01*
X302709Y1075125D01*
G37*
G36*
G01X303989Y1073279D02*
X303605Y1073097D01*
X303075Y1073628D01*
X303257Y1074011D01*
X303398Y1074153D01*
X304130Y1073421D01*
X303989Y1073279D01*
G37*
G36*
G01X304371Y1073463D02*
X304754Y1073645D01*
X305285Y1073115D01*
X305102Y1072731D01*
X304961Y1072590D01*
X304229Y1073322D01*
X304371Y1073463D01*
G37*
G36*
G01X305651Y1071618D02*
X305267Y1071436D01*
X304737Y1071966D01*
X304919Y1072350D01*
X305060Y1072491D01*
X305792Y1071759D01*
X305651Y1071618D01*
G37*
G36*
G01X300872Y1078472D02*
X300452Y1078409D01*
X300099Y1079070D01*
X300384Y1079385D01*
X300561Y1079479D01*
X301048Y1078566D01*
X300872Y1078472D01*
G37*
G36*
G01X303559Y1075975D02*
X303943Y1076157D01*
X304473Y1075627D01*
X304291Y1075244D01*
X304150Y1075102D01*
X303418Y1075834D01*
X303559Y1075975D01*
G37*
G36*
G01X303178Y1075792D02*
X302794Y1075609D01*
X302264Y1076140D01*
X302446Y1076523D01*
X302587Y1076665D01*
X303319Y1075933D01*
X303178Y1075792D01*
G37*
G36*
G01X304839Y1074130D02*
X304456Y1073948D01*
X303925Y1074478D01*
X304107Y1074862D01*
X304249Y1075003D01*
X304981Y1074271D01*
X304839Y1074130D01*
G37*
G36*
G01X305221Y1074314D02*
X305605Y1074496D01*
X306135Y1073965D01*
X305953Y1073582D01*
X305812Y1073440D01*
X305080Y1074172D01*
X305221Y1074314D01*
G37*
G36*
G01X298753Y1077339D02*
X298333Y1077276D01*
X297979Y1077938D01*
X298265Y1078252D01*
X298441Y1078346D01*
X298929Y1077433D01*
X298753Y1077339D01*
G37*
G36*
G01X298064Y1079477D02*
X298484Y1079540D01*
X298837Y1078878D01*
X298552Y1078564D01*
X298375Y1078470D01*
X297888Y1079382D01*
X298064Y1079477D01*
G37*
G36*
G01X297645Y1079412D02*
X297225Y1079349D01*
X296872Y1080010D01*
X297157Y1080324D01*
X297334Y1080419D01*
X297822Y1079506D01*
X297645Y1079412D01*
G37*
G36*
G01X300198Y1075937D02*
X300581Y1076119D01*
X301112Y1075589D01*
X300930Y1075205D01*
X300788Y1075064D01*
X300056Y1075796D01*
X300198Y1075937D01*
G37*
G36*
G01X301478Y1074092D02*
X301094Y1073909D01*
X300564Y1074440D01*
X300746Y1074823D01*
X300887Y1074965D01*
X301619Y1074233D01*
X301478Y1074092D01*
G37*
G36*
G01X301859Y1074275D02*
X302243Y1074457D01*
X302773Y1073927D01*
X302591Y1073544D01*
X302450Y1073402D01*
X301718Y1074134D01*
X301859Y1074275D01*
G37*
G36*
G01X303521Y1072614D02*
X303905Y1072796D01*
X304435Y1072265D01*
X304253Y1071882D01*
X304112Y1071740D01*
X303380Y1072472D01*
X303521Y1072614D01*
G37*
G36*
G01X305183Y1070952D02*
X305566Y1071134D01*
X306097Y1070604D01*
X305915Y1070220D01*
X305773Y1070079D01*
X305041Y1070811D01*
X305183Y1070952D01*
G37*
G36*
G01X304801Y1070768D02*
X304417Y1070586D01*
X303887Y1071116D01*
X304069Y1071500D01*
X304211Y1071641D01*
X304942Y1070910D01*
X304801Y1070768D01*
G37*
G36*
G01X303139Y1072430D02*
X302756Y1072248D01*
X302225Y1072778D01*
X302407Y1073162D01*
X302549Y1073303D01*
X303281Y1072571D01*
X303139Y1072430D01*
G37*
G36*
G01X305495Y1094365D02*
X305075Y1094427D01*
X304928Y1095162D01*
X305293Y1095380D01*
X305489Y1095419D01*
X305691Y1094404D01*
X305495Y1094365D01*
G37*
G36*
G01X304980Y1089602D02*
X305400Y1089665D01*
X305753Y1089003D01*
X305468Y1088689D01*
X305291Y1088595D01*
X304803Y1089508D01*
X304980Y1089602D01*
G37*
G36*
G01X303139Y1093896D02*
X302719Y1093958D01*
X302573Y1094694D01*
X302937Y1094911D01*
X303133Y1094950D01*
X303335Y1093935D01*
X303139Y1093896D01*
G37*
G36*
G01X303559Y1093837D02*
X303979Y1093775D01*
X304125Y1093040D01*
X303761Y1092822D01*
X303565Y1092783D01*
X303363Y1093798D01*
X303559Y1093837D01*
G37*
G36*
G01X303099Y1096142D02*
X303519Y1096080D01*
X303666Y1095345D01*
X303301Y1095127D01*
X303105Y1095088D01*
X302903Y1096103D01*
X303099Y1096142D01*
G37*
G36*
G01X304561Y1089537D02*
X304141Y1089474D01*
X303788Y1090135D01*
X304073Y1090450D01*
X304250Y1090544D01*
X304737Y1089631D01*
X304561Y1089537D01*
G37*
G36*
G01X305669Y1087464D02*
X305249Y1087401D01*
X304895Y1088063D01*
X305181Y1088377D01*
X305357Y1088471D01*
X305845Y1087559D01*
X305669Y1087464D01*
G37*
G36*
G01X304316Y1094130D02*
X303896Y1094192D01*
X303750Y1094928D01*
X304114Y1095146D01*
X304310Y1095185D01*
X304512Y1094169D01*
X304316Y1094130D01*
G37*
G36*
G01X304736Y1094071D02*
X305156Y1094010D01*
X305302Y1093274D01*
X304938Y1093056D01*
X304742Y1093017D01*
X304540Y1094032D01*
X304736Y1094071D01*
G37*
G36*
G01X304277Y1096376D02*
X304697Y1096314D01*
X304844Y1095579D01*
X304479Y1095361D01*
X304283Y1095322D01*
X304081Y1096337D01*
X304277Y1096376D01*
G37*
G36*
G01X305620Y1090103D02*
X305200Y1090040D01*
X304846Y1090701D01*
X305132Y1091016D01*
X305308Y1091110D01*
X305796Y1090197D01*
X305620Y1090103D01*
G37*
G36*
G01X301961Y1093662D02*
X301541Y1093724D01*
X301394Y1094459D01*
X301759Y1094677D01*
X301955Y1094716D01*
X302157Y1093701D01*
X301961Y1093662D01*
G37*
G36*
G01X305717Y1084826D02*
X305297Y1084763D01*
X304944Y1085424D01*
X305229Y1085738D01*
X305405Y1085833D01*
X305893Y1084920D01*
X305717Y1084826D01*
G37*
G36*
G01X302381Y1093603D02*
X302801Y1093541D01*
X302947Y1092805D01*
X302583Y1092588D01*
X302386Y1092549D01*
X302184Y1093564D01*
X302381Y1093603D01*
G37*
G36*
G01X302420Y1091357D02*
X301999Y1091419D01*
X301853Y1092154D01*
X302218Y1092372D01*
X302414Y1092411D01*
X302616Y1091396D01*
X302420Y1091357D01*
G37*
G36*
G01X301922Y1095907D02*
X302342Y1095846D01*
X302488Y1095110D01*
X302124Y1094892D01*
X301928Y1094853D01*
X301726Y1095868D01*
X301922Y1095907D01*
G37*
G36*
G01X304609Y1086898D02*
X304189Y1086835D01*
X303836Y1087497D01*
X304121Y1087811D01*
X304298Y1087905D01*
X304786Y1086992D01*
X304609Y1086898D01*
G37*
G36*
G01X303920Y1089036D02*
X304340Y1089099D01*
X304694Y1088437D01*
X304408Y1088123D01*
X304232Y1088029D01*
X303744Y1088941D01*
X303920Y1089036D01*
G37*
G36*
G01X303501Y1088971D02*
X303081Y1088908D01*
X302728Y1089569D01*
X303013Y1089883D01*
X303190Y1089978D01*
X303678Y1089065D01*
X303501Y1088971D01*
G37*
G36*
G01X305028Y1086963D02*
X305448Y1087026D01*
X305801Y1086365D01*
X305516Y1086050D01*
X305339Y1085956D01*
X304852Y1086869D01*
X305028Y1086963D01*
G37*
G36*
G01X297920Y1087394D02*
X298340Y1087457D01*
X298693Y1086795D01*
X298408Y1086481D01*
X298231Y1086387D01*
X297743Y1087299D01*
X297920Y1087394D01*
G37*
G36*
G01X298609Y1085256D02*
X298189Y1085193D01*
X297835Y1085855D01*
X298121Y1086169D01*
X298297Y1086263D01*
X298785Y1085350D01*
X298609Y1085256D01*
G37*
G36*
G01X296054Y1091955D02*
X295633Y1092017D01*
X295487Y1092752D01*
X295852Y1092970D01*
X296048Y1093009D01*
X296250Y1091994D01*
X296054Y1091955D01*
G37*
G36*
G01X296512Y1089650D02*
X296092Y1089712D01*
X295946Y1090448D01*
X296310Y1090665D01*
X296506Y1090704D01*
X296708Y1089689D01*
X296512Y1089650D01*
G37*
G36*
G01X296015Y1094201D02*
X296435Y1094139D01*
X296581Y1093403D01*
X296217Y1093185D01*
X296021Y1093146D01*
X295819Y1094162D01*
X296015Y1094201D01*
G37*
G36*
G01X297501Y1087328D02*
X297081Y1087266D01*
X296727Y1087927D01*
X297013Y1088241D01*
X297189Y1088336D01*
X297677Y1087423D01*
X297501Y1087328D01*
G37*
G36*
G01X296473Y1091896D02*
X296893Y1091834D01*
X297040Y1091098D01*
X296675Y1090881D01*
X296479Y1090842D01*
X296277Y1091857D01*
X296473Y1091896D01*
G37*
G36*
G01X295557Y1096505D02*
X295977Y1096444D01*
X296123Y1095708D01*
X295758Y1095490D01*
X295562Y1095451D01*
X295360Y1096467D01*
X295557Y1096505D01*
G37*
G36*
G01X295595Y1094260D02*
X295175Y1094322D01*
X295029Y1095057D01*
X295393Y1095275D01*
X295590Y1095314D01*
X295791Y1094299D01*
X295595Y1094260D01*
G37*
G36*
G01X301244Y1081177D02*
X301664Y1081240D01*
X302018Y1080578D01*
X301732Y1080264D01*
X301556Y1080170D01*
X301068Y1081082D01*
X301244Y1081177D01*
G37*
G36*
G01X299717Y1083184D02*
X299297Y1083121D01*
X298944Y1083782D01*
X299229Y1084097D01*
X299406Y1084191D01*
X299893Y1083278D01*
X299717Y1083184D01*
G37*
G36*
G01X299028Y1085321D02*
X299448Y1085384D01*
X299801Y1084723D01*
X299516Y1084409D01*
X299339Y1084314D01*
X298851Y1085227D01*
X299028Y1085321D01*
G37*
G36*
G01X300136Y1083249D02*
X300556Y1083312D01*
X300910Y1082650D01*
X300624Y1082336D01*
X300448Y1082242D01*
X299960Y1083155D01*
X300136Y1083249D01*
G37*
G36*
G01X300825Y1081112D02*
X300405Y1081049D01*
X300052Y1081710D01*
X300337Y1082024D01*
X300514Y1082119D01*
X301002Y1081206D01*
X300825Y1081112D01*
G37*
G36*
G01X298016Y1082116D02*
X298436Y1082178D01*
X298789Y1081517D01*
X298503Y1081203D01*
X298327Y1081108D01*
X297839Y1082021D01*
X298016Y1082116D01*
G37*
G36*
G01X298705Y1079978D02*
X298285Y1079915D01*
X297931Y1080576D01*
X298217Y1080891D01*
X298393Y1080985D01*
X298881Y1080072D01*
X298705Y1079978D01*
G37*
G36*
G01X296908Y1084188D02*
X297328Y1084251D01*
X297681Y1083589D01*
X297396Y1083275D01*
X297219Y1083181D01*
X296731Y1084094D01*
X296908Y1084188D01*
G37*
G36*
G01X297597Y1082050D02*
X297177Y1081988D01*
X296823Y1082649D01*
X297109Y1082963D01*
X297285Y1083057D01*
X297773Y1082145D01*
X297597Y1082050D01*
G37*
G36*
G01X296489Y1084123D02*
X296069Y1084060D01*
X295716Y1084721D01*
X296001Y1085036D01*
X296178Y1085130D01*
X296665Y1084217D01*
X296489Y1084123D01*
G37*
G36*
G01X293697Y1091486D02*
X293277Y1091548D01*
X293131Y1092284D01*
X293495Y1092501D01*
X293692Y1092540D01*
X293894Y1091525D01*
X293697Y1091486D01*
G37*
G36*
G01X294117Y1091427D02*
X294537Y1091365D01*
X294683Y1090630D01*
X294319Y1090412D01*
X294123Y1090373D01*
X293921Y1091388D01*
X294117Y1091427D01*
G37*
G36*
G01X294156Y1089181D02*
X293736Y1089243D01*
X293589Y1089979D01*
X293954Y1090196D01*
X294150Y1090236D01*
X294352Y1089220D01*
X294156Y1089181D01*
G37*
G36*
G01X293239Y1093791D02*
X292819Y1093853D01*
X292672Y1094588D01*
X293037Y1094806D01*
X293233Y1094845D01*
X293435Y1093830D01*
X293239Y1093791D01*
G37*
G36*
G01X293659Y1093732D02*
X294079Y1093670D01*
X294225Y1092934D01*
X293860Y1092717D01*
X293664Y1092678D01*
X293462Y1093693D01*
X293659Y1093732D01*
G37*
G36*
G01X295800Y1086261D02*
X296220Y1086323D01*
X296574Y1085662D01*
X296288Y1085348D01*
X296112Y1085253D01*
X295624Y1086166D01*
X295800Y1086261D01*
G37*
G36*
G01X295381Y1086195D02*
X294961Y1086133D01*
X294608Y1086794D01*
X294893Y1087108D01*
X295070Y1087203D01*
X295558Y1086290D01*
X295381Y1086195D01*
G37*
G36*
G01X297549Y1084689D02*
X297129Y1084626D01*
X296775Y1085288D01*
X297061Y1085602D01*
X297237Y1085696D01*
X297725Y1084784D01*
X297549Y1084689D01*
G37*
G36*
G01X297967Y1084754D02*
X298387Y1084817D01*
X298741Y1084156D01*
X298455Y1083842D01*
X298279Y1083747D01*
X297791Y1084660D01*
X297967Y1084754D01*
G37*
G36*
G01X298656Y1082617D02*
X298236Y1082554D01*
X297883Y1083215D01*
X298169Y1083530D01*
X298345Y1083624D01*
X298833Y1082711D01*
X298656Y1082617D01*
G37*
G36*
G01X294379Y1096271D02*
X294799Y1096209D01*
X294945Y1095474D01*
X294581Y1095256D01*
X294385Y1095217D01*
X294183Y1096232D01*
X294379Y1096271D01*
G37*
G36*
G01X294418Y1094026D02*
X293998Y1094087D01*
X293851Y1094823D01*
X294216Y1095041D01*
X294412Y1095080D01*
X294614Y1094065D01*
X294418Y1094026D01*
G37*
G36*
G01X296441Y1086762D02*
X296021Y1086699D01*
X295667Y1087360D01*
X295953Y1087675D01*
X296129Y1087769D01*
X296617Y1086856D01*
X296441Y1086762D01*
G37*
G36*
G01X295295Y1091661D02*
X295715Y1091600D01*
X295862Y1090864D01*
X295497Y1090646D01*
X295301Y1090607D01*
X295099Y1091622D01*
X295295Y1091661D01*
G37*
G36*
G01X294876Y1091721D02*
X294456Y1091782D01*
X294309Y1092518D01*
X294674Y1092736D01*
X294870Y1092775D01*
X295072Y1091760D01*
X294876Y1091721D01*
G37*
G36*
G01X295334Y1089416D02*
X294914Y1089478D01*
X294768Y1090213D01*
X295132Y1090431D01*
X295328Y1090470D01*
X295530Y1089455D01*
X295334Y1089416D01*
G37*
G36*
G01X294837Y1093966D02*
X295257Y1093905D01*
X295404Y1093169D01*
X295039Y1092951D01*
X294843Y1092912D01*
X294641Y1093927D01*
X294837Y1093966D01*
G37*
G36*
G01X296860Y1086827D02*
X297279Y1086890D01*
X297633Y1086228D01*
X297347Y1085914D01*
X297171Y1085820D01*
X296683Y1086733D01*
X296860Y1086827D01*
G37*
G36*
G01X300183Y1080609D02*
X300603Y1080672D01*
X300957Y1080011D01*
X300671Y1079697D01*
X300495Y1079602D01*
X300007Y1080515D01*
X300183Y1080609D01*
G37*
G36*
G01X299764Y1080544D02*
X299344Y1080481D01*
X298991Y1081143D01*
X299276Y1081457D01*
X299453Y1081551D01*
X299941Y1080639D01*
X299764Y1080544D01*
G37*
G36*
G01X299075Y1082682D02*
X299495Y1082745D01*
X299849Y1082083D01*
X299563Y1081769D01*
X299387Y1081675D01*
X298899Y1082588D01*
X299075Y1082682D01*
G37*
G36*
G01X295429Y1083556D02*
X295009Y1083494D01*
X294656Y1084155D01*
X294941Y1084469D01*
X295118Y1084564D01*
X295606Y1083651D01*
X295429Y1083556D01*
G37*
G36*
G01X296537Y1081484D02*
X296117Y1081421D01*
X295764Y1082083D01*
X296049Y1082397D01*
X296226Y1082491D01*
X296714Y1081578D01*
X296537Y1081484D01*
G37*
G36*
G01X295848Y1083622D02*
X296268Y1083684D01*
X296622Y1083023D01*
X296336Y1082709D01*
X296160Y1082615D01*
X295672Y1083527D01*
X295848Y1083622D01*
G37*
G36*
G01X296956Y1081549D02*
X297376Y1081612D01*
X297730Y1080951D01*
X297444Y1080636D01*
X297268Y1080542D01*
X296780Y1081455D01*
X296956Y1081549D01*
G37*
G36*
G01X294740Y1085694D02*
X295160Y1085757D01*
X295514Y1085096D01*
X295228Y1084781D01*
X295052Y1084687D01*
X294564Y1085600D01*
X294740Y1085694D01*
G37*
G36*
G01X294322Y1085629D02*
X293902Y1085566D01*
X293548Y1086227D01*
X293834Y1086542D01*
X294010Y1086636D01*
X294498Y1085723D01*
X294322Y1085629D01*
G37*
G36*
G01X292519Y1091252D02*
X292099Y1091313D01*
X291953Y1092049D01*
X292317Y1092267D01*
X292513Y1092306D01*
X292715Y1091291D01*
X292519Y1091252D01*
G37*
G36*
G01X292978Y1088947D02*
X292558Y1089009D01*
X292411Y1089744D01*
X292776Y1089962D01*
X292972Y1090001D01*
X293174Y1088986D01*
X292978Y1088947D01*
G37*
G36*
G01X292939Y1091193D02*
X293359Y1091131D01*
X293505Y1090395D01*
X293141Y1090177D01*
X292945Y1090138D01*
X292743Y1091154D01*
X292939Y1091193D01*
G37*
G36*
G01X292061Y1093557D02*
X291640Y1093618D01*
X291494Y1094354D01*
X291859Y1094572D01*
X292055Y1094611D01*
X292257Y1093596D01*
X292061Y1093557D01*
G37*
G36*
G01X292480Y1093497D02*
X292900Y1093436D01*
X293047Y1092700D01*
X292682Y1092482D01*
X292486Y1092443D01*
X292284Y1093458D01*
X292480Y1093497D01*
G37*
G36*
G01X305228Y1108726D02*
X304828Y1108869D01*
Y1109619D01*
X305228Y1109761D01*
X305428D01*
Y1108726D01*
X305228D01*
G37*
G36*
G01Y1111076D02*
X304828Y1111219D01*
Y1111969D01*
X305228Y1112111D01*
X305428D01*
Y1111076D01*
X305228D01*
G37*
G36*
G01X305456Y1096611D02*
X305876Y1096549D01*
X306022Y1095813D01*
X305658Y1095595D01*
X305462Y1095556D01*
X305260Y1096572D01*
X305456Y1096611D01*
G37*
G36*
G01X304997Y1098915D02*
X305418Y1098854D01*
X305564Y1098118D01*
X305199Y1097900D01*
X305003Y1097861D01*
X304801Y1098876D01*
X304997Y1098915D01*
G37*
G36*
G01X304539Y1101220D02*
X304959Y1101159D01*
X305105Y1100423D01*
X304741Y1100205D01*
X304545Y1100166D01*
X304343Y1101181D01*
X304539Y1101220D01*
G37*
G36*
G01X304578Y1098975D02*
X304158Y1099036D01*
X304011Y1099772D01*
X304376Y1099990D01*
X304572Y1100029D01*
X304774Y1099014D01*
X304578Y1098975D01*
G37*
G36*
G01X305036Y1096670D02*
X304616Y1096732D01*
X304470Y1097467D01*
X304834Y1097685D01*
X305031Y1097724D01*
X305232Y1096709D01*
X305036Y1096670D01*
G37*
G36*
G01X304119Y1101279D02*
X303699Y1101341D01*
X303553Y1102077D01*
X303917Y1102295D01*
X304113Y1102334D01*
X304315Y1101318D01*
X304119Y1101279D01*
G37*
G36*
G01X302744Y1108194D02*
X302323Y1108256D01*
X302177Y1108991D01*
X302542Y1109209D01*
X302738Y1109248D01*
X302940Y1108233D01*
X302744Y1108194D01*
G37*
G36*
G01X304080Y1103525D02*
X304500Y1103463D01*
X304647Y1102728D01*
X304282Y1102510D01*
X304086Y1102471D01*
X303884Y1103486D01*
X304080Y1103525D01*
G37*
G36*
G01X303622Y1105830D02*
X304042Y1105768D01*
X304188Y1105033D01*
X303824Y1104815D01*
X303628Y1104776D01*
X303426Y1105791D01*
X303622Y1105830D01*
G37*
G36*
G01X303661Y1103584D02*
X303241Y1103646D01*
X303094Y1104382D01*
X303459Y1104599D01*
X303655Y1104638D01*
X303857Y1103623D01*
X303661Y1103584D01*
G37*
G36*
G01X303163Y1108135D02*
X303583Y1108073D01*
X303730Y1107337D01*
X303365Y1107120D01*
X303169Y1107081D01*
X302967Y1108096D01*
X303163Y1108135D01*
G37*
G36*
G01X303202Y1105889D02*
X302782Y1105951D01*
X302636Y1106686D01*
X303000Y1106904D01*
X303196Y1106943D01*
X303398Y1105928D01*
X303202Y1105889D01*
G37*
G36*
G01X301763Y1100811D02*
X301343Y1100872D01*
X301197Y1101608D01*
X301561Y1101826D01*
X301757Y1101865D01*
X301959Y1100850D01*
X301763Y1100811D01*
G37*
G36*
G01X301723Y1103056D02*
X302143Y1102995D01*
X302290Y1102259D01*
X301925Y1102041D01*
X301729Y1102002D01*
X301527Y1103017D01*
X301723Y1103056D01*
G37*
G36*
G01X301266Y1105361D02*
X301686Y1105299D01*
X301832Y1104564D01*
X301468Y1104346D01*
X301271Y1104307D01*
X301069Y1105322D01*
X301266Y1105361D01*
G37*
G36*
G01X300846Y1105420D02*
X300426Y1105482D01*
X300279Y1106218D01*
X300644Y1106435D01*
X300840Y1106474D01*
X301042Y1105459D01*
X300846Y1105420D01*
G37*
G36*
G01X300807Y1107666D02*
X301227Y1107604D01*
X301373Y1106869D01*
X301009Y1106651D01*
X300813Y1106612D01*
X300611Y1107627D01*
X300807Y1107666D01*
G37*
G36*
G01X301305Y1103116D02*
X300884Y1103177D01*
X300738Y1103913D01*
X301103Y1104131D01*
X301299Y1104170D01*
X301501Y1103155D01*
X301305Y1103116D01*
G37*
G36*
G01X302680Y1096201D02*
X302260Y1096263D01*
X302114Y1096998D01*
X302478Y1097216D01*
X302675Y1097255D01*
X302877Y1096240D01*
X302680Y1096201D01*
G37*
G36*
G01X302183Y1100751D02*
X302603Y1100690D01*
X302749Y1099954D01*
X302385Y1099736D01*
X302189Y1099697D01*
X301987Y1100712D01*
X302183Y1100751D01*
G37*
G36*
G01X302640Y1098447D02*
X303061Y1098385D01*
X303207Y1097649D01*
X302842Y1097432D01*
X302646Y1097393D01*
X302444Y1098408D01*
X302640Y1098447D01*
G37*
G36*
G01X302222Y1098506D02*
X301802Y1098568D01*
X301655Y1099303D01*
X302020Y1099521D01*
X302216Y1099560D01*
X302418Y1098545D01*
X302222Y1098506D01*
G37*
G36*
G01X302023Y1105655D02*
X301603Y1105716D01*
X301457Y1106452D01*
X301821Y1106670D01*
X302017Y1106709D01*
X302219Y1105694D01*
X302023Y1105655D01*
G37*
G36*
G01X301566Y1107959D02*
X301145Y1108021D01*
X300999Y1108757D01*
X301364Y1108974D01*
X301560Y1109014D01*
X301762Y1107998D01*
X301566Y1107959D01*
G37*
G36*
G01X303819Y1098681D02*
X304239Y1098619D01*
X304385Y1097884D01*
X304021Y1097666D01*
X303824Y1097627D01*
X303622Y1098642D01*
X303819Y1098681D01*
G37*
G36*
G01X303360Y1100986D02*
X303780Y1100924D01*
X303926Y1100188D01*
X303562Y1099971D01*
X303366Y1099932D01*
X303164Y1100947D01*
X303360Y1100986D01*
G37*
G36*
G01X303859Y1096435D02*
X303438Y1096497D01*
X303292Y1097233D01*
X303657Y1097450D01*
X303853Y1097489D01*
X304055Y1096474D01*
X303859Y1096435D01*
G37*
G36*
G01X302940Y1101045D02*
X302520Y1101107D01*
X302374Y1101842D01*
X302738Y1102060D01*
X302935Y1102099D01*
X303137Y1101084D01*
X302940Y1101045D01*
G37*
G36*
G01X303400Y1098740D02*
X302980Y1098802D01*
X302833Y1099537D01*
X303198Y1099755D01*
X303394Y1099794D01*
X303596Y1098779D01*
X303400Y1098740D01*
G37*
G36*
G01X302483Y1103350D02*
X302063Y1103411D01*
X301916Y1104147D01*
X302281Y1104365D01*
X302477Y1104404D01*
X302679Y1103389D01*
X302483Y1103350D01*
G37*
G36*
G01X302901Y1103290D02*
X303322Y1103229D01*
X303468Y1102493D01*
X303103Y1102275D01*
X302907Y1102236D01*
X302705Y1103251D01*
X302901Y1103290D01*
G37*
G36*
G01X302443Y1105595D02*
X302863Y1105534D01*
X303009Y1104798D01*
X302645Y1104580D01*
X302449Y1104541D01*
X302247Y1105556D01*
X302443Y1105595D01*
G37*
G36*
G01X301984Y1107900D02*
X302404Y1107838D01*
X302551Y1107103D01*
X302186Y1106885D01*
X301990Y1106846D01*
X301788Y1107861D01*
X301984Y1107900D01*
G37*
G36*
G01X299209Y1107491D02*
X298789Y1107552D01*
X298643Y1108288D01*
X299007Y1108506D01*
X299203Y1108545D01*
X299405Y1107530D01*
X299209Y1107491D01*
G37*
G36*
G01X301463Y1098212D02*
X301883Y1098151D01*
X302030Y1097415D01*
X301665Y1097197D01*
X301469Y1097158D01*
X301267Y1098173D01*
X301463Y1098212D01*
G37*
G36*
G01X301044Y1098272D02*
X300624Y1098333D01*
X300477Y1099069D01*
X300842Y1099287D01*
X301038Y1099326D01*
X301240Y1098311D01*
X301044Y1098272D01*
G37*
G36*
G01X301502Y1095967D02*
X301082Y1096028D01*
X300936Y1096764D01*
X301300Y1096982D01*
X301496Y1097021D01*
X301698Y1096006D01*
X301502Y1095967D01*
G37*
G36*
G01X301005Y1100517D02*
X301425Y1100455D01*
X301571Y1099720D01*
X301207Y1099502D01*
X301010Y1099463D01*
X300809Y1100478D01*
X301005Y1100517D01*
G37*
G36*
G01X300585Y1100576D02*
X300165Y1100638D01*
X300019Y1101374D01*
X300383Y1101591D01*
X300579Y1101630D01*
X300781Y1100615D01*
X300585Y1100576D01*
G37*
G36*
G01X300126Y1102881D02*
X299706Y1102943D01*
X299560Y1103678D01*
X299924Y1103896D01*
X300121Y1103935D01*
X300323Y1102920D01*
X300126Y1102881D01*
G37*
G36*
G01X300087Y1105127D02*
X300508Y1105065D01*
X300654Y1104329D01*
X300289Y1104112D01*
X300093Y1104073D01*
X299891Y1105088D01*
X300087Y1105127D01*
G37*
G36*
G01X299668Y1105186D02*
X299248Y1105248D01*
X299101Y1105983D01*
X299466Y1106201D01*
X299662Y1106240D01*
X299864Y1105225D01*
X299668Y1105186D01*
G37*
G36*
G01X299629Y1107432D02*
X300049Y1107370D01*
X300195Y1106634D01*
X299831Y1106416D01*
X299635Y1106377D01*
X299433Y1107392D01*
X299629Y1107432D01*
G37*
G36*
G01X300546Y1102822D02*
X300966Y1102760D01*
X301113Y1102025D01*
X300748Y1101807D01*
X300552Y1101768D01*
X300350Y1102783D01*
X300546Y1102822D01*
G37*
G36*
G01X305228Y1115776D02*
X304828Y1115919D01*
Y1116669D01*
X305228Y1116811D01*
X305428D01*
Y1115776D01*
X305228D01*
G37*
G36*
G01Y1113426D02*
X304828Y1113569D01*
Y1114319D01*
X305228Y1114461D01*
X305428D01*
Y1113426D01*
X305228D01*
G37*
G36*
G01Y1120476D02*
X304828Y1120619D01*
Y1121369D01*
X305228Y1121511D01*
X305428D01*
Y1120476D01*
X305228D01*
G37*
G36*
G01Y1118126D02*
X304828Y1118269D01*
Y1119019D01*
X305228Y1119161D01*
X305428D01*
Y1118126D01*
X305228D01*
G37*
G36*
G01X297379Y1575686D02*
G03I-720J0D01*
G37*
G36*
G01X302335D02*
G03I-720J0D01*
G37*
G36*
G01X297379Y1580678D02*
G03I-720J0D01*
G37*
G36*
G01X302335D02*
G03I-720J0D01*
G37*
G36*
G01X290619Y1599884D02*
G03I-720J0D01*
G37*
G36*
G01X297379Y1587598D02*
G03I-720J0D01*
G37*
G36*
G01X302335D02*
G03I-720J0D01*
G37*
G36*
G01X297379Y1592590D02*
G03I-720J0D01*
G37*
G36*
G01X302335D02*
G03I-720J0D01*
G37*
G36*
G01X295575Y1599884D02*
G03I-720J0D01*
G37*
G36*
G01X302679D02*
G03I-720J0D01*
G37*
G36*
G01X290619Y1616788D02*
G03I-720J0D01*
G37*
G36*
G01Y1604876D02*
G03I-720J0D01*
G37*
G36*
G01Y1611796D02*
G03I-720J0D01*
G37*
G36*
G01X295575Y1616788D02*
G03I-720J0D01*
G37*
G36*
G01Y1604876D02*
G03I-720J0D01*
G37*
G36*
G01Y1611796D02*
G03I-720J0D01*
G37*
G36*
G01X302679Y1604876D02*
G03I-720J0D01*
G37*
G36*
G01Y1611796D02*
G03I-720J0D01*
G37*
G36*
G01Y1616788D02*
G03I-720J0D01*
G37*
G36*
G01X318597Y81953D02*
X318097D01*
X317867Y82183D01*
Y85373D01*
Y89113D01*
X318557Y89803D01*
X319000Y90246D01*
Y92983D01*
X319320Y93303D01*
X320557D01*
X321057Y92803D01*
Y88563D01*
Y84413D01*
X318597Y81953D01*
G37*
G36*
G01X340424Y240248D02*
X346456D01*
X348385Y238319D01*
Y227097D01*
X347540Y226252D01*
X345540D01*
X344980Y226812D01*
Y228942D01*
X344613Y229309D01*
X341485D01*
X340285Y228109D01*
Y226997D01*
X340194Y226906D01*
X340064D01*
G03X339176Y226537I1J-1256D01*
G01X338747Y226109D01*
X337185D01*
X336985Y226309D01*
Y235509D01*
X336850Y235644D01*
X336836Y235696D01*
G03X335385Y236811I-1451J-387D01*
G03X333974Y235825I0J-1503D01*
G01X333959Y235783D01*
X333885Y235709D01*
Y235382D01*
G03X333883Y235309I1500J-78D01*
G03X333885Y235236I1502J5D01*
G01Y233749D01*
X333455Y233319D01*
X327955D01*
X327884Y233248D01*
X327716D01*
Y233080D01*
X327445Y232809D01*
Y229294D01*
X327444Y229284D01*
G03X327437Y229139I1495J-145D01*
G03X327444Y228994I1502J0D01*
G01X327445Y228984D01*
Y223069D01*
X327875Y222639D01*
X329135D01*
X329425Y222349D01*
Y222019D01*
X329125Y221719D01*
X326685D01*
X326525Y221879D01*
Y224719D01*
X323914Y227330D01*
Y228431D01*
G03X324160Y229254I-1256J824D01*
G03X323914Y230077I-1502J-1D01*
G01Y231641D01*
G03X323863Y231996I-1256J1D01*
G01X323855Y232024D01*
Y233477D01*
X323313Y234019D01*
X320855D01*
X320655Y234219D01*
Y236474D01*
G02X321031Y236873I400J0D01*
G03X322442Y238372I-91J1499D01*
G03X322008Y239428I-1502J0D01*
G02X322293Y240109I285J281D01*
G01X340285D01*
X340424Y240248D01*
G37*
G36*
G01X311896Y852127D02*
X312296Y851984D01*
Y851234D01*
X311896Y851091D01*
X311696D01*
Y852127D01*
X311896D01*
G37*
G36*
G01X311496Y849917D02*
X311096Y850059D01*
Y850809D01*
X311496Y850951D01*
X311696D01*
Y849917D01*
X311496D01*
G37*
G36*
G01Y847567D02*
X311096Y847709D01*
Y848459D01*
X311496Y848601D01*
X311696D01*
Y847567D01*
X311496D01*
G37*
G36*
G01X311896Y849777D02*
X312296Y849634D01*
Y848884D01*
X311896Y848741D01*
X311696D01*
Y849777D01*
X311896D01*
G37*
G36*
G01X314296D02*
X314696Y849634D01*
Y848884D01*
X314296Y848741D01*
X314096D01*
Y849777D01*
X314296D01*
G37*
G36*
G01Y847427D02*
X314696Y847284D01*
Y846534D01*
X314296Y846391D01*
X314096D01*
Y847427D01*
X314296D01*
G37*
G36*
G01Y852127D02*
X314696Y851984D01*
Y851234D01*
X314296Y851091D01*
X314096D01*
Y852127D01*
X314296D01*
G37*
G36*
G01X313896Y849917D02*
X313496Y850059D01*
Y850809D01*
X313896Y850951D01*
X314096D01*
Y849917D01*
X313896D01*
G37*
G36*
G01Y847567D02*
X313496Y847709D01*
Y848459D01*
X313896Y848601D01*
X314096D01*
Y847567D01*
X313896D01*
G37*
G36*
G01X312696Y849917D02*
X312296Y850059D01*
Y850809D01*
X312696Y850951D01*
X312896D01*
Y849917D01*
X312696D01*
G37*
G36*
G01Y847567D02*
X312296Y847709D01*
Y848459D01*
X312696Y848601D01*
X312896D01*
Y847567D01*
X312696D01*
G37*
G36*
G01X313096Y849777D02*
X313496Y849634D01*
Y848884D01*
X313096Y848741D01*
X312896D01*
Y849777D01*
X313096D01*
G37*
G36*
G01Y847427D02*
X313496Y847284D01*
Y846534D01*
X313096Y846391D01*
X312896D01*
Y847427D01*
X313096D01*
G37*
G36*
G01Y852127D02*
X313496Y851984D01*
Y851234D01*
X313096Y851091D01*
X312896D01*
Y852127D01*
X313096D01*
G37*
G36*
G01X315096Y849917D02*
X314696Y850059D01*
Y850809D01*
X315096Y850951D01*
X315296D01*
Y849917D01*
X315096D01*
G37*
G36*
G01Y847567D02*
X314696Y847709D01*
Y848459D01*
X315096Y848601D01*
X315296D01*
Y847567D01*
X315096D01*
G37*
G36*
G01Y845217D02*
X314696Y845359D01*
Y846109D01*
X315096Y846251D01*
X315296D01*
Y845217D01*
X315096D01*
G37*
G36*
G01X315496Y849777D02*
X315896Y849634D01*
Y848884D01*
X315496Y848741D01*
X315296D01*
Y849777D01*
X315496D01*
G37*
G36*
G01Y847427D02*
X315896Y847284D01*
Y846534D01*
X315496Y846391D01*
X315296D01*
Y847427D01*
X315496D01*
G37*
G36*
G01Y852127D02*
X315896Y851984D01*
Y851234D01*
X315496Y851091D01*
X315296D01*
Y852127D01*
X315496D01*
G37*
G36*
G01X320676Y852647D02*
X321076Y852504D01*
Y851754D01*
X320676Y851611D01*
X320476D01*
Y852647D01*
X320676D01*
G37*
G36*
G01X305896Y862191D02*
X306296Y862049D01*
Y861299D01*
X305896Y861157D01*
X305696D01*
Y862191D01*
X305896D01*
G37*
G36*
G01Y866891D02*
X306296Y866749D01*
Y865999D01*
X305896Y865857D01*
X305696D01*
Y866891D01*
X305896D01*
G37*
G36*
G01Y864541D02*
X306296Y864399D01*
Y863649D01*
X305896Y863507D01*
X305696D01*
Y864541D01*
X305896D01*
G37*
G36*
G01X311896Y868577D02*
X312296Y868434D01*
Y867684D01*
X311896Y867541D01*
X311696D01*
Y868577D01*
X311896D01*
G37*
G36*
G01X311496Y852267D02*
X311096Y852409D01*
Y853159D01*
X311496Y853301D01*
X311696D01*
Y852267D01*
X311496D01*
G37*
G36*
G01X311896Y854477D02*
X312296Y854334D01*
Y853584D01*
X311896Y853441D01*
X311696D01*
Y854477D01*
X311896D01*
G37*
G36*
G01X311496Y856967D02*
X311096Y857109D01*
Y857859D01*
X311496Y858001D01*
X311696D01*
Y856967D01*
X311496D01*
G37*
G36*
G01Y854617D02*
X311096Y854759D01*
Y855509D01*
X311496Y855651D01*
X311696D01*
Y854617D01*
X311496D01*
G37*
G36*
G01Y859317D02*
X311096Y859459D01*
Y860209D01*
X311496Y860351D01*
X311696D01*
Y859317D01*
X311496D01*
G37*
G36*
G01Y861667D02*
X311096Y861809D01*
Y862559D01*
X311496Y862701D01*
X311696D01*
Y861667D01*
X311496D01*
G37*
G36*
G01X311896Y859177D02*
X312296Y859034D01*
Y858284D01*
X311896Y858141D01*
X311696D01*
Y859177D01*
X311896D01*
G37*
G36*
G01Y856827D02*
X312296Y856684D01*
Y855934D01*
X311896Y855791D01*
X311696D01*
Y856827D01*
X311896D01*
G37*
G36*
G01Y861527D02*
X312296Y861384D01*
Y860634D01*
X311896Y860491D01*
X311696D01*
Y861527D01*
X311896D01*
G37*
G36*
G01X311496Y864017D02*
X311096Y864159D01*
Y864909D01*
X311496Y865051D01*
X311696D01*
Y864017D01*
X311496D01*
G37*
G36*
G01Y866367D02*
X311096Y866509D01*
Y867259D01*
X311496Y867401D01*
X311696D01*
Y866367D01*
X311496D01*
G37*
G36*
G01X311896Y863877D02*
X312296Y863734D01*
Y862984D01*
X311896Y862841D01*
X311696D01*
Y863877D01*
X311896D01*
G37*
G36*
G01Y866227D02*
X312296Y866084D01*
Y865334D01*
X311896Y865191D01*
X311696D01*
Y866227D01*
X311896D01*
G37*
G36*
G01X313896Y852267D02*
X313496Y852409D01*
Y853159D01*
X313896Y853301D01*
X314096D01*
Y852267D01*
X313896D01*
G37*
G36*
G01X314296Y854477D02*
X314696Y854334D01*
Y853584D01*
X314296Y853441D01*
X314096D01*
Y854477D01*
X314296D01*
G37*
G36*
G01X313896Y856967D02*
X313496Y857109D01*
Y857859D01*
X313896Y858001D01*
X314096D01*
Y856967D01*
X313896D01*
G37*
G36*
G01Y854617D02*
X313496Y854759D01*
Y855509D01*
X313896Y855651D01*
X314096D01*
Y854617D01*
X313896D01*
G37*
G36*
G01Y859317D02*
X313496Y859459D01*
Y860209D01*
X313896Y860351D01*
X314096D01*
Y859317D01*
X313896D01*
G37*
G36*
G01Y861667D02*
X313496Y861809D01*
Y862559D01*
X313896Y862701D01*
X314096D01*
Y861667D01*
X313896D01*
G37*
G36*
G01X314296Y856827D02*
X314696Y856684D01*
Y855934D01*
X314296Y855791D01*
X314096D01*
Y856827D01*
X314296D01*
G37*
G36*
G01Y859177D02*
X314696Y859034D01*
Y858284D01*
X314296Y858141D01*
X314096D01*
Y859177D01*
X314296D01*
G37*
G36*
G01Y861527D02*
X314696Y861384D01*
Y860634D01*
X314296Y860491D01*
X314096D01*
Y861527D01*
X314296D01*
G37*
G36*
G01X313896Y864017D02*
X313496Y864159D01*
Y864909D01*
X313896Y865051D01*
X314096D01*
Y864017D01*
X313896D01*
G37*
G36*
G01Y866367D02*
X313496Y866509D01*
Y867259D01*
X313896Y867401D01*
X314096D01*
Y866367D01*
X313896D01*
G37*
G36*
G01X314296Y863877D02*
X314696Y863734D01*
Y862984D01*
X314296Y862841D01*
X314096D01*
Y863877D01*
X314296D01*
G37*
G36*
G01Y866227D02*
X314696Y866084D01*
Y865334D01*
X314296Y865191D01*
X314096D01*
Y866227D01*
X314296D01*
G37*
G36*
G01Y868577D02*
X314696Y868434D01*
Y867684D01*
X314296Y867541D01*
X314096D01*
Y868577D01*
X314296D01*
G37*
G36*
G01X312696Y866367D02*
X312296Y866509D01*
Y867259D01*
X312696Y867401D01*
X312896D01*
Y866367D01*
X312696D01*
G37*
G36*
G01X313096Y863877D02*
X313496Y863734D01*
Y862984D01*
X313096Y862841D01*
X312896D01*
Y863877D01*
X313096D01*
G37*
G36*
G01Y866227D02*
X313496Y866084D01*
Y865334D01*
X313096Y865191D01*
X312896D01*
Y866227D01*
X313096D01*
G37*
G36*
G01Y868577D02*
X313496Y868434D01*
Y867684D01*
X313096Y867541D01*
X312896D01*
Y868577D01*
X313096D01*
G37*
G36*
G01X312696Y852267D02*
X312296Y852409D01*
Y853159D01*
X312696Y853301D01*
X312896D01*
Y852267D01*
X312696D01*
G37*
G36*
G01X313096Y854477D02*
X313496Y854334D01*
Y853584D01*
X313096Y853441D01*
X312896D01*
Y854477D01*
X313096D01*
G37*
G36*
G01X312696Y856967D02*
X312296Y857109D01*
Y857859D01*
X312696Y858001D01*
X312896D01*
Y856967D01*
X312696D01*
G37*
G36*
G01Y854617D02*
X312296Y854759D01*
Y855509D01*
X312696Y855651D01*
X312896D01*
Y854617D01*
X312696D01*
G37*
G36*
G01Y859317D02*
X312296Y859459D01*
Y860209D01*
X312696Y860351D01*
X312896D01*
Y859317D01*
X312696D01*
G37*
G36*
G01Y861667D02*
X312296Y861809D01*
Y862559D01*
X312696Y862701D01*
X312896D01*
Y861667D01*
X312696D01*
G37*
G36*
G01X313096Y859177D02*
X313496Y859034D01*
Y858284D01*
X313096Y858141D01*
X312896D01*
Y859177D01*
X313096D01*
G37*
G36*
G01Y856827D02*
X313496Y856684D01*
Y855934D01*
X313096Y855791D01*
X312896D01*
Y856827D01*
X313096D01*
G37*
G36*
G01Y861527D02*
X313496Y861384D01*
Y860634D01*
X313096Y860491D01*
X312896D01*
Y861527D01*
X313096D01*
G37*
G36*
G01X312696Y864017D02*
X312296Y864159D01*
Y864909D01*
X312696Y865051D01*
X312896D01*
Y864017D01*
X312696D01*
G37*
G36*
G01X315096D02*
X314696Y864159D01*
Y864909D01*
X315096Y865051D01*
X315296D01*
Y864017D01*
X315096D01*
G37*
G36*
G01Y866367D02*
X314696Y866509D01*
Y867259D01*
X315096Y867401D01*
X315296D01*
Y866367D01*
X315096D01*
G37*
G36*
G01Y852267D02*
X314696Y852409D01*
Y853159D01*
X315096Y853301D01*
X315296D01*
Y852267D01*
X315096D01*
G37*
G36*
G01Y859317D02*
X314696Y859459D01*
Y860209D01*
X315096Y860351D01*
X315296D01*
Y859317D01*
X315096D01*
G37*
G36*
G01Y861667D02*
X314696Y861809D01*
Y862559D01*
X315096Y862701D01*
X315296D01*
Y861667D01*
X315096D01*
G37*
G36*
G01Y856967D02*
X314696Y857109D01*
Y857859D01*
X315096Y858001D01*
X315296D01*
Y856967D01*
X315096D01*
G37*
G36*
G01Y854617D02*
X314696Y854759D01*
Y855509D01*
X315096Y855651D01*
X315296D01*
Y854617D01*
X315096D01*
G37*
G36*
G01X315496Y866227D02*
X315896Y866084D01*
Y865334D01*
X315496Y865191D01*
X315296D01*
Y866227D01*
X315496D01*
G37*
G36*
G01Y868577D02*
X315896Y868434D01*
Y867684D01*
X315496Y867541D01*
X315296D01*
Y868577D01*
X315496D01*
G37*
G36*
G01Y854477D02*
X315896Y854334D01*
Y853584D01*
X315496Y853441D01*
X315296D01*
Y854477D01*
X315496D01*
G37*
G36*
G01Y861527D02*
X315896Y861384D01*
Y860634D01*
X315496Y860491D01*
X315296D01*
Y861527D01*
X315496D01*
G37*
G36*
G01Y859177D02*
X315896Y859034D01*
Y858284D01*
X315496Y858141D01*
X315296D01*
Y859177D01*
X315496D01*
G37*
G36*
G01Y856827D02*
X315896Y856684D01*
Y855934D01*
X315496Y855791D01*
X315296D01*
Y856827D01*
X315496D01*
G37*
G36*
G01Y863877D02*
X315896Y863734D01*
Y862984D01*
X315496Y862841D01*
X315296D01*
Y863877D01*
X315496D01*
G37*
G36*
G01X320276Y852787D02*
X319876Y852929D01*
Y853679D01*
X320276Y853821D01*
X320476D01*
Y852787D01*
X320276D01*
G37*
G36*
G01Y855137D02*
X319876Y855279D01*
Y856029D01*
X320276Y856171D01*
X320476D01*
Y855137D01*
X320276D01*
G37*
G36*
G01Y857487D02*
X319876Y857629D01*
Y858379D01*
X320276Y858521D01*
X320476D01*
Y857487D01*
X320276D01*
G37*
G36*
G01X320676Y854997D02*
X321076Y854854D01*
Y854104D01*
X320676Y853961D01*
X320476D01*
Y854997D01*
X320676D01*
G37*
G36*
G01Y857347D02*
X321076Y857204D01*
Y856454D01*
X320676Y856311D01*
X320476D01*
Y857347D01*
X320676D01*
G37*
G36*
G01Y859697D02*
X321076Y859554D01*
Y858804D01*
X320676Y858661D01*
X320476D01*
Y859697D01*
X320676D01*
G37*
G36*
G01X321476Y852787D02*
X321076Y852929D01*
Y853679D01*
X321476Y853821D01*
X321676D01*
Y852787D01*
X321476D01*
G37*
G36*
G01Y855137D02*
X321076Y855279D01*
Y856029D01*
X321476Y856171D01*
X321676D01*
Y855137D01*
X321476D01*
G37*
G36*
G01Y857487D02*
X321076Y857629D01*
Y858379D01*
X321476Y858521D01*
X321676D01*
Y857487D01*
X321476D01*
G37*
G36*
G01X305616Y881834D02*
X305434Y882217D01*
X305964Y882748D01*
X306348Y882565D01*
X306489Y882424D01*
X305757Y881692D01*
X305616Y881834D01*
G37*
G36*
G01X307461Y883114D02*
X307643Y882730D01*
X307113Y882200D01*
X306729Y882382D01*
X306588Y882523D01*
X307320Y883255D01*
X307461Y883114D01*
G37*
G36*
G01X307278Y883495D02*
X307095Y883879D01*
X307626Y884409D01*
X308009Y884227D01*
X308151Y884086D01*
X307419Y883354D01*
X307278Y883495D01*
G37*
G36*
G01X309123Y884775D02*
X309305Y884392D01*
X308775Y883861D01*
X308391Y884043D01*
X308250Y884185D01*
X308982Y884917D01*
X309123Y884775D01*
G37*
G36*
G01X306612Y883963D02*
X306794Y883579D01*
X306264Y883049D01*
X305880Y883231D01*
X305739Y883372D01*
X306471Y884104D01*
X306612Y883963D01*
G37*
G36*
G01X306429Y884344D02*
X306246Y884728D01*
X306777Y885258D01*
X307160Y885076D01*
X307302Y884935D01*
X306570Y884203D01*
X306429Y884344D01*
G37*
G36*
G01X308310Y882265D02*
X308492Y881881D01*
X307962Y881351D01*
X307578Y881533D01*
X307437Y881674D01*
X308169Y882406D01*
X308310Y882265D01*
G37*
G36*
G01X309972Y883926D02*
X310154Y883543D01*
X309624Y883012D01*
X309240Y883194D01*
X309099Y883336D01*
X309831Y884068D01*
X309972Y883926D01*
G37*
G36*
G01X306465Y880985D02*
X306283Y881368D01*
X306813Y881899D01*
X307197Y881716D01*
X307338Y881575D01*
X306606Y880843D01*
X306465Y880985D01*
G37*
G36*
G01X308127Y882646D02*
X307944Y883030D01*
X308475Y883560D01*
X308858Y883378D01*
X309000Y883237D01*
X308268Y882505D01*
X308127Y882646D01*
G37*
G36*
G01X309788Y884308D02*
X309606Y884692D01*
X310136Y885222D01*
X310520Y885040D01*
X310661Y884898D01*
X309930Y884167D01*
X309788Y884308D01*
G37*
G36*
G01X305896Y873941D02*
X306296Y873799D01*
Y873049D01*
X305896Y872907D01*
X305696D01*
Y873941D01*
X305896D01*
G37*
G36*
G01Y876291D02*
X306296Y876149D01*
Y875399D01*
X305896Y875257D01*
X305696D01*
Y876291D01*
X305896D01*
G37*
G36*
G01Y878641D02*
X306296Y878499D01*
Y877749D01*
X305896Y877607D01*
X305696D01*
Y878641D01*
X305896D01*
G37*
G36*
G01Y871591D02*
X306296Y871449D01*
Y870699D01*
X305896Y870557D01*
X305696D01*
Y871591D01*
X305896D01*
G37*
G36*
G01Y869241D02*
X306296Y869099D01*
Y868349D01*
X305896Y868207D01*
X305696D01*
Y869241D01*
X305896D01*
G37*
G36*
G01X311896Y873277D02*
X312296Y873134D01*
Y872384D01*
X311896Y872241D01*
X311696D01*
Y873277D01*
X311896D01*
G37*
G36*
G01Y875627D02*
X312296Y875484D01*
Y874734D01*
X311896Y874591D01*
X311696D01*
Y875627D01*
X311896D01*
G37*
G36*
G01X313702Y879168D02*
X313884Y878784D01*
X313353Y878254D01*
X312970Y878436D01*
X312828Y878577D01*
X313560Y879309D01*
X313702Y879168D01*
G37*
G36*
G01X313518Y879550D02*
X313336Y879933D01*
X313866Y880464D01*
X314250Y880281D01*
X314391Y880140D01*
X313659Y879408D01*
X313518Y879550D01*
G37*
G36*
G01X315363Y880830D02*
X315545Y880446D01*
X315015Y879916D01*
X314631Y880098D01*
X314490Y880239D01*
X315222Y880971D01*
X315363Y880830D01*
G37*
G36*
G01X311496Y868717D02*
X311096Y868859D01*
Y869609D01*
X311496Y869751D01*
X311696D01*
Y868717D01*
X311496D01*
G37*
G36*
G01Y871067D02*
X311096Y871209D01*
Y871959D01*
X311496Y872101D01*
X311696D01*
Y871067D01*
X311496D01*
G37*
G36*
G01X311896Y870927D02*
X312296Y870784D01*
Y870034D01*
X311896Y869891D01*
X311696D01*
Y870927D01*
X311896D01*
G37*
G36*
G01X311496Y873417D02*
X311096Y873559D01*
Y874309D01*
X311496Y874451D01*
X311696D01*
Y873417D01*
X311496D01*
G37*
G36*
G01Y875767D02*
X311096Y875909D01*
Y876659D01*
X311496Y876801D01*
X311696D01*
Y875767D01*
X311496D01*
G37*
G36*
G01X315180Y881211D02*
X314997Y881595D01*
X315528Y882125D01*
X315911Y881943D01*
X316053Y881802D01*
X315321Y881070D01*
X315180Y881211D01*
G37*
G36*
G01X317025Y882491D02*
X317207Y882108D01*
X316677Y881577D01*
X316293Y881759D01*
X316152Y881901D01*
X316884Y882633D01*
X317025Y882491D01*
G37*
G36*
G01X313896Y873417D02*
X313496Y873559D01*
Y874309D01*
X313896Y874451D01*
X314096D01*
Y873417D01*
X313896D01*
G37*
G36*
G01X314296Y873277D02*
X314696Y873134D01*
Y872384D01*
X314296Y872241D01*
X314096D01*
Y873277D01*
X314296D01*
G37*
G36*
G01Y875627D02*
X314696Y875484D01*
Y874734D01*
X314296Y874591D01*
X314096D01*
Y875627D01*
X314296D01*
G37*
G36*
G01X315400Y877470D02*
X315582Y877086D01*
X315051Y876556D01*
X314668Y876738D01*
X314526Y876879D01*
X315258Y877611D01*
X315400Y877470D01*
G37*
G36*
G01X313896Y868717D02*
X313496Y868859D01*
Y869609D01*
X313896Y869751D01*
X314096D01*
Y868717D01*
X313896D01*
G37*
G36*
G01Y871067D02*
X313496Y871209D01*
Y871959D01*
X313896Y872101D01*
X314096D01*
Y871067D01*
X313896D01*
G37*
G36*
G01X314296Y870927D02*
X314696Y870784D01*
Y870034D01*
X314296Y869891D01*
X314096D01*
Y870927D01*
X314296D01*
G37*
G36*
G01X315216Y877852D02*
X315034Y878235D01*
X315564Y878766D01*
X315948Y878583D01*
X316089Y878442D01*
X315357Y877710D01*
X315216Y877852D01*
G37*
G36*
G01X317061Y879132D02*
X317243Y878748D01*
X316713Y878218D01*
X316329Y878400D01*
X316188Y878541D01*
X316920Y879273D01*
X317061Y879132D01*
G37*
G36*
G01X316878Y879513D02*
X316695Y879897D01*
X317226Y880427D01*
X317609Y880245D01*
X317751Y880104D01*
X317019Y879372D01*
X316878Y879513D01*
G37*
G36*
G01X318723Y880793D02*
X318905Y880410D01*
X318375Y879879D01*
X317991Y880061D01*
X317850Y880203D01*
X318582Y880935D01*
X318723Y880793D01*
G37*
G36*
G01X320216Y883933D02*
X319816Y884076D01*
Y884826D01*
X320216Y884969D01*
X320416D01*
Y883933D01*
X320216D01*
G37*
G36*
G01X318539Y881175D02*
X318357Y881559D01*
X318887Y882089D01*
X319271Y881907D01*
X319412Y881765D01*
X318681Y881034D01*
X318539Y881175D01*
G37*
G36*
G01X313096Y873277D02*
X313496Y873134D01*
Y872384D01*
X313096Y872241D01*
X312896D01*
Y873277D01*
X313096D01*
G37*
G36*
G01Y875627D02*
X313496Y875484D01*
Y874734D01*
X313096Y874591D01*
X312896D01*
Y875627D01*
X313096D01*
G37*
G36*
G01X314367Y878701D02*
X314185Y879084D01*
X314715Y879615D01*
X315099Y879432D01*
X315240Y879291D01*
X314508Y878559D01*
X314367Y878701D01*
G37*
G36*
G01X314551Y878319D02*
X314733Y877935D01*
X314202Y877405D01*
X313819Y877587D01*
X313677Y877728D01*
X314409Y878460D01*
X314551Y878319D01*
G37*
G36*
G01X312696Y873417D02*
X312296Y873559D01*
Y874309D01*
X312696Y874451D01*
X312896D01*
Y873417D01*
X312696D01*
G37*
G36*
G01X313096Y870927D02*
X313496Y870784D01*
Y870034D01*
X313096Y869891D01*
X312896D01*
Y870927D01*
X313096D01*
G37*
G36*
G01X312696Y868717D02*
X312296Y868859D01*
Y869609D01*
X312696Y869751D01*
X312896D01*
Y868717D01*
X312696D01*
G37*
G36*
G01Y871067D02*
X312296Y871209D01*
Y871959D01*
X312696Y872101D01*
X312896D01*
Y871067D01*
X312696D01*
G37*
G36*
G01X316212Y879981D02*
X316394Y879597D01*
X315864Y879067D01*
X315480Y879249D01*
X315339Y879390D01*
X316071Y880122D01*
X316212Y879981D01*
G37*
G36*
G01X316029Y880362D02*
X315846Y880746D01*
X316377Y881276D01*
X316760Y881094D01*
X316902Y880953D01*
X316170Y880221D01*
X316029Y880362D01*
G37*
G36*
G01X317690Y882024D02*
X317508Y882408D01*
X318038Y882938D01*
X318422Y882756D01*
X318563Y882614D01*
X317832Y881883D01*
X317690Y882024D01*
G37*
G36*
G01X317874Y881642D02*
X318056Y881259D01*
X317526Y880728D01*
X317142Y880910D01*
X317001Y881052D01*
X317733Y881784D01*
X317874Y881642D01*
G37*
G36*
G01X319016Y883933D02*
X318616Y884076D01*
Y884826D01*
X319016Y884969D01*
X319216D01*
Y883933D01*
X319016D01*
G37*
G36*
G01X315096Y873417D02*
X314696Y873559D01*
Y874309D01*
X315096Y874451D01*
X315296D01*
Y873417D01*
X315096D01*
G37*
G36*
G01Y868717D02*
X314696Y868859D01*
Y869609D01*
X315096Y869751D01*
X315296D01*
Y868717D01*
X315096D01*
G37*
G36*
G01Y871067D02*
X314696Y871209D01*
Y871959D01*
X315096Y872101D01*
X315296D01*
Y871067D01*
X315096D01*
G37*
G36*
G01X315496Y873277D02*
X315896Y873134D01*
Y872384D01*
X315496Y872241D01*
X315296D01*
Y873277D01*
X315496D01*
G37*
G36*
G01X317910Y878283D02*
X318092Y877899D01*
X317562Y877369D01*
X317178Y877551D01*
X317037Y877692D01*
X317769Y878424D01*
X317910Y878283D01*
G37*
G36*
G01X317727Y878664D02*
X317544Y879048D01*
X318075Y879578D01*
X318458Y879396D01*
X318600Y879255D01*
X317868Y878523D01*
X317727Y878664D01*
G37*
G36*
G01X316065Y877003D02*
X315883Y877386D01*
X316413Y877917D01*
X316797Y877734D01*
X316938Y877593D01*
X316206Y876861D01*
X316065Y877003D01*
G37*
G36*
G01X315496Y870927D02*
X315896Y870784D01*
Y870034D01*
X315496Y869891D01*
X315296D01*
Y870927D01*
X315496D01*
G37*
G36*
G01X321234Y881606D02*
X321416Y881222D01*
X320886Y880692D01*
X320502Y880874D01*
X320360Y881015D01*
X321092Y881747D01*
X321234Y881606D01*
G37*
G36*
G01X319388Y880326D02*
X319206Y880710D01*
X319736Y881240D01*
X320120Y881058D01*
X320261Y880916D01*
X319530Y880185D01*
X319388Y880326D01*
G37*
G36*
G01X321416Y883933D02*
X321016Y884076D01*
Y884826D01*
X321416Y884969D01*
X321616D01*
Y883933D01*
X321416D01*
G37*
G36*
G01X319572Y879944D02*
X319754Y879561D01*
X319224Y879030D01*
X318840Y879212D01*
X318699Y879354D01*
X319431Y880086D01*
X319572Y879944D01*
G37*
G36*
G01X308695Y900072D02*
X308513Y900456D01*
X309044Y900986D01*
X309427Y900804D01*
X309569Y900663D01*
X308837Y899931D01*
X308695Y900072D01*
G37*
G36*
G01X310541Y901352D02*
X310723Y900968D01*
X310193Y900438D01*
X309809Y900620D01*
X309668Y900762D01*
X310399Y901493D01*
X310541Y901352D01*
G37*
G36*
G01X308216Y890267D02*
X307816Y890409D01*
Y891159D01*
X308216Y891301D01*
X308416D01*
Y890267D01*
X308216D01*
G37*
G36*
G01X308616Y890127D02*
X309016Y889984D01*
Y889234D01*
X308616Y889091D01*
X308416D01*
Y890127D01*
X308616D01*
G37*
G36*
G01Y892477D02*
X309016Y892334D01*
Y891584D01*
X308616Y891441D01*
X308416D01*
Y892477D01*
X308616D01*
G37*
G36*
G01X311209Y899247D02*
X311027Y899631D01*
X311557Y900161D01*
X311941Y899979D01*
X312082Y899837D01*
X311351Y899106D01*
X311209Y899247D01*
G37*
G36*
G01X309547Y897585D02*
X309365Y897969D01*
X309896Y898499D01*
X310279Y898317D01*
X310421Y898176D01*
X309689Y897444D01*
X309547Y897585D01*
G37*
G36*
G01X311393Y898865D02*
X311575Y898482D01*
X311045Y897951D01*
X310661Y898133D01*
X310520Y898275D01*
X311252Y899007D01*
X311393Y898865D01*
G37*
G36*
G01X309731Y897204D02*
X309913Y896820D01*
X309383Y896290D01*
X308999Y896472D01*
X308858Y896613D01*
X309590Y897345D01*
X309731Y897204D01*
G37*
G36*
G01X308216Y892617D02*
X307816Y892759D01*
Y893509D01*
X308216Y893651D01*
X308416D01*
Y892617D01*
X308216D01*
G37*
G36*
G01X308616Y894827D02*
X309016Y894684D01*
Y893934D01*
X308616Y893791D01*
X308416D01*
Y894827D01*
X308616D01*
G37*
G36*
G01X313055Y900527D02*
X313237Y900143D01*
X312706Y899613D01*
X312323Y899795D01*
X312181Y899936D01*
X312913Y900668D01*
X313055Y900527D01*
G37*
G36*
G01X307425Y886473D02*
X307607Y886090D01*
X307077Y885559D01*
X306693Y885741D01*
X306552Y885883D01*
X307284Y886615D01*
X307425Y886473D01*
G37*
G36*
G01X305580Y885193D02*
X305397Y885577D01*
X305928Y886107D01*
X306311Y885925D01*
X306453Y885784D01*
X305721Y885052D01*
X305580Y885193D01*
G37*
G36*
G01X311016Y890127D02*
X311416Y889984D01*
Y889234D01*
X311016Y889091D01*
X310816D01*
Y890127D01*
X311016D01*
G37*
G36*
G01X311245Y895887D02*
X311063Y896271D01*
X311594Y896801D01*
X311977Y896619D01*
X312119Y896478D01*
X311387Y895746D01*
X311245Y895887D01*
G37*
G36*
G01X310616Y892617D02*
X310216Y892759D01*
Y893509D01*
X310616Y893651D01*
X310816D01*
Y892617D01*
X310616D01*
G37*
G36*
G01X314569Y899211D02*
X314387Y899594D01*
X314917Y900125D01*
X315301Y899943D01*
X315442Y899801D01*
X314710Y899069D01*
X314569Y899211D01*
G37*
G36*
G01X312907Y897549D02*
X312725Y897933D01*
X313255Y898463D01*
X313639Y898281D01*
X313780Y898139D01*
X313049Y897408D01*
X312907Y897549D01*
G37*
G36*
G01X314753Y898829D02*
X314935Y898445D01*
X314404Y897915D01*
X314021Y898097D01*
X313879Y898238D01*
X314611Y898970D01*
X314753Y898829D01*
G37*
G36*
G01X313091Y897167D02*
X313273Y896784D01*
X312743Y896253D01*
X312359Y896435D01*
X312218Y896577D01*
X312950Y897309D01*
X313091Y897167D01*
G37*
G36*
G01X310616Y890267D02*
X310216Y890409D01*
Y891159D01*
X310616Y891301D01*
X310816D01*
Y890267D01*
X310616D01*
G37*
G36*
G01Y887917D02*
X310216Y888059D01*
Y888809D01*
X310616Y888951D01*
X310816D01*
Y887917D01*
X310616D01*
G37*
G36*
G01X311016Y892477D02*
X311416Y892334D01*
Y891584D01*
X311016Y891441D01*
X310816D01*
Y892477D01*
X311016D01*
G37*
G36*
G01X308939Y885157D02*
X308757Y885541D01*
X309287Y886071D01*
X309671Y885889D01*
X309812Y885747D01*
X309081Y885016D01*
X308939Y885157D01*
G37*
G36*
G01X316414Y900491D02*
X316597Y900107D01*
X316066Y899577D01*
X315683Y899759D01*
X315541Y899900D01*
X316273Y900632D01*
X316414Y900491D01*
G37*
G36*
G01X308274Y885624D02*
X308456Y885241D01*
X307926Y884710D01*
X307542Y884892D01*
X307401Y885034D01*
X308133Y885766D01*
X308274Y885624D01*
G37*
G36*
G01X309416Y887917D02*
X309016Y888059D01*
Y888809D01*
X309416Y888951D01*
X309616D01*
Y887917D01*
X309416D01*
G37*
G36*
G01Y890267D02*
X309016Y890409D01*
Y891159D01*
X309416Y891301D01*
X309616D01*
Y890267D01*
X309416D01*
G37*
G36*
G01X309816Y890127D02*
X310216Y889984D01*
Y889234D01*
X309816Y889091D01*
X309616D01*
Y890127D01*
X309816D01*
G37*
G36*
G01Y892477D02*
X310216Y892334D01*
Y891584D01*
X309816Y891441D01*
X309616D01*
Y892477D01*
X309816D01*
G37*
G36*
G01X312058Y898398D02*
X311876Y898782D01*
X312406Y899312D01*
X312790Y899130D01*
X312931Y898988D01*
X312200Y898257D01*
X312058Y898398D01*
G37*
G36*
G01X310396Y896736D02*
X310214Y897120D01*
X310745Y897650D01*
X311128Y897468D01*
X311270Y897327D01*
X310538Y896595D01*
X310396Y896736D01*
G37*
G36*
G01X312242Y898016D02*
X312424Y897633D01*
X311894Y897102D01*
X311510Y897284D01*
X311369Y897426D01*
X312101Y898158D01*
X312242Y898016D01*
G37*
G36*
G01X309416Y892617D02*
X309016Y892759D01*
Y893509D01*
X309416Y893651D01*
X309616D01*
Y892617D01*
X309416D01*
G37*
G36*
G01X309816Y894827D02*
X310216Y894684D01*
Y893934D01*
X309816Y893791D01*
X309616D01*
Y894827D01*
X309816D01*
G37*
G36*
G01X313904Y899678D02*
X314086Y899294D01*
X313555Y898764D01*
X313172Y898946D01*
X313030Y899087D01*
X313762Y899819D01*
X313904Y899678D01*
G37*
G36*
G01X313720Y900060D02*
X313538Y900443D01*
X314068Y900974D01*
X314452Y900792D01*
X314593Y900650D01*
X313861Y899918D01*
X313720Y900060D01*
G37*
G36*
G01X308090Y886006D02*
X307908Y886390D01*
X308438Y886920D01*
X308822Y886738D01*
X308963Y886596D01*
X308232Y885865D01*
X308090Y886006D01*
G37*
G36*
G01X315565Y901340D02*
X315748Y900956D01*
X315217Y900426D01*
X314834Y900608D01*
X314692Y900749D01*
X315424Y901481D01*
X315565Y901340D01*
G37*
G36*
G01X311634Y885588D02*
X311816Y885204D01*
X311286Y884674D01*
X310902Y884856D01*
X310760Y884997D01*
X311492Y885729D01*
X311634Y885588D01*
G37*
G36*
G01X312216Y890127D02*
X312616Y889984D01*
Y889234D01*
X312216Y889091D01*
X312016D01*
Y890127D01*
X312216D01*
G37*
G36*
G01Y892477D02*
X312616Y892334D01*
Y891584D01*
X312216Y891441D01*
X312016D01*
Y892477D01*
X312216D01*
G37*
G36*
G01X311816Y887917D02*
X311416Y888059D01*
Y888809D01*
X311816Y888951D01*
X312016D01*
Y887917D01*
X311816D01*
G37*
G36*
G01Y890267D02*
X311416Y890409D01*
Y891159D01*
X311816Y891301D01*
X312016D01*
Y890267D01*
X311816D01*
G37*
G36*
G01Y892617D02*
X311416Y892759D01*
Y893509D01*
X311816Y893651D01*
X312016D01*
Y892617D01*
X311816D01*
G37*
G36*
G01X315602Y897980D02*
X315784Y897596D01*
X315253Y897066D01*
X314870Y897248D01*
X314728Y897389D01*
X315460Y898121D01*
X315602Y897980D01*
G37*
G36*
G01X313940Y896318D02*
X314122Y895935D01*
X313592Y895404D01*
X313208Y895586D01*
X313067Y895728D01*
X313799Y896460D01*
X313940Y896318D01*
G37*
G36*
G01X313756Y896700D02*
X313574Y897084D01*
X314104Y897614D01*
X314488Y897432D01*
X314629Y897290D01*
X313898Y896559D01*
X313756Y896700D01*
G37*
G36*
G01X315418Y898362D02*
X315236Y898745D01*
X315766Y899276D01*
X316150Y899094D01*
X316291Y898952D01*
X315559Y898220D01*
X315418Y898362D01*
G37*
G36*
G01X317263Y899642D02*
X317446Y899258D01*
X316915Y898728D01*
X316532Y898910D01*
X316390Y899051D01*
X317122Y899783D01*
X317263Y899642D01*
G37*
G36*
G01X317080Y900023D02*
X316898Y900407D01*
X317428Y900937D01*
X317811Y900755D01*
X317953Y900614D01*
X317221Y899882D01*
X317080Y900023D01*
G37*
G36*
G01X318925Y901303D02*
X319107Y900920D01*
X318577Y900389D01*
X318193Y900571D01*
X318052Y900713D01*
X318784Y901445D01*
X318925Y901303D01*
G37*
G36*
G01X317816Y888633D02*
X317416Y888776D01*
Y889526D01*
X317816Y889669D01*
X318016D01*
Y888633D01*
X317816D01*
G37*
G36*
G01X318216Y890843D02*
X318616Y890701D01*
Y889951D01*
X318216Y889809D01*
X318016D01*
Y890843D01*
X318216D01*
G37*
G36*
G01X317816Y886283D02*
X317416Y886426D01*
Y887176D01*
X317816Y887319D01*
X318016D01*
Y886283D01*
X317816D01*
G37*
G36*
G01X318216Y888493D02*
X318616Y888351D01*
Y887601D01*
X318216Y887459D01*
X318016D01*
Y888493D01*
X318216D01*
G37*
G36*
G01Y886143D02*
X318616Y886001D01*
Y885251D01*
X318216Y885109D01*
X318016D01*
Y886143D01*
X318216D01*
G37*
G36*
G01X320426Y894880D02*
X320244Y895264D01*
X320774Y895794D01*
X321158Y895612D01*
X321299Y895470D01*
X320568Y894739D01*
X320426Y894880D01*
G37*
G36*
G01X318764Y893218D02*
X318582Y893602D01*
X319113Y894132D01*
X319496Y893950D01*
X319638Y893809D01*
X318906Y893077D01*
X318764Y893218D01*
G37*
G36*
G01X320610Y894498D02*
X320792Y894114D01*
X320262Y893584D01*
X319878Y893766D01*
X319737Y893908D01*
X320469Y894640D01*
X320610Y894498D01*
G37*
G36*
G01X322272Y896160D02*
X322454Y895776D01*
X321923Y895246D01*
X321540Y895428D01*
X321398Y895569D01*
X322130Y896301D01*
X322272Y896160D01*
G37*
G36*
G01X320216Y886283D02*
X319816Y886426D01*
Y887176D01*
X320216Y887319D01*
X320416D01*
Y886283D01*
X320216D01*
G37*
G36*
G01X320616Y888493D02*
X321016Y888351D01*
Y887601D01*
X320616Y887459D01*
X320416D01*
Y888493D01*
X320616D01*
G37*
G36*
G01X320216Y888633D02*
X319816Y888776D01*
Y889526D01*
X320216Y889669D01*
X320416D01*
Y888633D01*
X320216D01*
G37*
G36*
G01X322308Y892800D02*
X322491Y892416D01*
X321960Y891886D01*
X321577Y892068D01*
X321435Y892209D01*
X322167Y892941D01*
X322308Y892800D01*
G37*
G36*
G01X320616Y886143D02*
X321016Y886001D01*
Y885251D01*
X320616Y885109D01*
X320416D01*
Y886143D01*
X320616D01*
G37*
G36*
G01X319016Y888633D02*
X318616Y888776D01*
Y889526D01*
X319016Y889669D01*
X319216D01*
Y888633D01*
X319016D01*
G37*
G36*
G01X319416Y890843D02*
X319816Y890701D01*
Y889951D01*
X319416Y889809D01*
X319216D01*
Y890843D01*
X319416D01*
G37*
G36*
G01X319614Y892369D02*
X319432Y892752D01*
X319962Y893283D01*
X320346Y893101D01*
X320487Y892959D01*
X319755Y892227D01*
X319614Y892369D01*
G37*
G36*
G01X321459Y893649D02*
X321642Y893265D01*
X321111Y892735D01*
X320728Y892917D01*
X320586Y893058D01*
X321318Y893790D01*
X321459Y893649D01*
G37*
G36*
G01X321276Y894030D02*
X321094Y894414D01*
X321624Y894944D01*
X322007Y894762D01*
X322149Y894621D01*
X321417Y893889D01*
X321276Y894030D01*
G37*
G36*
G01X319016Y886283D02*
X318616Y886426D01*
Y887176D01*
X319016Y887319D01*
X319216D01*
Y886283D01*
X319016D01*
G37*
G36*
G01X319416Y888493D02*
X319816Y888351D01*
Y887601D01*
X319416Y887459D01*
X319216D01*
Y888493D01*
X319416D01*
G37*
G36*
G01Y886143D02*
X319816Y886001D01*
Y885251D01*
X319416Y885109D01*
X319216D01*
Y886143D01*
X319416D01*
G37*
G36*
G01X321416Y888633D02*
X321016Y888776D01*
Y889526D01*
X321416Y889669D01*
X321616D01*
Y888633D01*
X321416D01*
G37*
G36*
G01Y886283D02*
X321016Y886426D01*
Y887176D01*
X321416Y887319D01*
X321616D01*
Y886283D01*
X321416D01*
G37*
G36*
G01X321816Y888493D02*
X322216Y888351D01*
Y887601D01*
X321816Y887459D01*
X321616D01*
Y888493D01*
X321816D01*
G37*
G36*
G01Y886143D02*
X322216Y886001D01*
Y885251D01*
X321816Y885109D01*
X321616D01*
Y886143D01*
X321816D01*
G37*
G36*
G01X308473Y916831D02*
X308291Y917215D01*
X308822Y917745D01*
X309205Y917563D01*
X309347Y917422D01*
X308615Y916690D01*
X308473Y916831D01*
G37*
G36*
G01X308657Y916450D02*
X308839Y916066D01*
X308309Y915536D01*
X307925Y915718D01*
X307784Y915859D01*
X308516Y916591D01*
X308657Y916450D01*
G37*
G36*
G01X310355Y914752D02*
X310537Y914368D01*
X310007Y913838D01*
X309623Y914020D01*
X309482Y914161D01*
X310214Y914893D01*
X310355Y914752D01*
G37*
G36*
G01X308694Y913090D02*
X308876Y912706D01*
X308345Y912176D01*
X307962Y912358D01*
X307820Y912499D01*
X308552Y913231D01*
X308694Y913090D01*
G37*
G36*
G01X310171Y915133D02*
X309989Y915517D01*
X310520Y916047D01*
X310903Y915865D01*
X311045Y915724D01*
X310313Y914992D01*
X310171Y915133D01*
G37*
G36*
G01X308510Y913472D02*
X308328Y913855D01*
X308858Y914386D01*
X309242Y914203D01*
X309383Y914062D01*
X308651Y913330D01*
X308510Y913472D01*
G37*
G36*
G01X312017Y916413D02*
X312199Y916030D01*
X311669Y915499D01*
X311285Y915681D01*
X311144Y915823D01*
X311876Y916555D01*
X312017Y916413D01*
G37*
G36*
G01X311833Y916795D02*
X311651Y917179D01*
X312181Y917709D01*
X312565Y917527D01*
X312706Y917385D01*
X311975Y916654D01*
X311833Y916795D01*
G37*
G36*
G01X309471Y905943D02*
X309289Y906327D01*
X309819Y906857D01*
X310203Y906675D01*
X310345Y906534D01*
X309613Y905802D01*
X309471Y905943D01*
G37*
G36*
G01X307810Y904281D02*
X307627Y904665D01*
X308158Y905195D01*
X308541Y905013D01*
X308683Y904872D01*
X307951Y904140D01*
X307810Y904281D01*
G37*
G36*
G01X311317Y907223D02*
X311499Y906839D01*
X310969Y906309D01*
X310585Y906491D01*
X310444Y906633D01*
X311175Y907364D01*
X311317Y907223D01*
G37*
G36*
G01X309655Y905561D02*
X309837Y905178D01*
X309307Y904647D01*
X308923Y904829D01*
X308782Y904971D01*
X309514Y905703D01*
X309655Y905561D01*
G37*
G36*
G01X307993Y903900D02*
X308175Y903516D01*
X307645Y902986D01*
X307262Y903168D01*
X307120Y903309D01*
X307852Y904041D01*
X307993Y903900D01*
G37*
G36*
G01X311133Y907605D02*
X310951Y907988D01*
X311481Y908519D01*
X311865Y908337D01*
X312006Y908195D01*
X311274Y907463D01*
X311133Y907605D01*
G37*
G36*
G01X314456Y910928D02*
X314274Y911312D01*
X314805Y911842D01*
X315188Y911660D01*
X315330Y911519D01*
X314598Y910787D01*
X314456Y910928D01*
G37*
G36*
G01X312795Y909266D02*
X312613Y909650D01*
X313143Y910180D01*
X313527Y909998D01*
X313668Y909857D01*
X312936Y909125D01*
X312795Y909266D01*
G37*
G36*
G01X314640Y910546D02*
X314822Y910163D01*
X314292Y909632D01*
X313908Y909815D01*
X313767Y909956D01*
X314499Y910688D01*
X314640Y910546D01*
G37*
G36*
G01X312978Y908885D02*
X313161Y908501D01*
X312630Y907971D01*
X312247Y908153D01*
X312105Y908294D01*
X312837Y909026D01*
X312978Y908885D01*
G37*
G36*
G01X316302Y912208D02*
X316484Y911824D01*
X315954Y911294D01*
X315570Y911476D01*
X315429Y911618D01*
X316160Y912349D01*
X316302Y912208D01*
G37*
G36*
G01X316118Y912590D02*
X315936Y912974D01*
X316466Y913504D01*
X316850Y913322D01*
X316991Y913180D01*
X316259Y912448D01*
X316118Y912590D01*
G37*
G36*
G01X317780Y914252D02*
X317598Y914635D01*
X318128Y915166D01*
X318512Y914983D01*
X318653Y914842D01*
X317921Y914110D01*
X317780Y914252D01*
G37*
G36*
G01X317964Y913870D02*
X318146Y913486D01*
X317615Y912956D01*
X317232Y913138D01*
X317090Y913279D01*
X317822Y914011D01*
X317964Y913870D01*
G37*
G36*
G01X319625Y915531D02*
X319807Y915148D01*
X319277Y914618D01*
X318893Y914800D01*
X318752Y914941D01*
X319484Y915673D01*
X319625Y915531D01*
G37*
G36*
G01X319441Y915913D02*
X319259Y916297D01*
X319790Y916827D01*
X320173Y916645D01*
X320315Y916504D01*
X319583Y915772D01*
X319441Y915913D01*
G37*
G36*
G01X321287Y917193D02*
X321469Y916810D01*
X320939Y916279D01*
X320555Y916461D01*
X320414Y916603D01*
X321146Y917335D01*
X321287Y917193D01*
G37*
G36*
G01X309692Y902201D02*
X309874Y901817D01*
X309344Y901287D01*
X308960Y901469D01*
X308819Y901611D01*
X309550Y902342D01*
X309692Y902201D01*
G37*
G36*
G01X311354Y903863D02*
X311536Y903479D01*
X311005Y902949D01*
X310622Y903131D01*
X310480Y903272D01*
X311212Y904004D01*
X311354Y903863D01*
G37*
G36*
G01X311170Y904245D02*
X310988Y904628D01*
X311518Y905159D01*
X311902Y904976D01*
X312043Y904835D01*
X311311Y904103D01*
X311170Y904245D01*
G37*
G36*
G01X313015Y905524D02*
X313197Y905141D01*
X312667Y904611D01*
X312283Y904793D01*
X312142Y904934D01*
X312874Y905666D01*
X313015Y905524D01*
G37*
G36*
G01X314677Y907186D02*
X314859Y906803D01*
X314329Y906272D01*
X313945Y906454D01*
X313804Y906596D01*
X314536Y907328D01*
X314677Y907186D01*
G37*
G36*
G01X312831Y905906D02*
X312649Y906290D01*
X313180Y906820D01*
X313563Y906638D01*
X313705Y906497D01*
X312973Y905765D01*
X312831Y905906D01*
G37*
G36*
G01X314493Y907568D02*
X314311Y907952D01*
X314841Y908482D01*
X315225Y908300D01*
X315366Y908158D01*
X314635Y907427D01*
X314493Y907568D01*
G37*
G36*
G01X309508Y902583D02*
X309326Y902966D01*
X309856Y903497D01*
X310240Y903315D01*
X310381Y903173D01*
X309649Y902441D01*
X309508Y902583D01*
G37*
G36*
G01X316339Y908848D02*
X316521Y908464D01*
X315990Y907934D01*
X315607Y908116D01*
X315465Y908257D01*
X316197Y908989D01*
X316339Y908848D01*
G37*
G36*
G01X318000Y910510D02*
X318182Y910126D01*
X317652Y909596D01*
X317269Y909778D01*
X317127Y909919D01*
X317859Y910651D01*
X318000Y910510D01*
G37*
G36*
G01X316155Y909230D02*
X315973Y909613D01*
X316503Y910144D01*
X316887Y909962D01*
X317028Y909820D01*
X316296Y909088D01*
X316155Y909230D01*
G37*
G36*
G01X317817Y910891D02*
X317634Y911275D01*
X318165Y911805D01*
X318548Y911623D01*
X318690Y911482D01*
X317958Y910750D01*
X317817Y910891D01*
G37*
G36*
G01X319662Y912171D02*
X319844Y911788D01*
X319314Y911257D01*
X318930Y911439D01*
X318789Y911581D01*
X319521Y912313D01*
X319662Y912171D01*
G37*
G36*
G01X321324Y913833D02*
X321506Y913449D01*
X320976Y912919D01*
X320592Y913101D01*
X320451Y913243D01*
X321182Y913974D01*
X321324Y913833D01*
G37*
G36*
G01X319478Y912553D02*
X319296Y912937D01*
X319827Y913467D01*
X320210Y913285D01*
X320352Y913144D01*
X319620Y912412D01*
X319478Y912553D01*
G37*
G36*
G01X321140Y914215D02*
X320958Y914598D01*
X321488Y915129D01*
X321872Y914947D01*
X322013Y914805D01*
X321281Y914073D01*
X321140Y914215D01*
G37*
G36*
G01X308659Y903432D02*
X308477Y903815D01*
X309007Y904346D01*
X309391Y904164D01*
X309532Y904022D01*
X308800Y903290D01*
X308659Y903432D01*
G37*
G36*
G01X313828Y908035D02*
X314010Y907652D01*
X313480Y907121D01*
X313096Y907303D01*
X312955Y907445D01*
X313687Y908177D01*
X313828Y908035D01*
G37*
G36*
G01X315490Y909697D02*
X315672Y909313D01*
X315141Y908783D01*
X314758Y908965D01*
X314616Y909106D01*
X315348Y909838D01*
X315490Y909697D01*
G37*
G36*
G01X313644Y908417D02*
X313462Y908801D01*
X313992Y909331D01*
X314376Y909149D01*
X314517Y909007D01*
X313786Y908276D01*
X313644Y908417D01*
G37*
G36*
G01X308843Y903050D02*
X309025Y902666D01*
X308495Y902136D01*
X308111Y902318D01*
X307970Y902460D01*
X308701Y903191D01*
X308843Y903050D01*
G37*
G36*
G01X312166Y906373D02*
X312348Y905990D01*
X311818Y905460D01*
X311434Y905642D01*
X311293Y905783D01*
X312025Y906515D01*
X312166Y906373D01*
G37*
G36*
G01X310505Y904712D02*
X310687Y904328D01*
X310156Y903798D01*
X309773Y903980D01*
X309631Y904121D01*
X310363Y904853D01*
X310505Y904712D01*
G37*
G36*
G01X311982Y906755D02*
X311800Y907139D01*
X312331Y907669D01*
X312714Y907487D01*
X312856Y907346D01*
X312124Y906614D01*
X311982Y906755D01*
G37*
G36*
G01X310321Y905094D02*
X310139Y905477D01*
X310669Y906008D01*
X311053Y905825D01*
X311194Y905684D01*
X310462Y904952D01*
X310321Y905094D01*
G37*
G36*
G01X315306Y910079D02*
X315124Y910462D01*
X315654Y910993D01*
X316038Y910811D01*
X316179Y910669D01*
X315447Y909937D01*
X315306Y910079D01*
G37*
G36*
G01X317151Y911359D02*
X317333Y910975D01*
X316803Y910445D01*
X316420Y910627D01*
X316278Y910768D01*
X317010Y911500D01*
X317151Y911359D01*
G37*
G36*
G01X318813Y913020D02*
X318995Y912637D01*
X318465Y912106D01*
X318081Y912288D01*
X317940Y912430D01*
X318672Y913162D01*
X318813Y913020D01*
G37*
G36*
G01X316968Y911740D02*
X316785Y912124D01*
X317316Y912654D01*
X317699Y912472D01*
X317841Y912331D01*
X317109Y911599D01*
X316968Y911740D01*
G37*
G36*
G01X320475Y914682D02*
X320657Y914298D01*
X320127Y913768D01*
X319743Y913950D01*
X319602Y914092D01*
X320333Y914823D01*
X320475Y914682D01*
G37*
G36*
G01X320291Y915064D02*
X320109Y915447D01*
X320639Y915978D01*
X321023Y915796D01*
X321164Y915654D01*
X320432Y914922D01*
X320291Y915064D01*
G37*
G36*
G01X322137Y916344D02*
X322319Y915960D01*
X321788Y915430D01*
X321405Y915612D01*
X321263Y915753D01*
X321995Y916485D01*
X322137Y916344D01*
G37*
G36*
G01X318629Y913402D02*
X318447Y913786D01*
X318978Y914316D01*
X319361Y914134D01*
X319503Y913993D01*
X318771Y913261D01*
X318629Y913402D01*
G37*
G36*
G01X312019Y903396D02*
X311837Y903779D01*
X312367Y904310D01*
X312751Y904127D01*
X312892Y903986D01*
X312160Y903254D01*
X312019Y903396D01*
G37*
G36*
G01X313864Y904675D02*
X314046Y904292D01*
X313516Y903762D01*
X313132Y903944D01*
X312991Y904085D01*
X313723Y904817D01*
X313864Y904675D01*
G37*
G36*
G01X315526Y906337D02*
X315708Y905954D01*
X315178Y905423D01*
X314794Y905605D01*
X314653Y905747D01*
X315385Y906479D01*
X315526Y906337D01*
G37*
G36*
G01X313680Y905057D02*
X313498Y905441D01*
X314029Y905971D01*
X314412Y905789D01*
X314554Y905648D01*
X313822Y904916D01*
X313680Y905057D01*
G37*
G36*
G01X312203Y903014D02*
X312385Y902630D01*
X311854Y902100D01*
X311471Y902282D01*
X311329Y902423D01*
X312061Y903155D01*
X312203Y903014D01*
G37*
G36*
G01X310357Y901734D02*
X310175Y902117D01*
X310705Y902648D01*
X311089Y902466D01*
X311230Y902324D01*
X310498Y901592D01*
X310357Y901734D01*
G37*
G36*
G01X317004Y908381D02*
X316822Y908764D01*
X317352Y909295D01*
X317736Y909113D01*
X317877Y908971D01*
X317145Y908239D01*
X317004Y908381D01*
G37*
G36*
G01X315342Y906719D02*
X315160Y907103D01*
X315690Y907633D01*
X316074Y907451D01*
X316215Y907309D01*
X315484Y906578D01*
X315342Y906719D01*
G37*
G36*
G01X317188Y907999D02*
X317370Y907615D01*
X316839Y907085D01*
X316456Y907267D01*
X316314Y907408D01*
X317046Y908140D01*
X317188Y907999D01*
G37*
G36*
G01X318849Y909661D02*
X319031Y909277D01*
X318501Y908747D01*
X318118Y908929D01*
X317976Y909070D01*
X318708Y909802D01*
X318849Y909661D01*
G37*
G36*
G01X320511Y911322D02*
X320693Y910939D01*
X320163Y910408D01*
X319779Y910590D01*
X319638Y910732D01*
X320370Y911464D01*
X320511Y911322D01*
G37*
G36*
G01X318666Y910042D02*
X318483Y910426D01*
X319014Y910956D01*
X319397Y910774D01*
X319539Y910633D01*
X318807Y909901D01*
X318666Y910042D01*
G37*
G36*
G01X320327Y911704D02*
X320145Y912088D01*
X320676Y912618D01*
X321059Y912436D01*
X321201Y912295D01*
X320469Y911563D01*
X320327Y911704D01*
G37*
G36*
G01X322173Y912984D02*
X322355Y912600D01*
X321825Y912070D01*
X321441Y912252D01*
X321300Y912394D01*
X322031Y913125D01*
X322173Y912984D01*
G37*
G36*
G01X312871Y900909D02*
X312689Y901292D01*
X313219Y901823D01*
X313603Y901641D01*
X313744Y901499D01*
X313012Y900767D01*
X312871Y900909D01*
G37*
G36*
G01X314716Y902189D02*
X314899Y901805D01*
X314368Y901275D01*
X313985Y901457D01*
X313843Y901598D01*
X314575Y902330D01*
X314716Y902189D01*
G37*
G36*
G01X314533Y902570D02*
X314351Y902954D01*
X314881Y903484D01*
X315264Y903302D01*
X315406Y903161D01*
X314674Y902429D01*
X314533Y902570D01*
G37*
G36*
G01X316194Y904232D02*
X316012Y904616D01*
X316543Y905146D01*
X316926Y904964D01*
X317068Y904823D01*
X316336Y904091D01*
X316194Y904232D01*
G37*
G36*
G01X317856Y905894D02*
X317674Y906277D01*
X318204Y906808D01*
X318588Y906626D01*
X318729Y906484D01*
X317997Y905752D01*
X317856Y905894D01*
G37*
G36*
G01X318040Y905512D02*
X318222Y905128D01*
X317692Y904598D01*
X317308Y904780D01*
X317167Y904922D01*
X317898Y905653D01*
X318040Y905512D01*
G37*
G36*
G01X316378Y903850D02*
X316560Y903467D01*
X316030Y902936D01*
X315646Y903118D01*
X315505Y903260D01*
X316237Y903992D01*
X316378Y903850D01*
G37*
G36*
G01X319702Y907174D02*
X319884Y906790D01*
X319353Y906260D01*
X318970Y906442D01*
X318828Y906583D01*
X319560Y907315D01*
X319702Y907174D01*
G37*
G36*
G01X319518Y907556D02*
X319336Y907939D01*
X319866Y908469D01*
X320250Y908287D01*
X320391Y908146D01*
X319659Y907414D01*
X319518Y907556D01*
G37*
G36*
G01X321363Y908835D02*
X321545Y908452D01*
X321015Y907921D01*
X320631Y908104D01*
X320490Y908245D01*
X321222Y908977D01*
X321363Y908835D01*
G37*
G36*
G01X321179Y909217D02*
X320997Y909601D01*
X321528Y910131D01*
X321911Y909949D01*
X322053Y909808D01*
X321321Y909076D01*
X321179Y909217D01*
G37*
G36*
G01X316231Y900872D02*
X316049Y901256D01*
X316579Y901786D01*
X316962Y901604D01*
X317104Y901463D01*
X316372Y900731D01*
X316231Y900872D01*
G37*
G36*
G01X318076Y902152D02*
X318258Y901769D01*
X317728Y901238D01*
X317344Y901420D01*
X317203Y901562D01*
X317935Y902294D01*
X318076Y902152D01*
G37*
G36*
G01X317892Y902534D02*
X317710Y902918D01*
X318241Y903448D01*
X318624Y903266D01*
X318766Y903125D01*
X318034Y902393D01*
X317892Y902534D01*
G37*
G36*
G01X319554Y904196D02*
X319372Y904579D01*
X319902Y905110D01*
X320286Y904928D01*
X320427Y904786D01*
X319695Y904054D01*
X319554Y904196D01*
G37*
G36*
G01X321400Y905476D02*
X321582Y905092D01*
X321051Y904562D01*
X320668Y904744D01*
X320526Y904885D01*
X321258Y905617D01*
X321400Y905476D01*
G37*
G36*
G01X319738Y903814D02*
X319920Y903430D01*
X319390Y902900D01*
X319006Y903082D01*
X318865Y903224D01*
X319596Y903955D01*
X319738Y903814D01*
G37*
G36*
G01X321216Y905858D02*
X321034Y906241D01*
X321564Y906771D01*
X321948Y906589D01*
X322089Y906448D01*
X321357Y905716D01*
X321216Y905858D01*
G37*
G36*
G01X317043Y903383D02*
X316861Y903767D01*
X317392Y904297D01*
X317775Y904115D01*
X317917Y903974D01*
X317185Y903242D01*
X317043Y903383D01*
G37*
G36*
G01X318889Y904663D02*
X319071Y904279D01*
X318541Y903749D01*
X318157Y903931D01*
X318016Y904073D01*
X318747Y904804D01*
X318889Y904663D01*
G37*
G36*
G01X317227Y903001D02*
X317409Y902618D01*
X316879Y902087D01*
X316495Y902269D01*
X316354Y902411D01*
X317086Y903143D01*
X317227Y903001D01*
G37*
G36*
G01X315382Y901721D02*
X315200Y902105D01*
X315730Y902635D01*
X316113Y902453D01*
X316255Y902312D01*
X315523Y901580D01*
X315382Y901721D01*
G37*
G36*
G01X318705Y905045D02*
X318523Y905428D01*
X319053Y905959D01*
X319437Y905777D01*
X319578Y905635D01*
X318846Y904903D01*
X318705Y905045D01*
G37*
G36*
G01X320367Y906707D02*
X320185Y907090D01*
X320715Y907620D01*
X321099Y907438D01*
X321240Y907297D01*
X320508Y906565D01*
X320367Y906707D01*
G37*
G36*
G01X320551Y906325D02*
X320733Y905941D01*
X320202Y905411D01*
X319819Y905593D01*
X319677Y905734D01*
X320409Y906466D01*
X320551Y906325D01*
G37*
G36*
G01X322212Y907986D02*
X322394Y907603D01*
X321864Y907072D01*
X321480Y907255D01*
X321339Y907396D01*
X322071Y908128D01*
X322212Y907986D01*
G37*
G36*
G01X320587Y902965D02*
X320769Y902581D01*
X320239Y902051D01*
X319855Y902233D01*
X319714Y902375D01*
X320445Y903106D01*
X320587Y902965D01*
G37*
G36*
G01X318741Y901685D02*
X318559Y902069D01*
X319090Y902599D01*
X319473Y902417D01*
X319615Y902276D01*
X318883Y901544D01*
X318741Y901685D01*
G37*
G36*
G01X320403Y903347D02*
X320221Y903730D01*
X320751Y904261D01*
X321135Y904079D01*
X321276Y903937D01*
X320544Y903205D01*
X320403Y903347D01*
G37*
G36*
G01X322249Y904627D02*
X322431Y904243D01*
X321900Y903713D01*
X321517Y903895D01*
X321375Y904036D01*
X322107Y904768D01*
X322249Y904627D01*
G37*
G36*
G01X311168Y917262D02*
X311350Y916879D01*
X310820Y916348D01*
X310436Y916530D01*
X310295Y916672D01*
X311027Y917404D01*
X311168Y917262D01*
G37*
G36*
G01X309322Y915982D02*
X309140Y916366D01*
X309671Y916896D01*
X310054Y916714D01*
X310196Y916573D01*
X309464Y915841D01*
X309322Y915982D01*
G37*
G36*
G01X309506Y915601D02*
X309688Y915217D01*
X309158Y914687D01*
X308774Y914869D01*
X308633Y915010D01*
X309365Y915742D01*
X309506Y915601D01*
G37*
G36*
G01X307845Y913939D02*
X308027Y913555D01*
X307496Y913025D01*
X307113Y913207D01*
X306971Y913348D01*
X307703Y914080D01*
X307845Y913939D01*
G37*
G36*
G01X307661Y914321D02*
X307479Y914704D01*
X308009Y915235D01*
X308393Y915052D01*
X308534Y914911D01*
X307802Y914179D01*
X307661Y914321D01*
G37*
G36*
G01X310319Y918111D02*
X310501Y917728D01*
X309971Y917197D01*
X309587Y917379D01*
X309446Y917521D01*
X310178Y918253D01*
X310319Y918111D01*
G37*
G36*
G01X311797Y920155D02*
X311615Y920538D01*
X312145Y921069D01*
X312529Y920887D01*
X312670Y920745D01*
X311938Y920013D01*
X311797Y920155D01*
G37*
G36*
G01X311981Y919773D02*
X312163Y919389D01*
X311632Y918859D01*
X311249Y919041D01*
X311107Y919182D01*
X311839Y919914D01*
X311981Y919773D01*
G37*
G36*
G01X313459Y921816D02*
X313277Y922200D01*
X313807Y922730D01*
X314190Y922548D01*
X314332Y922407D01*
X313600Y921675D01*
X313459Y921816D01*
G37*
G36*
G01X315120Y923478D02*
X314938Y923862D01*
X315469Y924392D01*
X315852Y924210D01*
X315994Y924069D01*
X315262Y923337D01*
X315120Y923478D01*
G37*
G36*
G01X313642Y921435D02*
X313825Y921051D01*
X313294Y920521D01*
X312911Y920703D01*
X312769Y920844D01*
X313501Y921576D01*
X313642Y921435D01*
G37*
G36*
G01X315304Y923096D02*
X315486Y922713D01*
X314956Y922182D01*
X314572Y922364D01*
X314431Y922506D01*
X315163Y923238D01*
X315304Y923096D01*
G37*
G36*
G01X310135Y918493D02*
X309953Y918877D01*
X310483Y919407D01*
X310867Y919225D01*
X311008Y919083D01*
X310277Y918352D01*
X310135Y918493D01*
G37*
G36*
G01X316966Y924758D02*
X317148Y924374D01*
X316618Y923844D01*
X316234Y924026D01*
X316093Y924168D01*
X316824Y924899D01*
X316966Y924758D01*
G37*
G36*
G01X316782Y925140D02*
X316600Y925523D01*
X317130Y926054D01*
X317514Y925872D01*
X317655Y925730D01*
X316923Y924998D01*
X316782Y925140D01*
G37*
G36*
G01X318628Y926420D02*
X318810Y926036D01*
X318279Y925506D01*
X317896Y925688D01*
X317754Y925829D01*
X318486Y926561D01*
X318628Y926420D01*
G37*
G36*
G01X321951Y929743D02*
X322133Y929360D01*
X321603Y928829D01*
X321219Y929011D01*
X321078Y929153D01*
X321810Y929885D01*
X321951Y929743D01*
G37*
G36*
G01X320289Y928081D02*
X320471Y927698D01*
X319941Y927167D01*
X319557Y927350D01*
X319416Y927491D01*
X320148Y928223D01*
X320289Y928081D01*
G37*
G36*
G01X318444Y926802D02*
X318262Y927185D01*
X318792Y927715D01*
X319176Y927533D01*
X319317Y927392D01*
X318585Y926660D01*
X318444Y926802D01*
G37*
G36*
G01X320105Y928463D02*
X319923Y928847D01*
X320454Y929377D01*
X320837Y929195D01*
X320979Y929054D01*
X320247Y928322D01*
X320105Y928463D01*
G37*
G36*
G01X321767Y930125D02*
X321585Y930509D01*
X322115Y931039D01*
X322499Y930857D01*
X322640Y930715D01*
X321909Y929984D01*
X321767Y930125D01*
G37*
G36*
G01X313679Y918075D02*
X313861Y917691D01*
X313330Y917161D01*
X312947Y917343D01*
X312805Y917484D01*
X313537Y918216D01*
X313679Y918075D01*
G37*
G36*
G01X315340Y919737D02*
X315523Y919353D01*
X314992Y918823D01*
X314609Y919005D01*
X314467Y919146D01*
X315199Y919878D01*
X315340Y919737D01*
G37*
G36*
G01X313495Y918457D02*
X313313Y918840D01*
X313843Y919371D01*
X314227Y919189D01*
X314368Y919047D01*
X313636Y918315D01*
X313495Y918457D01*
G37*
G36*
G01X315157Y920118D02*
X314975Y920502D01*
X315505Y921032D01*
X315888Y920850D01*
X316030Y920709D01*
X315298Y919977D01*
X315157Y920118D01*
G37*
G36*
G01X317002Y921398D02*
X317184Y921015D01*
X316654Y920484D01*
X316270Y920666D01*
X316129Y920808D01*
X316861Y921540D01*
X317002Y921398D01*
G37*
G36*
G01X318664Y923060D02*
X318846Y922676D01*
X318316Y922146D01*
X317932Y922328D01*
X317791Y922470D01*
X318522Y923201D01*
X318664Y923060D01*
G37*
G36*
G01X316818Y921780D02*
X316636Y922164D01*
X317167Y922694D01*
X317550Y922512D01*
X317692Y922371D01*
X316960Y921639D01*
X316818Y921780D01*
G37*
G36*
G01X320326Y924722D02*
X320508Y924338D01*
X319977Y923808D01*
X319594Y923990D01*
X319452Y924131D01*
X320184Y924863D01*
X320326Y924722D01*
G37*
G36*
G01X320142Y925104D02*
X319960Y925487D01*
X320490Y926017D01*
X320874Y925835D01*
X321015Y925694D01*
X320283Y924962D01*
X320142Y925104D01*
G37*
G36*
G01X321987Y926383D02*
X322169Y926000D01*
X321639Y925469D01*
X321255Y925652D01*
X321114Y925793D01*
X321846Y926525D01*
X321987Y926383D01*
G37*
G36*
G01X321803Y926765D02*
X321621Y927149D01*
X322152Y927679D01*
X322535Y927497D01*
X322677Y927356D01*
X321945Y926624D01*
X321803Y926765D01*
G37*
G36*
G01X318480Y923442D02*
X318298Y923825D01*
X318828Y924356D01*
X319212Y924174D01*
X319353Y924032D01*
X318621Y923300D01*
X318480Y923442D01*
G37*
G36*
G01X321103Y917575D02*
X320921Y917959D01*
X321451Y918489D01*
X321835Y918307D01*
X321976Y918165D01*
X321245Y917434D01*
X321103Y917575D01*
G37*
G36*
G01X309470Y918960D02*
X309652Y918577D01*
X309122Y918046D01*
X308738Y918228D01*
X308597Y918370D01*
X309329Y919102D01*
X309470Y918960D01*
G37*
G36*
G01X310948Y921004D02*
X310766Y921387D01*
X311296Y921918D01*
X311680Y921736D01*
X311821Y921594D01*
X311089Y920862D01*
X310948Y921004D01*
G37*
G36*
G01X309286Y919342D02*
X309104Y919726D01*
X309634Y920256D01*
X310018Y920074D01*
X310159Y919932D01*
X309428Y919201D01*
X309286Y919342D01*
G37*
G36*
G01X312793Y922284D02*
X312976Y921900D01*
X312445Y921370D01*
X312062Y921552D01*
X311920Y921693D01*
X312652Y922425D01*
X312793Y922284D01*
G37*
G36*
G01X311132Y920622D02*
X311314Y920238D01*
X310783Y919708D01*
X310400Y919890D01*
X310258Y920031D01*
X310990Y920763D01*
X311132Y920622D01*
G37*
G36*
G01X312610Y922665D02*
X312428Y923049D01*
X312958Y923579D01*
X313341Y923397D01*
X313483Y923256D01*
X312751Y922524D01*
X312610Y922665D01*
G37*
G36*
G01X314271Y924327D02*
X314089Y924711D01*
X314620Y925241D01*
X315003Y925059D01*
X315145Y924918D01*
X314413Y924186D01*
X314271Y924327D01*
G37*
G36*
G01X314455Y923945D02*
X314637Y923562D01*
X314107Y923031D01*
X313723Y923213D01*
X313582Y923355D01*
X314314Y924087D01*
X314455Y923945D01*
G37*
G36*
G01X316117Y925607D02*
X316299Y925223D01*
X315769Y924693D01*
X315385Y924875D01*
X315244Y925017D01*
X315975Y925748D01*
X316117Y925607D01*
G37*
G36*
G01X315933Y925989D02*
X315751Y926372D01*
X316281Y926903D01*
X316665Y926721D01*
X316806Y926579D01*
X316074Y925847D01*
X315933Y925989D01*
G37*
G36*
G01X317595Y927651D02*
X317413Y928034D01*
X317943Y928564D01*
X318327Y928382D01*
X318468Y928241D01*
X317736Y927509D01*
X317595Y927651D01*
G37*
G36*
G01X317779Y927269D02*
X317961Y926885D01*
X317430Y926355D01*
X317047Y926537D01*
X316905Y926678D01*
X317637Y927410D01*
X317779Y927269D01*
G37*
G36*
G01X319256Y929312D02*
X319074Y929696D01*
X319605Y930226D01*
X319988Y930044D01*
X320130Y929903D01*
X319398Y929171D01*
X319256Y929312D01*
G37*
G36*
G01X319440Y928930D02*
X319622Y928547D01*
X319092Y928016D01*
X318708Y928199D01*
X318567Y928340D01*
X319299Y929072D01*
X319440Y928930D01*
G37*
G36*
G01X321102Y930592D02*
X321284Y930209D01*
X320754Y929678D01*
X320370Y929860D01*
X320229Y930002D01*
X320961Y930734D01*
X321102Y930592D01*
G37*
G36*
G01X320918Y930974D02*
X320736Y931358D01*
X321266Y931888D01*
X321650Y931706D01*
X321791Y931564D01*
X321060Y930833D01*
X320918Y930974D01*
G37*
G36*
G01X312830Y918924D02*
X313012Y918540D01*
X312481Y918010D01*
X312098Y918192D01*
X311956Y918333D01*
X312688Y919065D01*
X312830Y918924D01*
G37*
G36*
G01X310984Y917644D02*
X310802Y918028D01*
X311332Y918558D01*
X311716Y918376D01*
X311857Y918234D01*
X311126Y917503D01*
X310984Y917644D01*
G37*
G36*
G01X314308Y920967D02*
X314126Y921351D01*
X314656Y921881D01*
X315039Y921699D01*
X315181Y921558D01*
X314449Y920826D01*
X314308Y920967D01*
G37*
G36*
G01X314491Y920586D02*
X314674Y920202D01*
X314143Y919672D01*
X313760Y919854D01*
X313618Y919995D01*
X314350Y920727D01*
X314491Y920586D01*
G37*
G36*
G01X312646Y919306D02*
X312464Y919689D01*
X312994Y920220D01*
X313378Y920038D01*
X313519Y919896D01*
X312787Y919164D01*
X312646Y919306D01*
G37*
G36*
G01X317815Y923909D02*
X317997Y923525D01*
X317467Y922995D01*
X317083Y923177D01*
X316942Y923319D01*
X317673Y924050D01*
X317815Y923909D01*
G37*
G36*
G01X317631Y924291D02*
X317449Y924674D01*
X317979Y925205D01*
X318363Y925023D01*
X318504Y924881D01*
X317772Y924149D01*
X317631Y924291D01*
G37*
G36*
G01X315969Y922629D02*
X315787Y923013D01*
X316318Y923543D01*
X316701Y923361D01*
X316843Y923220D01*
X316111Y922488D01*
X315969Y922629D01*
G37*
G36*
G01X316153Y922247D02*
X316335Y921864D01*
X315805Y921333D01*
X315421Y921515D01*
X315280Y921657D01*
X316012Y922389D01*
X316153Y922247D01*
G37*
G36*
G01X319477Y925571D02*
X319659Y925187D01*
X319128Y924657D01*
X318745Y924839D01*
X318603Y924980D01*
X319335Y925712D01*
X319477Y925571D01*
G37*
G36*
G01X319293Y925953D02*
X319111Y926336D01*
X319641Y926866D01*
X320025Y926684D01*
X320166Y926543D01*
X319434Y925811D01*
X319293Y925953D01*
G37*
G36*
G01X321138Y927232D02*
X321320Y926849D01*
X320790Y926318D01*
X320406Y926501D01*
X320265Y926642D01*
X320997Y927374D01*
X321138Y927232D01*
G37*
G36*
G01X320954Y927614D02*
X320772Y927998D01*
X321303Y928528D01*
X321686Y928346D01*
X321828Y928205D01*
X321096Y927473D01*
X320954Y927614D01*
G37*
G36*
G01X308650Y981779D02*
X308792Y982179D01*
X309542D01*
X309685Y981779D01*
Y981579D01*
X308650D01*
Y981779D01*
G37*
G36*
G01X308510Y981379D02*
X308368Y980979D01*
X307618D01*
X307475Y981379D01*
Y981579D01*
X308510D01*
Y981379D01*
G37*
G36*
G01X311000Y981779D02*
X311142Y982179D01*
X311892D01*
X312035Y981779D01*
Y981579D01*
X311000D01*
Y981779D01*
G37*
G36*
G01X315560Y981379D02*
X315418Y980979D01*
X314668D01*
X314525Y981379D01*
Y981579D01*
X315560D01*
Y981379D01*
G37*
G36*
G01X313350Y981779D02*
X313492Y982179D01*
X314242D01*
X314385Y981779D01*
Y981579D01*
X313350D01*
Y981779D01*
G37*
G36*
G01X310860Y981379D02*
X310718Y980979D01*
X309968D01*
X309825Y981379D01*
Y981579D01*
X310860D01*
Y981379D01*
G37*
G36*
G01X313210D02*
X313068Y980979D01*
X312318D01*
X312175Y981379D01*
Y981579D01*
X313210D01*
Y981379D01*
G37*
G36*
G01X317910D02*
X317768Y980979D01*
X317018D01*
X316875Y981379D01*
Y981579D01*
X317910D01*
Y981379D01*
G37*
G36*
G01X318050Y981779D02*
X318192Y982179D01*
X318942D01*
X319085Y981779D01*
Y981579D01*
X318050D01*
Y981779D01*
G37*
G36*
G01X315700D02*
X315842Y982179D01*
X316592D01*
X316735Y981779D01*
Y981579D01*
X315700D01*
Y981779D01*
G37*
G36*
G01X320260Y981379D02*
X320118Y980979D01*
X319368D01*
X319225Y981379D01*
Y981579D01*
X320260D01*
Y981379D01*
G37*
G36*
G01X306300Y980578D02*
X306442Y980978D01*
X307192D01*
X307335Y980578D01*
Y980378D01*
X306300D01*
Y980578D01*
G37*
G36*
G01X308650D02*
X308792Y980978D01*
X309542D01*
X309685Y980578D01*
Y980378D01*
X308650D01*
Y980578D01*
G37*
G36*
G01X308510Y980178D02*
X308368Y979778D01*
X307618D01*
X307475Y980178D01*
Y980378D01*
X308510D01*
Y980178D01*
G37*
G36*
G01X313350Y980578D02*
X313492Y980978D01*
X314242D01*
X314385Y980578D01*
Y980378D01*
X313350D01*
Y980578D01*
G37*
G36*
G01X315560Y980178D02*
X315418Y979778D01*
X314668D01*
X314525Y980178D01*
Y980378D01*
X315560D01*
Y980178D01*
G37*
G36*
G01X311000Y980578D02*
X311142Y980978D01*
X311892D01*
X312035Y980578D01*
Y980378D01*
X311000D01*
Y980578D01*
G37*
G36*
G01X313210Y980178D02*
X313068Y979778D01*
X312318D01*
X312175Y980178D01*
Y980378D01*
X313210D01*
Y980178D01*
G37*
G36*
G01X310860D02*
X310718Y979778D01*
X309968D01*
X309825Y980178D01*
Y980378D01*
X310860D01*
Y980178D01*
G37*
G36*
G01X315700Y980578D02*
X315842Y980978D01*
X316592D01*
X316735Y980578D01*
Y980378D01*
X315700D01*
Y980578D01*
G37*
G36*
G01X318050D02*
X318192Y980978D01*
X318942D01*
X319085Y980578D01*
Y980378D01*
X318050D01*
Y980578D01*
G37*
G36*
G01X317910Y980178D02*
X317768Y979778D01*
X317018D01*
X316875Y980178D01*
Y980378D01*
X317910D01*
Y980178D01*
G37*
G36*
G01X308650Y979378D02*
X308792Y979778D01*
X309542D01*
X309685Y979378D01*
Y979178D01*
X308650D01*
Y979378D01*
G37*
G36*
G01X308510Y978978D02*
X308368Y978578D01*
X307618D01*
X307475Y978978D01*
Y979178D01*
X308510D01*
Y978978D01*
G37*
G36*
G01X313350Y979378D02*
X313492Y979778D01*
X314242D01*
X314385Y979378D01*
Y979178D01*
X313350D01*
Y979378D01*
G37*
G36*
G01X315560Y978978D02*
X315418Y978578D01*
X314668D01*
X314525Y978978D01*
Y979178D01*
X315560D01*
Y978978D01*
G37*
G36*
G01X311000Y979378D02*
X311142Y979778D01*
X311892D01*
X312035Y979378D01*
Y979178D01*
X311000D01*
Y979378D01*
G37*
G36*
G01X310860Y978978D02*
X310718Y978578D01*
X309968D01*
X309825Y978978D01*
Y979178D01*
X310860D01*
Y978978D01*
G37*
G36*
G01X313210D02*
X313068Y978578D01*
X312318D01*
X312175Y978978D01*
Y979178D01*
X313210D01*
Y978978D01*
G37*
G36*
G01X318050Y979378D02*
X318192Y979778D01*
X318942D01*
X319085Y979378D01*
Y979178D01*
X318050D01*
Y979378D01*
G37*
G36*
G01X317910Y978978D02*
X317768Y978578D01*
X317018D01*
X316875Y978978D01*
Y979178D01*
X317910D01*
Y978978D01*
G37*
G36*
G01X315700Y979378D02*
X315842Y979778D01*
X316592D01*
X316735Y979378D01*
Y979178D01*
X315700D01*
Y979378D01*
G37*
G36*
G01X320260Y978978D02*
X320118Y978578D01*
X319368D01*
X319225Y978978D01*
Y979178D01*
X320260D01*
Y978978D01*
G37*
G36*
G01X308650Y978178D02*
X308792Y978578D01*
X309542D01*
X309685Y978178D01*
Y977978D01*
X308650D01*
Y978178D01*
G37*
G36*
G01X308510Y977778D02*
X308368Y977378D01*
X307618D01*
X307475Y977778D01*
Y977978D01*
X308510D01*
Y977778D01*
G37*
G36*
G01X313350Y978178D02*
X313492Y978578D01*
X314242D01*
X314385Y978178D01*
Y977978D01*
X313350D01*
Y978178D01*
G37*
G36*
G01X315560Y977778D02*
X315418Y977378D01*
X314668D01*
X314525Y977778D01*
Y977978D01*
X315560D01*
Y977778D01*
G37*
G36*
G01X311000Y978178D02*
X311142Y978578D01*
X311892D01*
X312035Y978178D01*
Y977978D01*
X311000D01*
Y978178D01*
G37*
G36*
G01X313210Y977778D02*
X313068Y977378D01*
X312318D01*
X312175Y977778D01*
Y977978D01*
X313210D01*
Y977778D01*
G37*
G36*
G01X310860D02*
X310718Y977378D01*
X309968D01*
X309825Y977778D01*
Y977978D01*
X310860D01*
Y977778D01*
G37*
G36*
G01X318050Y978178D02*
X318192Y978578D01*
X318942D01*
X319085Y978178D01*
Y977978D01*
X318050D01*
Y978178D01*
G37*
G36*
G01X317910Y977778D02*
X317768Y977378D01*
X317018D01*
X316875Y977778D01*
Y977978D01*
X317910D01*
Y977778D01*
G37*
G36*
G01X315700Y978178D02*
X315842Y978578D01*
X316592D01*
X316735Y978178D01*
Y977978D01*
X315700D01*
Y978178D01*
G37*
G36*
G01X320260Y977778D02*
X320118Y977378D01*
X319368D01*
X319225Y977778D01*
Y977978D01*
X320260D01*
Y977778D01*
G37*
G36*
G01X308650Y976978D02*
X308792Y977378D01*
X309542D01*
X309685Y976978D01*
Y976778D01*
X308650D01*
Y976978D01*
G37*
G36*
G01X308510Y976578D02*
X308368Y976178D01*
X307618D01*
X307475Y976578D01*
Y976778D01*
X308510D01*
Y976578D01*
G37*
G36*
G01X313350Y976978D02*
X313492Y977378D01*
X314242D01*
X314385Y976978D01*
Y976778D01*
X313350D01*
Y976978D01*
G37*
G36*
G01X315560Y976578D02*
X315418Y976178D01*
X314668D01*
X314525Y976578D01*
Y976778D01*
X315560D01*
Y976578D01*
G37*
G36*
G01X311000Y976978D02*
X311142Y977378D01*
X311892D01*
X312035Y976978D01*
Y976778D01*
X311000D01*
Y976978D01*
G37*
G36*
G01X313210Y976578D02*
X313068Y976178D01*
X312318D01*
X312175Y976578D01*
Y976778D01*
X313210D01*
Y976578D01*
G37*
G36*
G01X310860D02*
X310718Y976178D01*
X309968D01*
X309825Y976578D01*
Y976778D01*
X310860D01*
Y976578D01*
G37*
G36*
G01X318050Y976978D02*
X318192Y977378D01*
X318942D01*
X319085Y976978D01*
Y976778D01*
X318050D01*
Y976978D01*
G37*
G36*
G01X317910Y976578D02*
X317768Y976178D01*
X317018D01*
X316875Y976578D01*
Y976778D01*
X317910D01*
Y976578D01*
G37*
G36*
G01X315700Y976978D02*
X315842Y977378D01*
X316592D01*
X316735Y976978D01*
Y976778D01*
X315700D01*
Y976978D01*
G37*
G36*
G01X320260Y976578D02*
X320118Y976178D01*
X319368D01*
X319225Y976578D01*
Y976778D01*
X320260D01*
Y976578D01*
G37*
G36*
G01X308650Y975778D02*
X308792Y976178D01*
X309542D01*
X309685Y975778D01*
Y975578D01*
X308650D01*
Y975778D01*
G37*
G36*
G01X308510Y975378D02*
X308368Y974978D01*
X307618D01*
X307475Y975378D01*
Y975578D01*
X308510D01*
Y975378D01*
G37*
G36*
G01X313350Y975778D02*
X313492Y976178D01*
X314242D01*
X314385Y975778D01*
Y975578D01*
X313350D01*
Y975778D01*
G37*
G36*
G01X315560Y975378D02*
X315418Y974978D01*
X314668D01*
X314525Y975378D01*
Y975578D01*
X315560D01*
Y975378D01*
G37*
G36*
G01X311000Y975778D02*
X311142Y976178D01*
X311892D01*
X312035Y975778D01*
Y975578D01*
X311000D01*
Y975778D01*
G37*
G36*
G01X313210Y975378D02*
X313068Y974978D01*
X312318D01*
X312175Y975378D01*
Y975578D01*
X313210D01*
Y975378D01*
G37*
G36*
G01X310860D02*
X310718Y974978D01*
X309968D01*
X309825Y975378D01*
Y975578D01*
X310860D01*
Y975378D01*
G37*
G36*
G01X315700Y975778D02*
X315842Y976178D01*
X316592D01*
X316735Y975778D01*
Y975578D01*
X315700D01*
Y975778D01*
G37*
G36*
G01X318050D02*
X318192Y976178D01*
X318942D01*
X319085Y975778D01*
Y975578D01*
X318050D01*
Y975778D01*
G37*
G36*
G01X317910Y975378D02*
X317768Y974978D01*
X317018D01*
X316875Y975378D01*
Y975578D01*
X317910D01*
Y975378D01*
G37*
G36*
G01X320260D02*
X320118Y974978D01*
X319368D01*
X319225Y975378D01*
Y975578D01*
X320260D01*
Y975378D01*
G37*
G36*
G01X308650Y974578D02*
X308792Y974978D01*
X309542D01*
X309685Y974578D01*
Y974378D01*
X308650D01*
Y974578D01*
G37*
G36*
G01X306300D02*
X306442Y974978D01*
X307192D01*
X307335Y974578D01*
Y974378D01*
X306300D01*
Y974578D01*
G37*
G36*
G01X308510Y974178D02*
X308368Y973778D01*
X307618D01*
X307475Y974178D01*
Y974378D01*
X308510D01*
Y974178D01*
G37*
G36*
G01X313350Y974578D02*
X313492Y974978D01*
X314242D01*
X314385Y974578D01*
Y974378D01*
X313350D01*
Y974578D01*
G37*
G36*
G01X315560Y974178D02*
X315418Y973778D01*
X314668D01*
X314525Y974178D01*
Y974378D01*
X315560D01*
Y974178D01*
G37*
G36*
G01X311000Y974578D02*
X311142Y974978D01*
X311892D01*
X312035Y974578D01*
Y974378D01*
X311000D01*
Y974578D01*
G37*
G36*
G01X313210Y974178D02*
X313068Y973778D01*
X312318D01*
X312175Y974178D01*
Y974378D01*
X313210D01*
Y974178D01*
G37*
G36*
G01X310860D02*
X310718Y973778D01*
X309968D01*
X309825Y974178D01*
Y974378D01*
X310860D01*
Y974178D01*
G37*
G36*
G01X315700Y974578D02*
X315842Y974978D01*
X316592D01*
X316735Y974578D01*
Y974378D01*
X315700D01*
Y974578D01*
G37*
G36*
G01X318050D02*
X318192Y974978D01*
X318942D01*
X319085Y974578D01*
Y974378D01*
X318050D01*
Y974578D01*
G37*
G36*
G01X317910Y974178D02*
X317768Y973778D01*
X317018D01*
X316875Y974178D01*
Y974378D01*
X317910D01*
Y974178D01*
G37*
G36*
G01X308650Y970978D02*
X308792Y971378D01*
X309542D01*
X309685Y970978D01*
Y970778D01*
X308650D01*
Y970978D01*
G37*
G36*
G01X306300D02*
X306442Y971378D01*
X307192D01*
X307335Y970978D01*
Y970778D01*
X306300D01*
Y970978D01*
G37*
G36*
G01X308510Y970578D02*
X308368Y970178D01*
X307618D01*
X307475Y970578D01*
Y970778D01*
X308510D01*
Y970578D01*
G37*
G36*
G01X313350Y970978D02*
X313492Y971378D01*
X314242D01*
X314385Y970978D01*
Y970778D01*
X313350D01*
Y970978D01*
G37*
G36*
G01X315560Y970578D02*
X315418Y970178D01*
X314668D01*
X314525Y970578D01*
Y970778D01*
X315560D01*
Y970578D01*
G37*
G36*
G01X311000Y970978D02*
X311142Y971378D01*
X311892D01*
X312035Y970978D01*
Y970778D01*
X311000D01*
Y970978D01*
G37*
G36*
G01X313210Y970578D02*
X313068Y970178D01*
X312318D01*
X312175Y970578D01*
Y970778D01*
X313210D01*
Y970578D01*
G37*
G36*
G01X310860D02*
X310718Y970178D01*
X309968D01*
X309825Y970578D01*
Y970778D01*
X310860D01*
Y970578D01*
G37*
G36*
G01X315700Y970978D02*
X315842Y971378D01*
X316592D01*
X316735Y970978D01*
Y970778D01*
X315700D01*
Y970978D01*
G37*
G36*
G01X317910Y970578D02*
X317768Y970178D01*
X317018D01*
X316875Y970578D01*
Y970778D01*
X317910D01*
Y970578D01*
G37*
G36*
G01X308510Y968178D02*
X308368Y967778D01*
X307618D01*
X307475Y968178D01*
Y968378D01*
X308510D01*
Y968178D01*
G37*
G36*
G01X315560D02*
X315418Y967778D01*
X314668D01*
X314525Y968178D01*
Y968378D01*
X315560D01*
Y968178D01*
G37*
G36*
G01X313210D02*
X313068Y967778D01*
X312318D01*
X312175Y968178D01*
Y968378D01*
X313210D01*
Y968178D01*
G37*
G36*
G01X310860D02*
X310718Y967778D01*
X309968D01*
X309825Y968178D01*
Y968378D01*
X310860D01*
Y968178D01*
G37*
G36*
G01X308650Y968578D02*
X308792Y968978D01*
X309542D01*
X309685Y968578D01*
Y968378D01*
X308650D01*
Y968578D01*
G37*
G36*
G01X306300D02*
X306442Y968978D01*
X307192D01*
X307335Y968578D01*
Y968378D01*
X306300D01*
Y968578D01*
G37*
G36*
G01X313350D02*
X313492Y968978D01*
X314242D01*
X314385Y968578D01*
Y968378D01*
X313350D01*
Y968578D01*
G37*
G36*
G01X311000D02*
X311142Y968978D01*
X311892D01*
X312035Y968578D01*
Y968378D01*
X311000D01*
Y968578D01*
G37*
G36*
G01X315700D02*
X315842Y968978D01*
X316592D01*
X316735Y968578D01*
Y968378D01*
X315700D01*
Y968578D01*
G37*
G36*
G01X308650Y972178D02*
X308792Y972578D01*
X309542D01*
X309685Y972178D01*
Y971978D01*
X308650D01*
Y972178D01*
G37*
G36*
G01X306300D02*
X306442Y972578D01*
X307192D01*
X307335Y972178D01*
Y971978D01*
X306300D01*
Y972178D01*
G37*
G36*
G01X308510Y971778D02*
X308368Y971378D01*
X307618D01*
X307475Y971778D01*
Y971978D01*
X308510D01*
Y971778D01*
G37*
G36*
G01X313350Y972178D02*
X313492Y972578D01*
X314242D01*
X314385Y972178D01*
Y971978D01*
X313350D01*
Y972178D01*
G37*
G36*
G01X315560Y971778D02*
X315418Y971378D01*
X314668D01*
X314525Y971778D01*
Y971978D01*
X315560D01*
Y971778D01*
G37*
G36*
G01X311000Y972178D02*
X311142Y972578D01*
X311892D01*
X312035Y972178D01*
Y971978D01*
X311000D01*
Y972178D01*
G37*
G36*
G01X313210Y971778D02*
X313068Y971378D01*
X312318D01*
X312175Y971778D01*
Y971978D01*
X313210D01*
Y971778D01*
G37*
G36*
G01X310860D02*
X310718Y971378D01*
X309968D01*
X309825Y971778D01*
Y971978D01*
X310860D01*
Y971778D01*
G37*
G36*
G01X315700Y972178D02*
X315842Y972578D01*
X316592D01*
X316735Y972178D01*
Y971978D01*
X315700D01*
Y972178D01*
G37*
G36*
G01X317910Y971778D02*
X317768Y971378D01*
X317018D01*
X316875Y971778D01*
Y971978D01*
X317910D01*
Y971778D01*
G37*
G36*
G01X306300Y969778D02*
X306442Y970178D01*
X307192D01*
X307335Y969778D01*
Y969578D01*
X306300D01*
Y969778D01*
G37*
G36*
G01X308510Y969378D02*
X308368Y968978D01*
X307618D01*
X307475Y969378D01*
Y969578D01*
X308510D01*
Y969378D01*
G37*
G36*
G01X308650Y969778D02*
X308792Y970178D01*
X309542D01*
X309685Y969778D01*
Y969578D01*
X308650D01*
Y969778D01*
G37*
G36*
G01X313210Y969378D02*
X313068Y968978D01*
X312318D01*
X312175Y969378D01*
Y969578D01*
X313210D01*
Y969378D01*
G37*
G36*
G01X310860D02*
X310718Y968978D01*
X309968D01*
X309825Y969378D01*
Y969578D01*
X310860D01*
Y969378D01*
G37*
G36*
G01X313350Y969778D02*
X313492Y970178D01*
X314242D01*
X314385Y969778D01*
Y969578D01*
X313350D01*
Y969778D01*
G37*
G36*
G01X315560Y969378D02*
X315418Y968978D01*
X314668D01*
X314525Y969378D01*
Y969578D01*
X315560D01*
Y969378D01*
G37*
G36*
G01X311000Y969778D02*
X311142Y970178D01*
X311892D01*
X312035Y969778D01*
Y969578D01*
X311000D01*
Y969778D01*
G37*
G36*
G01X315700D02*
X315842Y970178D01*
X316592D01*
X316735Y969778D01*
Y969578D01*
X315700D01*
Y969778D01*
G37*
G36*
G01X308650Y973378D02*
X308792Y973778D01*
X309542D01*
X309685Y973378D01*
Y973178D01*
X308650D01*
Y973378D01*
G37*
G36*
G01X306300D02*
X306442Y973778D01*
X307192D01*
X307335Y973378D01*
Y973178D01*
X306300D01*
Y973378D01*
G37*
G36*
G01X308510Y972978D02*
X308368Y972578D01*
X307618D01*
X307475Y972978D01*
Y973178D01*
X308510D01*
Y972978D01*
G37*
G36*
G01X313350Y973378D02*
X313492Y973778D01*
X314242D01*
X314385Y973378D01*
Y973178D01*
X313350D01*
Y973378D01*
G37*
G36*
G01X315560Y972978D02*
X315418Y972578D01*
X314668D01*
X314525Y972978D01*
Y973178D01*
X315560D01*
Y972978D01*
G37*
G36*
G01X311000Y973378D02*
X311142Y973778D01*
X311892D01*
X312035Y973378D01*
Y973178D01*
X311000D01*
Y973378D01*
G37*
G36*
G01X313210Y972978D02*
X313068Y972578D01*
X312318D01*
X312175Y972978D01*
Y973178D01*
X313210D01*
Y972978D01*
G37*
G36*
G01X310860D02*
X310718Y972578D01*
X309968D01*
X309825Y972978D01*
Y973178D01*
X310860D01*
Y972978D01*
G37*
G36*
G01X315700Y973378D02*
X315842Y973778D01*
X316592D01*
X316735Y973378D01*
Y973178D01*
X315700D01*
Y973378D01*
G37*
G36*
G01X318050D02*
X318192Y973778D01*
X318942D01*
X319085Y973378D01*
Y973178D01*
X318050D01*
Y973378D01*
G37*
G36*
G01X317910Y972978D02*
X317768Y972578D01*
X317018D01*
X316875Y972978D01*
Y973178D01*
X317910D01*
Y972978D01*
G37*
G36*
G01X314654Y1014119D02*
X314796Y1014519D01*
X315546D01*
X315689Y1014119D01*
Y1013919D01*
X314654D01*
Y1014119D01*
G37*
G36*
G01X312304D02*
X312446Y1014519D01*
X313196D01*
X313339Y1014119D01*
Y1013919D01*
X312304D01*
Y1014119D01*
G37*
G36*
G01X314514Y1013719D02*
X314372Y1013319D01*
X313622D01*
X313479Y1013719D01*
Y1013919D01*
X314514D01*
Y1013719D01*
G37*
G36*
G01X309954Y1014119D02*
X310096Y1014519D01*
X310846D01*
X310989Y1014119D01*
Y1013919D01*
X309954D01*
Y1014119D01*
G37*
G36*
G01X312164Y1013719D02*
X312022Y1013319D01*
X311272D01*
X311129Y1013719D01*
Y1013919D01*
X312164D01*
Y1013719D01*
G37*
G36*
G01X317004Y1014119D02*
X317146Y1014519D01*
X317896D01*
X318039Y1014119D01*
Y1013919D01*
X317004D01*
Y1014119D01*
G37*
G36*
G01X319214Y1013719D02*
X319072Y1013319D01*
X318322D01*
X318179Y1013719D01*
Y1013919D01*
X319214D01*
Y1013719D01*
G37*
G36*
G01X316864D02*
X316722Y1013319D01*
X315972D01*
X315829Y1013719D01*
Y1013919D01*
X316864D01*
Y1013719D01*
G37*
G36*
G01X319354Y1014119D02*
X319496Y1014519D01*
X320246D01*
X320389Y1014119D01*
Y1013919D01*
X319354D01*
Y1014119D01*
G37*
G36*
G01X321564Y1013719D02*
X321422Y1013319D01*
X320672D01*
X320529Y1013719D01*
Y1013919D01*
X321564D01*
Y1013719D01*
G37*
G36*
G01X314654Y1012919D02*
X314796Y1013319D01*
X315546D01*
X315689Y1012919D01*
Y1012719D01*
X314654D01*
Y1012919D01*
G37*
G36*
G01X312304D02*
X312446Y1013319D01*
X313196D01*
X313339Y1012919D01*
Y1012719D01*
X312304D01*
Y1012919D01*
G37*
G36*
G01X314514Y1012519D02*
X314372Y1012119D01*
X313622D01*
X313479Y1012519D01*
Y1012719D01*
X314514D01*
Y1012519D01*
G37*
G36*
G01X309954Y1012919D02*
X310096Y1013319D01*
X310846D01*
X310989Y1012919D01*
Y1012719D01*
X309954D01*
Y1012919D01*
G37*
G36*
G01X312164Y1012519D02*
X312022Y1012119D01*
X311272D01*
X311129Y1012519D01*
Y1012719D01*
X312164D01*
Y1012519D01*
G37*
G36*
G01X317004Y1012919D02*
X317146Y1013319D01*
X317896D01*
X318039Y1012919D01*
Y1012719D01*
X317004D01*
Y1012919D01*
G37*
G36*
G01X319214Y1012519D02*
X319072Y1012119D01*
X318322D01*
X318179Y1012519D01*
Y1012719D01*
X319214D01*
Y1012519D01*
G37*
G36*
G01X316864D02*
X316722Y1012119D01*
X315972D01*
X315829Y1012519D01*
Y1012719D01*
X316864D01*
Y1012519D01*
G37*
G36*
G01X319354Y1012919D02*
X319496Y1013319D01*
X320246D01*
X320389Y1012919D01*
Y1012719D01*
X319354D01*
Y1012919D01*
G37*
G36*
G01X321564Y1012519D02*
X321422Y1012119D01*
X320672D01*
X320529Y1012519D01*
Y1012719D01*
X321564D01*
Y1012519D01*
G37*
G36*
G01X314654Y1011719D02*
X314796Y1012119D01*
X315546D01*
X315689Y1011719D01*
Y1011519D01*
X314654D01*
Y1011719D01*
G37*
G36*
G01X312304D02*
X312446Y1012119D01*
X313196D01*
X313339Y1011719D01*
Y1011519D01*
X312304D01*
Y1011719D01*
G37*
G36*
G01X309954D02*
X310096Y1012119D01*
X310846D01*
X310989Y1011719D01*
Y1011519D01*
X309954D01*
Y1011719D01*
G37*
G36*
G01X314514Y1011319D02*
X314372Y1010919D01*
X313622D01*
X313479Y1011319D01*
Y1011519D01*
X314514D01*
Y1011319D01*
G37*
G36*
G01X312164D02*
X312022Y1010919D01*
X311272D01*
X311129Y1011319D01*
Y1011519D01*
X312164D01*
Y1011319D01*
G37*
G36*
G01X317004Y1011719D02*
X317146Y1012119D01*
X317896D01*
X318039Y1011719D01*
Y1011519D01*
X317004D01*
Y1011719D01*
G37*
G36*
G01X319214Y1011319D02*
X319072Y1010919D01*
X318322D01*
X318179Y1011319D01*
Y1011519D01*
X319214D01*
Y1011319D01*
G37*
G36*
G01X316864D02*
X316722Y1010919D01*
X315972D01*
X315829Y1011319D01*
Y1011519D01*
X316864D01*
Y1011319D01*
G37*
G36*
G01X319354Y1011719D02*
X319496Y1012119D01*
X320246D01*
X320389Y1011719D01*
Y1011519D01*
X319354D01*
Y1011719D01*
G37*
G36*
G01X321564Y1011319D02*
X321422Y1010919D01*
X320672D01*
X320529Y1011319D01*
Y1011519D01*
X321564D01*
Y1011319D01*
G37*
G36*
G01X314654Y1010519D02*
X314796Y1010919D01*
X315546D01*
X315689Y1010519D01*
Y1010319D01*
X314654D01*
Y1010519D01*
G37*
G36*
G01X312304D02*
X312446Y1010919D01*
X313196D01*
X313339Y1010519D01*
Y1010319D01*
X312304D01*
Y1010519D01*
G37*
G36*
G01X314514Y1010119D02*
X314372Y1009719D01*
X313622D01*
X313479Y1010119D01*
Y1010319D01*
X314514D01*
Y1010119D01*
G37*
G36*
G01X309954Y1010519D02*
X310096Y1010919D01*
X310846D01*
X310989Y1010519D01*
Y1010319D01*
X309954D01*
Y1010519D01*
G37*
G36*
G01X309814Y1010119D02*
X309672Y1009719D01*
X308922D01*
X308779Y1010119D01*
Y1010319D01*
X309814D01*
Y1010119D01*
G37*
G36*
G01X312164D02*
X312022Y1009719D01*
X311272D01*
X311129Y1010119D01*
Y1010319D01*
X312164D01*
Y1010119D01*
G37*
G36*
G01X317004Y1010519D02*
X317146Y1010919D01*
X317896D01*
X318039Y1010519D01*
Y1010319D01*
X317004D01*
Y1010519D01*
G37*
G36*
G01X319214Y1010119D02*
X319072Y1009719D01*
X318322D01*
X318179Y1010119D01*
Y1010319D01*
X319214D01*
Y1010119D01*
G37*
G36*
G01X316864D02*
X316722Y1009719D01*
X315972D01*
X315829Y1010119D01*
Y1010319D01*
X316864D01*
Y1010119D01*
G37*
G36*
G01X319354Y1010519D02*
X319496Y1010919D01*
X320246D01*
X320389Y1010519D01*
Y1010319D01*
X319354D01*
Y1010519D01*
G37*
G36*
G01X321564Y1010119D02*
X321422Y1009719D01*
X320672D01*
X320529Y1010119D01*
Y1010319D01*
X321564D01*
Y1010119D01*
G37*
G36*
G01X314654Y1009319D02*
X314796Y1009719D01*
X315546D01*
X315689Y1009319D01*
Y1009119D01*
X314654D01*
Y1009319D01*
G37*
G36*
G01X312304D02*
X312446Y1009719D01*
X313196D01*
X313339Y1009319D01*
Y1009119D01*
X312304D01*
Y1009319D01*
G37*
G36*
G01X314514Y1008919D02*
X314372Y1008519D01*
X313622D01*
X313479Y1008919D01*
Y1009119D01*
X314514D01*
Y1008919D01*
G37*
G36*
G01X309954Y1009319D02*
X310096Y1009719D01*
X310846D01*
X310989Y1009319D01*
Y1009119D01*
X309954D01*
Y1009319D01*
G37*
G36*
G01X309814Y1008919D02*
X309672Y1008519D01*
X308922D01*
X308779Y1008919D01*
Y1009119D01*
X309814D01*
Y1008919D01*
G37*
G36*
G01X312164D02*
X312022Y1008519D01*
X311272D01*
X311129Y1008919D01*
Y1009119D01*
X312164D01*
Y1008919D01*
G37*
G36*
G01X316864D02*
X316722Y1008519D01*
X315972D01*
X315829Y1008919D01*
Y1009119D01*
X316864D01*
Y1008919D01*
G37*
G36*
G01X317004Y1009319D02*
X317146Y1009719D01*
X317896D01*
X318039Y1009319D01*
Y1009119D01*
X317004D01*
Y1009319D01*
G37*
G36*
G01X319214Y1008919D02*
X319072Y1008519D01*
X318322D01*
X318179Y1008919D01*
Y1009119D01*
X319214D01*
Y1008919D01*
G37*
G36*
G01X319354Y1009319D02*
X319496Y1009719D01*
X320246D01*
X320389Y1009319D01*
Y1009119D01*
X319354D01*
Y1009319D01*
G37*
G36*
G01X321564Y1008919D02*
X321422Y1008519D01*
X320672D01*
X320529Y1008919D01*
Y1009119D01*
X321564D01*
Y1008919D01*
G37*
G36*
G01X314514Y1017319D02*
X314372Y1016919D01*
X313622D01*
X313479Y1017319D01*
Y1017519D01*
X314514D01*
Y1017319D01*
G37*
G36*
G01X312304Y1017719D02*
X312446Y1018119D01*
X313196D01*
X313339Y1017719D01*
Y1017519D01*
X312304D01*
Y1017719D01*
G37*
G36*
G01X314654D02*
X314796Y1018119D01*
X315546D01*
X315689Y1017719D01*
Y1017519D01*
X314654D01*
Y1017719D01*
G37*
G36*
G01X316864Y1017319D02*
X316722Y1016919D01*
X315972D01*
X315829Y1017319D01*
Y1017519D01*
X316864D01*
Y1017319D01*
G37*
G36*
G01X319214D02*
X319072Y1016919D01*
X318322D01*
X318179Y1017319D01*
Y1017519D01*
X319214D01*
Y1017319D01*
G37*
G36*
G01X317004Y1017719D02*
X317146Y1018119D01*
X317896D01*
X318039Y1017719D01*
Y1017519D01*
X317004D01*
Y1017719D01*
G37*
G36*
G01X321564Y1017319D02*
X321422Y1016919D01*
X320672D01*
X320529Y1017319D01*
Y1017519D01*
X321564D01*
Y1017319D01*
G37*
G36*
G01X319354Y1017719D02*
X319496Y1018119D01*
X320246D01*
X320389Y1017719D01*
Y1017519D01*
X319354D01*
Y1017719D01*
G37*
G36*
G01X312304Y1016519D02*
X312446Y1016919D01*
X313196D01*
X313339Y1016519D01*
Y1016319D01*
X312304D01*
Y1016519D01*
G37*
G36*
G01X314654D02*
X314796Y1016919D01*
X315546D01*
X315689Y1016519D01*
Y1016319D01*
X314654D01*
Y1016519D01*
G37*
G36*
G01X314514Y1016119D02*
X314372Y1015719D01*
X313622D01*
X313479Y1016119D01*
Y1016319D01*
X314514D01*
Y1016119D01*
G37*
G36*
G01X312164D02*
X312022Y1015719D01*
X311272D01*
X311129Y1016119D01*
Y1016319D01*
X312164D01*
Y1016119D01*
G37*
G36*
G01X317004Y1016519D02*
X317146Y1016919D01*
X317896D01*
X318039Y1016519D01*
Y1016319D01*
X317004D01*
Y1016519D01*
G37*
G36*
G01X316864Y1016119D02*
X316722Y1015719D01*
X315972D01*
X315829Y1016119D01*
Y1016319D01*
X316864D01*
Y1016119D01*
G37*
G36*
G01X319214D02*
X319072Y1015719D01*
X318322D01*
X318179Y1016119D01*
Y1016319D01*
X319214D01*
Y1016119D01*
G37*
G36*
G01X319354Y1016519D02*
X319496Y1016919D01*
X320246D01*
X320389Y1016519D01*
Y1016319D01*
X319354D01*
Y1016519D01*
G37*
G36*
G01X321564Y1016119D02*
X321422Y1015719D01*
X320672D01*
X320529Y1016119D01*
Y1016319D01*
X321564D01*
Y1016119D01*
G37*
G36*
G01X312304Y1015319D02*
X312446Y1015719D01*
X313196D01*
X313339Y1015319D01*
Y1015119D01*
X312304D01*
Y1015319D01*
G37*
G36*
G01X314654D02*
X314796Y1015719D01*
X315546D01*
X315689Y1015319D01*
Y1015119D01*
X314654D01*
Y1015319D01*
G37*
G36*
G01X314514Y1014919D02*
X314372Y1014519D01*
X313622D01*
X313479Y1014919D01*
Y1015119D01*
X314514D01*
Y1014919D01*
G37*
G36*
G01X312164D02*
X312022Y1014519D01*
X311272D01*
X311129Y1014919D01*
Y1015119D01*
X312164D01*
Y1014919D01*
G37*
G36*
G01X317004Y1015319D02*
X317146Y1015719D01*
X317896D01*
X318039Y1015319D01*
Y1015119D01*
X317004D01*
Y1015319D01*
G37*
G36*
G01X319214Y1014919D02*
X319072Y1014519D01*
X318322D01*
X318179Y1014919D01*
Y1015119D01*
X319214D01*
Y1014919D01*
G37*
G36*
G01X316864D02*
X316722Y1014519D01*
X315972D01*
X315829Y1014919D01*
Y1015119D01*
X316864D01*
Y1014919D01*
G37*
G36*
G01X319354Y1015319D02*
X319496Y1015719D01*
X320246D01*
X320389Y1015319D01*
Y1015119D01*
X319354D01*
Y1015319D01*
G37*
G36*
G01X321564Y1014919D02*
X321422Y1014519D01*
X320672D01*
X320529Y1014919D01*
Y1015119D01*
X321564D01*
Y1014919D01*
G37*
G36*
G01X321079Y1028268D02*
X320696Y1028086D01*
X320165Y1028616D01*
X320348Y1029000D01*
X320489Y1029141D01*
X321221Y1028409D01*
X321079Y1028268D01*
G37*
G36*
G01X319799Y1030113D02*
X320183Y1030295D01*
X320713Y1029765D01*
X320531Y1029381D01*
X320390Y1029240D01*
X319658Y1029972D01*
X319799Y1030113D01*
G37*
G36*
G01X319418Y1029929D02*
X319034Y1029747D01*
X318504Y1030278D01*
X318686Y1030661D01*
X318827Y1030803D01*
X319559Y1030071D01*
X319418Y1029929D01*
G37*
G36*
G01X320267Y1030779D02*
X319884Y1030597D01*
X319353Y1031127D01*
X319535Y1031511D01*
X319677Y1031652D01*
X320409Y1030920D01*
X320267Y1030779D01*
G37*
G36*
G01X320649Y1030963D02*
X321033Y1031145D01*
X321563Y1030615D01*
X321381Y1030231D01*
X321239Y1030090D01*
X320508Y1030821D01*
X320649Y1030963D01*
G37*
G36*
G01X321929Y1029117D02*
X321545Y1028935D01*
X321015Y1029466D01*
X321197Y1029849D01*
X321338Y1029991D01*
X322070Y1029259D01*
X321929Y1029117D01*
G37*
G36*
G01X318568Y1029080D02*
X318185Y1028898D01*
X317654Y1029428D01*
X317836Y1029812D01*
X317978Y1029953D01*
X318710Y1029221D01*
X318568Y1029080D01*
G37*
G36*
G01X317288Y1030926D02*
X317672Y1031108D01*
X318202Y1030577D01*
X318020Y1030194D01*
X317879Y1030052D01*
X317147Y1030784D01*
X317288Y1030926D01*
G37*
G36*
G01X316906Y1030742D02*
X316523Y1030560D01*
X315993Y1031090D01*
X316175Y1031474D01*
X316316Y1031615D01*
X317048Y1030883D01*
X316906Y1030742D01*
G37*
G36*
G01X320230Y1027418D02*
X319846Y1027236D01*
X319316Y1027767D01*
X319498Y1028150D01*
X319639Y1028292D01*
X320371Y1027560D01*
X320230Y1027418D01*
G37*
G36*
G01X320612Y1027602D02*
X320995Y1027784D01*
X321526Y1027254D01*
X321344Y1026870D01*
X321202Y1026729D01*
X320470Y1027461D01*
X320612Y1027602D01*
G37*
G36*
G01X318950Y1029264D02*
X319334Y1029446D01*
X319864Y1028916D01*
X319682Y1028532D01*
X319540Y1028391D01*
X318809Y1029122D01*
X318950Y1029264D01*
G37*
G36*
G01X319214Y1022119D02*
X319072Y1021719D01*
X318322D01*
X318179Y1022119D01*
Y1022319D01*
X319214D01*
Y1022119D01*
G37*
G36*
G01X321564D02*
X321422Y1021719D01*
X320672D01*
X320529Y1022119D01*
Y1022319D01*
X321564D01*
Y1022119D01*
G37*
G36*
G01X319354Y1022519D02*
X319496Y1022919D01*
X320246D01*
X320389Y1022519D01*
Y1022319D01*
X319354D01*
Y1022519D01*
G37*
G36*
G01X312304Y1018919D02*
X312446Y1019319D01*
X313196D01*
X313339Y1018919D01*
Y1018719D01*
X312304D01*
Y1018919D01*
G37*
G36*
G01X314654D02*
X314796Y1019319D01*
X315546D01*
X315689Y1018919D01*
Y1018719D01*
X314654D01*
Y1018919D01*
G37*
G36*
G01X314514Y1018519D02*
X314372Y1018119D01*
X313622D01*
X313479Y1018519D01*
Y1018719D01*
X314514D01*
Y1018519D01*
G37*
G36*
G01X317004Y1018919D02*
X317146Y1019319D01*
X317896D01*
X318039Y1018919D01*
Y1018719D01*
X317004D01*
Y1018919D01*
G37*
G36*
G01X319214Y1018519D02*
X319072Y1018119D01*
X318322D01*
X318179Y1018519D01*
Y1018719D01*
X319214D01*
Y1018519D01*
G37*
G36*
G01X316864D02*
X316722Y1018119D01*
X315972D01*
X315829Y1018519D01*
Y1018719D01*
X316864D01*
Y1018519D01*
G37*
G36*
G01X319354Y1018919D02*
X319496Y1019319D01*
X320246D01*
X320389Y1018919D01*
Y1018719D01*
X319354D01*
Y1018919D01*
G37*
G36*
G01X321564Y1018519D02*
X321422Y1018119D01*
X320672D01*
X320529Y1018519D01*
Y1018719D01*
X321564D01*
Y1018519D01*
G37*
G36*
G01X317004Y1021319D02*
X317146Y1021719D01*
X317896D01*
X318039Y1021319D01*
Y1021119D01*
X317004D01*
Y1021319D01*
G37*
G36*
G01X316864Y1020919D02*
X316722Y1020519D01*
X315972D01*
X315829Y1020919D01*
Y1021119D01*
X316864D01*
Y1020919D01*
G37*
G36*
G01X319214D02*
X319072Y1020519D01*
X318322D01*
X318179Y1020919D01*
Y1021119D01*
X319214D01*
Y1020919D01*
G37*
G36*
G01X319354Y1021319D02*
X319496Y1021719D01*
X320246D01*
X320389Y1021319D01*
Y1021119D01*
X319354D01*
Y1021319D01*
G37*
G36*
G01X321564Y1020919D02*
X321422Y1020519D01*
X320672D01*
X320529Y1020919D01*
Y1021119D01*
X321564D01*
Y1020919D01*
G37*
G36*
G01X314654Y1020119D02*
X314796Y1020519D01*
X315546D01*
X315689Y1020119D01*
Y1019919D01*
X314654D01*
Y1020119D01*
G37*
G36*
G01X314514Y1019719D02*
X314372Y1019319D01*
X313622D01*
X313479Y1019719D01*
Y1019919D01*
X314514D01*
Y1019719D01*
G37*
G36*
G01X317004Y1020119D02*
X317146Y1020519D01*
X317896D01*
X318039Y1020119D01*
Y1019919D01*
X317004D01*
Y1020119D01*
G37*
G36*
G01X319214Y1019719D02*
X319072Y1019319D01*
X318322D01*
X318179Y1019719D01*
Y1019919D01*
X319214D01*
Y1019719D01*
G37*
G36*
G01X316864D02*
X316722Y1019319D01*
X315972D01*
X315829Y1019719D01*
Y1019919D01*
X316864D01*
Y1019719D01*
G37*
G36*
G01X319354Y1020119D02*
X319496Y1020519D01*
X320246D01*
X320389Y1020119D01*
Y1019919D01*
X319354D01*
Y1020119D01*
G37*
G36*
G01X321564Y1019719D02*
X321422Y1019319D01*
X320672D01*
X320529Y1019719D01*
Y1019919D01*
X321564D01*
Y1019719D01*
G37*
G36*
G01X319893Y1047003D02*
X320277Y1047185D01*
X320807Y1046655D01*
X320625Y1046271D01*
X320483Y1046130D01*
X319752Y1046861D01*
X319893Y1047003D01*
G37*
G36*
G01X319511Y1046819D02*
X319128Y1046637D01*
X318597Y1047167D01*
X318779Y1047551D01*
X318921Y1047692D01*
X319653Y1046960D01*
X319511Y1046819D01*
G37*
G36*
G01X321555Y1045341D02*
X321938Y1045523D01*
X322469Y1044993D01*
X322287Y1044609D01*
X322145Y1044468D01*
X321413Y1045200D01*
X321555Y1045341D01*
G37*
G36*
G01X321173Y1045157D02*
X320789Y1044975D01*
X320259Y1045506D01*
X320441Y1045889D01*
X320582Y1046031D01*
X321314Y1045299D01*
X321173Y1045157D01*
G37*
G36*
G01X316151Y1046782D02*
X315767Y1046600D01*
X315237Y1047130D01*
X315419Y1047514D01*
X315560Y1047656D01*
X316292Y1046924D01*
X316151Y1046782D01*
G37*
G36*
G01X316533Y1046966D02*
X316916Y1047148D01*
X317447Y1046618D01*
X317265Y1046234D01*
X317123Y1046093D01*
X316391Y1046825D01*
X316533Y1046966D01*
G37*
G36*
G01X318194Y1045304D02*
X318578Y1045486D01*
X319108Y1044956D01*
X318926Y1044573D01*
X318785Y1044431D01*
X318053Y1045163D01*
X318194Y1045304D01*
G37*
G36*
G01X317813Y1045121D02*
X317429Y1044938D01*
X316899Y1045469D01*
X317081Y1045852D01*
X317222Y1045994D01*
X317954Y1045262D01*
X317813Y1045121D01*
G37*
G36*
G01X321518Y1041981D02*
X321901Y1042163D01*
X322432Y1041633D01*
X322250Y1041249D01*
X322108Y1041108D01*
X321376Y1041840D01*
X321518Y1041981D01*
G37*
G36*
G01X319856Y1043643D02*
X320240Y1043825D01*
X320770Y1043294D01*
X320588Y1042911D01*
X320447Y1042769D01*
X319715Y1043501D01*
X319856Y1043643D01*
G37*
G36*
G01X319474Y1043459D02*
X319091Y1043277D01*
X318560Y1043807D01*
X318742Y1044191D01*
X318884Y1044332D01*
X319616Y1043600D01*
X319474Y1043459D01*
G37*
G36*
G01X321136Y1041797D02*
X320752Y1041615D01*
X320222Y1042145D01*
X320404Y1042529D01*
X320546Y1042670D01*
X321277Y1041939D01*
X321136Y1041797D01*
G37*
G36*
G01X318662Y1045970D02*
X318279Y1045788D01*
X317748Y1046318D01*
X317930Y1046702D01*
X318072Y1046843D01*
X318804Y1046111D01*
X318662Y1045970D01*
G37*
G36*
G01X320706Y1044492D02*
X321089Y1044674D01*
X321620Y1044144D01*
X321438Y1043760D01*
X321296Y1043619D01*
X320564Y1044351D01*
X320706Y1044492D01*
G37*
G36*
G01X319044Y1046154D02*
X319428Y1046336D01*
X319958Y1045806D01*
X319776Y1045422D01*
X319634Y1045281D01*
X318903Y1046012D01*
X319044Y1046154D01*
G37*
G36*
G01X320324Y1044308D02*
X319940Y1044126D01*
X319410Y1044657D01*
X319592Y1045040D01*
X319733Y1045182D01*
X320465Y1044450D01*
X320324Y1044308D01*
G37*
G36*
G01X321986Y1042647D02*
X321602Y1042465D01*
X321072Y1042995D01*
X321254Y1043379D01*
X321395Y1043520D01*
X322127Y1042788D01*
X321986Y1042647D01*
G37*
G36*
G01X314022Y1047779D02*
X314406Y1047961D01*
X314936Y1047431D01*
X314754Y1047047D01*
X314612Y1046906D01*
X313881Y1047637D01*
X314022Y1047779D01*
G37*
G36*
G01X315302Y1045933D02*
X314918Y1045751D01*
X314388Y1046281D01*
X314570Y1046665D01*
X314711Y1046807D01*
X315443Y1046075D01*
X315302Y1045933D01*
G37*
G36*
G01X315684Y1046117D02*
X316067Y1046299D01*
X316598Y1045769D01*
X316416Y1045385D01*
X316274Y1045244D01*
X315542Y1045976D01*
X315684Y1046117D01*
G37*
G36*
G01X318625Y1042610D02*
X318242Y1042428D01*
X317711Y1042958D01*
X317893Y1043342D01*
X318035Y1043483D01*
X318767Y1042751D01*
X318625Y1042610D01*
G37*
G36*
G01X317345Y1044455D02*
X317729Y1044637D01*
X318259Y1044107D01*
X318077Y1043724D01*
X317936Y1043582D01*
X317204Y1044314D01*
X317345Y1044455D01*
G37*
G36*
G01X316964Y1044272D02*
X316580Y1044089D01*
X316050Y1044620D01*
X316232Y1045003D01*
X316373Y1045145D01*
X317105Y1044413D01*
X316964Y1044272D01*
G37*
G36*
G01X320287Y1040948D02*
X319903Y1040766D01*
X319373Y1041296D01*
X319555Y1041680D01*
X319697Y1041821D01*
X320428Y1041090D01*
X320287Y1040948D01*
G37*
G36*
G01X319007Y1042794D02*
X319391Y1042976D01*
X319921Y1042445D01*
X319739Y1042062D01*
X319598Y1041920D01*
X318866Y1042652D01*
X319007Y1042794D01*
G37*
G36*
G01X320669Y1041132D02*
X321052Y1041314D01*
X321583Y1040784D01*
X321401Y1040400D01*
X321259Y1040259D01*
X320527Y1040991D01*
X320669Y1041132D01*
G37*
G36*
G01X321949Y1039286D02*
X321565Y1039104D01*
X321035Y1039635D01*
X321217Y1040018D01*
X321358Y1040160D01*
X322090Y1039428D01*
X321949Y1039286D01*
G37*
G36*
G01X311528Y1041783D02*
X311912Y1041965D01*
X312442Y1041434D01*
X312260Y1041051D01*
X312119Y1040909D01*
X311387Y1041641D01*
X311528Y1041783D01*
G37*
G36*
G01X309867Y1043444D02*
X310250Y1043626D01*
X310781Y1043096D01*
X310598Y1042712D01*
X310457Y1042571D01*
X309725Y1043303D01*
X309867Y1043444D01*
G37*
G36*
G01X312808Y1039937D02*
X312425Y1039755D01*
X311894Y1040285D01*
X312076Y1040669D01*
X312218Y1040810D01*
X312950Y1040078D01*
X312808Y1039937D01*
G37*
G36*
G01X311146Y1041599D02*
X310763Y1041417D01*
X310233Y1041947D01*
X310415Y1042331D01*
X310556Y1042472D01*
X311288Y1041740D01*
X311146Y1041599D01*
G37*
G36*
G01X309485Y1043260D02*
X309101Y1043078D01*
X308571Y1043609D01*
X308753Y1043992D01*
X308894Y1044134D01*
X309626Y1043402D01*
X309485Y1043260D01*
G37*
G36*
G01X308205Y1045106D02*
X308588Y1045288D01*
X309119Y1044758D01*
X308937Y1044374D01*
X308795Y1044233D01*
X308063Y1044965D01*
X308205Y1045106D01*
G37*
G36*
G01X306543Y1046768D02*
X306927Y1046950D01*
X307457Y1046419D01*
X307275Y1046036D01*
X307134Y1045894D01*
X306402Y1046626D01*
X306543Y1046768D01*
G37*
G36*
G01X307823Y1044922D02*
X307439Y1044740D01*
X306909Y1045270D01*
X307091Y1045654D01*
X307233Y1045795D01*
X307964Y1045064D01*
X307823Y1044922D01*
G37*
G36*
G01X313190Y1040121D02*
X313574Y1040303D01*
X314104Y1039773D01*
X313922Y1039389D01*
X313780Y1039248D01*
X313049Y1039979D01*
X313190Y1040121D01*
G37*
G36*
G01X314470Y1038275D02*
X314086Y1038093D01*
X313556Y1038624D01*
X313738Y1039007D01*
X313879Y1039149D01*
X314611Y1038417D01*
X314470Y1038275D01*
G37*
G36*
G01X314852Y1038459D02*
X315235Y1038641D01*
X315766Y1038111D01*
X315584Y1037727D01*
X315442Y1037586D01*
X314710Y1038318D01*
X314852Y1038459D01*
G37*
G36*
G01X316132Y1036614D02*
X315748Y1036432D01*
X315218Y1036962D01*
X315400Y1037345D01*
X315541Y1037487D01*
X316273Y1036755D01*
X316132Y1036614D01*
G37*
G36*
G01X316513Y1036797D02*
X316897Y1036980D01*
X317427Y1036449D01*
X317245Y1036066D01*
X317104Y1035924D01*
X316372Y1036656D01*
X316513Y1036797D01*
G37*
G36*
G01X318175Y1035136D02*
X318559Y1035318D01*
X319089Y1034787D01*
X318907Y1034404D01*
X318766Y1034262D01*
X318034Y1034994D01*
X318175Y1035136D01*
G37*
G36*
G01X317793Y1034952D02*
X317410Y1034770D01*
X316879Y1035300D01*
X317061Y1035684D01*
X317203Y1035825D01*
X317935Y1035093D01*
X317793Y1034952D01*
G37*
G36*
G01X319837Y1033474D02*
X320220Y1033656D01*
X320751Y1033126D01*
X320569Y1032742D01*
X320427Y1032601D01*
X319695Y1033333D01*
X319837Y1033474D01*
G37*
G36*
G01X321117Y1031628D02*
X320733Y1031446D01*
X320203Y1031977D01*
X320385Y1032360D01*
X320526Y1032502D01*
X321258Y1031770D01*
X321117Y1031628D01*
G37*
G36*
G01X319455Y1033290D02*
X319071Y1033108D01*
X318541Y1033638D01*
X318723Y1034022D01*
X318865Y1034163D01*
X319596Y1033432D01*
X319455Y1033290D01*
G37*
G36*
G01X321498Y1031812D02*
X321882Y1031994D01*
X322412Y1031464D01*
X322230Y1031080D01*
X322089Y1030939D01*
X321357Y1031671D01*
X321498Y1031812D01*
G37*
G36*
G01X314433Y1034915D02*
X314049Y1034733D01*
X313519Y1035263D01*
X313701Y1035646D01*
X313842Y1035788D01*
X314574Y1035056D01*
X314433Y1034915D01*
G37*
G36*
G01X314814Y1035098D02*
X315198Y1035281D01*
X315728Y1034750D01*
X315546Y1034367D01*
X315405Y1034225D01*
X314673Y1034957D01*
X314814Y1035098D01*
G37*
G36*
G01X311491Y1038422D02*
X311875Y1038604D01*
X312405Y1038074D01*
X312223Y1037690D01*
X312081Y1037549D01*
X311350Y1038280D01*
X311491Y1038422D01*
G37*
G36*
G01X313153Y1036760D02*
X313536Y1036942D01*
X314067Y1036412D01*
X313885Y1036028D01*
X313743Y1035887D01*
X313011Y1036619D01*
X313153Y1036760D01*
G37*
G36*
G01X311109Y1038238D02*
X310726Y1038056D01*
X310195Y1038586D01*
X310377Y1038970D01*
X310519Y1039111D01*
X311251Y1038379D01*
X311109Y1038238D01*
G37*
G36*
G01X309447Y1039900D02*
X309064Y1039718D01*
X308534Y1040248D01*
X308716Y1040632D01*
X308857Y1040773D01*
X309589Y1040041D01*
X309447Y1039900D01*
G37*
G36*
G01X307786Y1041561D02*
X307402Y1041379D01*
X306872Y1041910D01*
X307054Y1042293D01*
X307195Y1042435D01*
X307927Y1041703D01*
X307786Y1041561D01*
G37*
G36*
G01X309829Y1040084D02*
X310213Y1040266D01*
X310743Y1039735D01*
X310561Y1039352D01*
X310420Y1039210D01*
X309688Y1039942D01*
X309829Y1040084D01*
G37*
G36*
G01X308168Y1041745D02*
X308551Y1041927D01*
X309082Y1041397D01*
X308899Y1041013D01*
X308758Y1040872D01*
X308026Y1041604D01*
X308168Y1041745D01*
G37*
G36*
G01X306506Y1043407D02*
X306889Y1043589D01*
X307420Y1043059D01*
X307238Y1042675D01*
X307096Y1042534D01*
X306364Y1043266D01*
X306506Y1043407D01*
G37*
G36*
G01X312771Y1036576D02*
X312387Y1036394D01*
X311857Y1036925D01*
X312039Y1037308D01*
X312180Y1037450D01*
X312912Y1036718D01*
X312771Y1036576D01*
G37*
G36*
G01X316094Y1033253D02*
X315711Y1033071D01*
X315180Y1033601D01*
X315362Y1033985D01*
X315504Y1034126D01*
X316236Y1033394D01*
X316094Y1033253D01*
G37*
G36*
G01X317756Y1031591D02*
X317372Y1031409D01*
X316842Y1031939D01*
X317024Y1032323D01*
X317166Y1032464D01*
X317897Y1031733D01*
X317756Y1031591D01*
G37*
G36*
G01X316476Y1033437D02*
X316860Y1033619D01*
X317390Y1033088D01*
X317208Y1032705D01*
X317067Y1032563D01*
X316335Y1033295D01*
X316476Y1033437D01*
G37*
G36*
G01X318138Y1031775D02*
X318521Y1031957D01*
X319052Y1031427D01*
X318870Y1031043D01*
X318728Y1030902D01*
X317996Y1031634D01*
X318138Y1031775D01*
G37*
G36*
G01X314002Y1037610D02*
X314386Y1037792D01*
X314916Y1037261D01*
X314734Y1036878D01*
X314593Y1036736D01*
X313861Y1037468D01*
X314002Y1037610D01*
G37*
G36*
G01X310297Y1040749D02*
X309913Y1040567D01*
X309383Y1041097D01*
X309565Y1041481D01*
X309707Y1041622D01*
X310438Y1040891D01*
X310297Y1040749D01*
G37*
G36*
G01X308635Y1042411D02*
X308252Y1042229D01*
X307721Y1042759D01*
X307903Y1043143D01*
X308045Y1043284D01*
X308777Y1042552D01*
X308635Y1042411D01*
G37*
G36*
G01X306974Y1044073D02*
X306590Y1043891D01*
X306060Y1044421D01*
X306242Y1044804D01*
X306383Y1044946D01*
X307115Y1044214D01*
X306974Y1044073D01*
G37*
G36*
G01X311959Y1039088D02*
X311575Y1038905D01*
X311045Y1039436D01*
X311227Y1039819D01*
X311368Y1039961D01*
X312100Y1039229D01*
X311959Y1039088D01*
G37*
G36*
G01X310679Y1040933D02*
X311062Y1041115D01*
X311593Y1040585D01*
X311411Y1040201D01*
X311269Y1040060D01*
X310537Y1040792D01*
X310679Y1040933D01*
G37*
G36*
G01X309017Y1042595D02*
X309401Y1042777D01*
X309931Y1042247D01*
X309749Y1041863D01*
X309608Y1041721D01*
X308876Y1042453D01*
X309017Y1042595D01*
G37*
G36*
G01X307355Y1044256D02*
X307739Y1044439D01*
X308269Y1043908D01*
X308087Y1043525D01*
X307946Y1043383D01*
X307214Y1044115D01*
X307355Y1044256D01*
G37*
G36*
G01X305694Y1045918D02*
X306077Y1046100D01*
X306608Y1045570D01*
X306426Y1045186D01*
X306284Y1045045D01*
X305552Y1045777D01*
X305694Y1045918D01*
G37*
G36*
G01X312340Y1039271D02*
X312724Y1039453D01*
X313254Y1038923D01*
X313072Y1038539D01*
X312931Y1038398D01*
X312199Y1039130D01*
X312340Y1039271D01*
G37*
G36*
G01X313620Y1037426D02*
X313237Y1037244D01*
X312706Y1037774D01*
X312889Y1038158D01*
X313030Y1038299D01*
X313762Y1037567D01*
X313620Y1037426D01*
G37*
G36*
G01X315282Y1035764D02*
X314898Y1035582D01*
X314368Y1036112D01*
X314550Y1036496D01*
X314692Y1036637D01*
X315423Y1035906D01*
X315282Y1035764D01*
G37*
G36*
G01X318605Y1032441D02*
X318222Y1032259D01*
X317692Y1032789D01*
X317874Y1033173D01*
X318015Y1033314D01*
X318747Y1032582D01*
X318605Y1032441D01*
G37*
G36*
G01X317326Y1034286D02*
X317709Y1034468D01*
X318240Y1033938D01*
X318057Y1033554D01*
X317916Y1033413D01*
X317184Y1034145D01*
X317326Y1034286D01*
G37*
G36*
G01X316944Y1034102D02*
X316560Y1033920D01*
X316030Y1034451D01*
X316212Y1034834D01*
X316353Y1034976D01*
X317085Y1034244D01*
X316944Y1034102D01*
G37*
G36*
G01X315664Y1035948D02*
X316048Y1036130D01*
X316578Y1035600D01*
X316396Y1035216D01*
X316254Y1035075D01*
X315522Y1035807D01*
X315664Y1035948D01*
G37*
G36*
G01X318987Y1032625D02*
X319371Y1032807D01*
X319901Y1032276D01*
X319719Y1031893D01*
X319578Y1031751D01*
X318846Y1032483D01*
X318987Y1032625D01*
G37*
G36*
G01X313583Y1034065D02*
X313199Y1033883D01*
X312669Y1034413D01*
X312851Y1034797D01*
X312993Y1034938D01*
X313724Y1034207D01*
X313583Y1034065D01*
G37*
G36*
G01X315245Y1032403D02*
X314861Y1032221D01*
X314331Y1032752D01*
X314513Y1033135D01*
X314654Y1033277D01*
X315386Y1032545D01*
X315245Y1032403D01*
G37*
G36*
G01X313965Y1034249D02*
X314349Y1034431D01*
X314879Y1033901D01*
X314697Y1033517D01*
X314555Y1033376D01*
X313823Y1034108D01*
X313965Y1034249D01*
G37*
G36*
G01X308980Y1039234D02*
X309363Y1039416D01*
X309894Y1038886D01*
X309712Y1038502D01*
X309570Y1038361D01*
X308838Y1039093D01*
X308980Y1039234D01*
G37*
G36*
G01X308598Y1039050D02*
X308214Y1038868D01*
X307684Y1039398D01*
X307866Y1039782D01*
X308008Y1039923D01*
X308739Y1039192D01*
X308598Y1039050D01*
G37*
G36*
G01X306936Y1040712D02*
X306553Y1040530D01*
X306022Y1041060D01*
X306204Y1041444D01*
X306346Y1041585D01*
X307078Y1040853D01*
X306936Y1040712D01*
G37*
G36*
G01X307318Y1040896D02*
X307702Y1041078D01*
X308232Y1040548D01*
X308050Y1040164D01*
X307909Y1040022D01*
X307177Y1040754D01*
X307318Y1040896D01*
G37*
G36*
G01X305656Y1042557D02*
X306040Y1042740D01*
X306570Y1042209D01*
X306388Y1041826D01*
X306247Y1041684D01*
X305515Y1042416D01*
X305656Y1042557D01*
G37*
G36*
G01X310260Y1037389D02*
X309876Y1037206D01*
X309346Y1037737D01*
X309528Y1038120D01*
X309669Y1038262D01*
X310401Y1037530D01*
X310260Y1037389D01*
G37*
G36*
G01X311921Y1035727D02*
X311538Y1035545D01*
X311007Y1036075D01*
X311190Y1036459D01*
X311331Y1036600D01*
X312063Y1035868D01*
X311921Y1035727D01*
G37*
G36*
G01X310641Y1037572D02*
X311025Y1037754D01*
X311555Y1037224D01*
X311373Y1036840D01*
X311232Y1036699D01*
X310500Y1037431D01*
X310641Y1037572D01*
G37*
G36*
G01X312303Y1035911D02*
X312687Y1036093D01*
X313217Y1035562D01*
X313035Y1035179D01*
X312894Y1035037D01*
X312162Y1035769D01*
X312303Y1035911D01*
G37*
G36*
G01X315627Y1032587D02*
X316010Y1032769D01*
X316541Y1032239D01*
X316358Y1031855D01*
X316217Y1031714D01*
X315485Y1032446D01*
X315627Y1032587D01*
G37*
G36*
G01X314908Y1051988D02*
X315291Y1052170D01*
X315822Y1051640D01*
X315640Y1051256D01*
X315498Y1051115D01*
X314766Y1051847D01*
X314908Y1051988D01*
G37*
G36*
G01X314526Y1051804D02*
X314142Y1051622D01*
X313612Y1052152D01*
X313794Y1052536D01*
X313936Y1052677D01*
X314667Y1051946D01*
X314526Y1051804D01*
G37*
G36*
G01X308261Y1058635D02*
X308645Y1058817D01*
X309175Y1058287D01*
X308993Y1057903D01*
X308851Y1057762D01*
X308120Y1058493D01*
X308261Y1058635D01*
G37*
G36*
G01X309541Y1056789D02*
X309157Y1056607D01*
X308627Y1057138D01*
X308809Y1057521D01*
X308950Y1057663D01*
X309682Y1056931D01*
X309541Y1056789D01*
G37*
G36*
G01X306599Y1060297D02*
X306983Y1060479D01*
X307513Y1059948D01*
X307331Y1059565D01*
X307190Y1059423D01*
X306458Y1060155D01*
X306599Y1060297D01*
G37*
G36*
G01X307879Y1058451D02*
X307496Y1058269D01*
X306965Y1058799D01*
X307147Y1059183D01*
X307289Y1059324D01*
X308021Y1058592D01*
X307879Y1058451D01*
G37*
G36*
G01X311584Y1055311D02*
X311968Y1055493D01*
X312498Y1054963D01*
X312316Y1054580D01*
X312175Y1054438D01*
X311443Y1055170D01*
X311584Y1055311D01*
G37*
G36*
G01X309923Y1056973D02*
X310306Y1057155D01*
X310837Y1056625D01*
X310655Y1056241D01*
X310513Y1056100D01*
X309781Y1056832D01*
X309923Y1056973D01*
G37*
G36*
G01X312864Y1053466D02*
X312481Y1053284D01*
X311950Y1053814D01*
X312132Y1054198D01*
X312274Y1054339D01*
X313006Y1053607D01*
X312864Y1053466D01*
G37*
G36*
G01X311203Y1055128D02*
X310819Y1054945D01*
X310289Y1055476D01*
X310471Y1055859D01*
X310612Y1056001D01*
X311344Y1055269D01*
X311203Y1055128D01*
G37*
G36*
G01X313246Y1053650D02*
X313630Y1053832D01*
X314160Y1053301D01*
X313978Y1052918D01*
X313837Y1052776D01*
X313105Y1053508D01*
X313246Y1053650D01*
G37*
G36*
G01X316188Y1050142D02*
X315804Y1049960D01*
X315274Y1050491D01*
X315456Y1050874D01*
X315597Y1051016D01*
X316329Y1050284D01*
X316188Y1050142D01*
G37*
G36*
G01X316570Y1050326D02*
X316953Y1050508D01*
X317483Y1049978D01*
X317301Y1049594D01*
X317160Y1049453D01*
X316428Y1050185D01*
X316570Y1050326D01*
G37*
G36*
G01X318231Y1048665D02*
X318615Y1048847D01*
X319145Y1048316D01*
X318963Y1047933D01*
X318822Y1047791D01*
X318090Y1048523D01*
X318231Y1048665D01*
G37*
G36*
G01X317849Y1048481D02*
X317466Y1048299D01*
X316935Y1048829D01*
X317118Y1049213D01*
X317259Y1049354D01*
X317991Y1048622D01*
X317849Y1048481D01*
G37*
G36*
G01X312828Y1050106D02*
X312444Y1049924D01*
X311914Y1050454D01*
X312096Y1050838D01*
X312237Y1050979D01*
X312969Y1050247D01*
X312828Y1050106D01*
G37*
G36*
G01X311548Y1051951D02*
X311931Y1052133D01*
X312462Y1051603D01*
X312279Y1051219D01*
X312138Y1051078D01*
X311406Y1051810D01*
X311548Y1051951D01*
G37*
G36*
G01X313209Y1050289D02*
X313593Y1050472D01*
X314123Y1049941D01*
X313941Y1049558D01*
X313800Y1049416D01*
X313068Y1050148D01*
X313209Y1050289D01*
G37*
G36*
G01X309886Y1053613D02*
X310270Y1053795D01*
X310800Y1053265D01*
X310618Y1052881D01*
X310476Y1052740D01*
X309745Y1053471D01*
X309886Y1053613D01*
G37*
G36*
G01X311166Y1051767D02*
X310782Y1051585D01*
X310252Y1052116D01*
X310434Y1052499D01*
X310575Y1052641D01*
X311307Y1051909D01*
X311166Y1051767D01*
G37*
G36*
G01X308224Y1055275D02*
X308608Y1055457D01*
X309138Y1054926D01*
X308956Y1054543D01*
X308815Y1054401D01*
X308083Y1055133D01*
X308224Y1055275D01*
G37*
G36*
G01X309504Y1053429D02*
X309120Y1053247D01*
X308590Y1053777D01*
X308772Y1054161D01*
X308914Y1054302D01*
X309646Y1053570D01*
X309504Y1053429D01*
G37*
G36*
G01X306563Y1056936D02*
X306946Y1057118D01*
X307476Y1056588D01*
X307294Y1056204D01*
X307153Y1056063D01*
X306421Y1056795D01*
X306563Y1056936D01*
G37*
G36*
G01X307842Y1055091D02*
X307459Y1054909D01*
X306928Y1055439D01*
X307111Y1055823D01*
X307252Y1055964D01*
X307984Y1055232D01*
X307842Y1055091D01*
G37*
G36*
G01X314489Y1048444D02*
X314106Y1048262D01*
X313575Y1048792D01*
X313757Y1049176D01*
X313899Y1049317D01*
X314631Y1048585D01*
X314489Y1048444D01*
G37*
G36*
G01X314871Y1048628D02*
X315255Y1048810D01*
X315785Y1048280D01*
X315603Y1047896D01*
X315461Y1047755D01*
X314730Y1048486D01*
X314871Y1048628D01*
G37*
G36*
G01X314059Y1051139D02*
X314442Y1051321D01*
X314973Y1050791D01*
X314791Y1050407D01*
X314649Y1050266D01*
X313917Y1050998D01*
X314059Y1051139D01*
G37*
G36*
G01X313677Y1050955D02*
X313293Y1050773D01*
X312763Y1051303D01*
X312945Y1051687D01*
X313087Y1051828D01*
X313818Y1051097D01*
X313677Y1050955D01*
G37*
G36*
G01X315339Y1049293D02*
X314955Y1049111D01*
X314425Y1049642D01*
X314607Y1050025D01*
X314748Y1050167D01*
X315480Y1049435D01*
X315339Y1049293D01*
G37*
G36*
G01X310354Y1054279D02*
X309970Y1054096D01*
X309440Y1054627D01*
X309622Y1055010D01*
X309763Y1055152D01*
X310495Y1054420D01*
X310354Y1054279D01*
G37*
G36*
G01X312397Y1052801D02*
X312781Y1052983D01*
X313311Y1052452D01*
X313129Y1052069D01*
X312988Y1051927D01*
X312256Y1052659D01*
X312397Y1052801D01*
G37*
G36*
G01X310735Y1054462D02*
X311119Y1054644D01*
X311649Y1054114D01*
X311467Y1053731D01*
X311326Y1053589D01*
X310594Y1054321D01*
X310735Y1054462D01*
G37*
G36*
G01X308692Y1055940D02*
X308308Y1055758D01*
X307778Y1056289D01*
X307960Y1056672D01*
X308101Y1056814D01*
X308833Y1056082D01*
X308692Y1055940D01*
G37*
G36*
G01X305750Y1059448D02*
X306134Y1059630D01*
X306664Y1059099D01*
X306482Y1058716D01*
X306341Y1058574D01*
X305609Y1059306D01*
X305750Y1059448D01*
G37*
G36*
G01X307412Y1057786D02*
X307796Y1057968D01*
X308326Y1057438D01*
X308144Y1057054D01*
X308002Y1056913D01*
X307271Y1057644D01*
X307412Y1057786D01*
G37*
G36*
G01X307030Y1057602D02*
X306647Y1057420D01*
X306116Y1057950D01*
X306298Y1058334D01*
X306440Y1058475D01*
X307172Y1057743D01*
X307030Y1057602D01*
G37*
G36*
G01X309074Y1056124D02*
X309457Y1056306D01*
X309988Y1055776D01*
X309806Y1055392D01*
X309664Y1055251D01*
X308932Y1055983D01*
X309074Y1056124D01*
G37*
G36*
G01X312015Y1052617D02*
X311632Y1052435D01*
X311101Y1052965D01*
X311283Y1053349D01*
X311425Y1053490D01*
X312157Y1052758D01*
X312015Y1052617D01*
G37*
G36*
G01X317000Y1047632D02*
X316617Y1047450D01*
X316086Y1047980D01*
X316269Y1048364D01*
X316410Y1048505D01*
X317142Y1047773D01*
X317000Y1047632D01*
G37*
G36*
G01X315721Y1049477D02*
X316104Y1049659D01*
X316634Y1049129D01*
X316452Y1048745D01*
X316311Y1048604D01*
X315579Y1049336D01*
X315721Y1049477D01*
G37*
G36*
G01X317382Y1047816D02*
X317766Y1047998D01*
X318296Y1047467D01*
X318114Y1047084D01*
X317973Y1046942D01*
X317241Y1047674D01*
X317382Y1047816D01*
G37*
G36*
G01X311979Y1049257D02*
X311595Y1049075D01*
X311065Y1049605D01*
X311247Y1049989D01*
X311388Y1050130D01*
X312120Y1049398D01*
X311979Y1049257D01*
G37*
G36*
G01X310699Y1051102D02*
X311082Y1051284D01*
X311613Y1050754D01*
X311430Y1050370D01*
X311289Y1050229D01*
X310557Y1050961D01*
X310699Y1051102D01*
G37*
G36*
G01X310317Y1050918D02*
X309933Y1050736D01*
X309403Y1051267D01*
X309585Y1051650D01*
X309726Y1051792D01*
X310458Y1051060D01*
X310317Y1050918D01*
G37*
G36*
G01X309037Y1052764D02*
X309421Y1052946D01*
X309951Y1052416D01*
X309769Y1052032D01*
X309627Y1051891D01*
X308896Y1052622D01*
X309037Y1052764D01*
G37*
G36*
G01X308655Y1052580D02*
X308271Y1052398D01*
X307741Y1052928D01*
X307923Y1053312D01*
X308065Y1053453D01*
X308797Y1052721D01*
X308655Y1052580D01*
G37*
G36*
G01X306993Y1054242D02*
X306610Y1054060D01*
X306079Y1054590D01*
X306262Y1054974D01*
X306403Y1055115D01*
X307135Y1054383D01*
X306993Y1054242D01*
G37*
G36*
G01X307375Y1054426D02*
X307759Y1054608D01*
X308289Y1054077D01*
X308107Y1053694D01*
X307966Y1053552D01*
X307234Y1054284D01*
X307375Y1054426D01*
G37*
G36*
G01X305714Y1056087D02*
X306097Y1056269D01*
X306627Y1055739D01*
X306445Y1055355D01*
X306304Y1055214D01*
X305572Y1055946D01*
X305714Y1056087D01*
G37*
G36*
G01X313640Y1047595D02*
X313257Y1047413D01*
X312726Y1047943D01*
X312908Y1048327D01*
X313050Y1048468D01*
X313782Y1047736D01*
X313640Y1047595D01*
G37*
G36*
G01X312360Y1049440D02*
X312744Y1049623D01*
X313274Y1049092D01*
X313092Y1048709D01*
X312951Y1048567D01*
X312219Y1049299D01*
X312360Y1049440D01*
G37*
G36*
G01X318982Y1061685D02*
X318598Y1061503D01*
X318068Y1062033D01*
X318250Y1062417D01*
X318391Y1062559D01*
X319123Y1061827D01*
X318982Y1061685D01*
G37*
G36*
G01X317702Y1063531D02*
X318086Y1063713D01*
X318616Y1063183D01*
X318434Y1062799D01*
X318292Y1062658D01*
X317561Y1063389D01*
X317702Y1063531D01*
G37*
G36*
G01X317320Y1063347D02*
X316937Y1063165D01*
X316406Y1063695D01*
X316588Y1064079D01*
X316730Y1064220D01*
X317462Y1063488D01*
X317320Y1063347D01*
G37*
G36*
G01X319364Y1061869D02*
X319747Y1062051D01*
X320278Y1061521D01*
X320096Y1061137D01*
X319954Y1060996D01*
X319222Y1061728D01*
X319364Y1061869D01*
G37*
G36*
G01X322305Y1058362D02*
X321922Y1058180D01*
X321391Y1058710D01*
X321573Y1059094D01*
X321715Y1059235D01*
X322447Y1058503D01*
X322305Y1058362D01*
G37*
G36*
G01X320644Y1060024D02*
X320260Y1059841D01*
X319730Y1060372D01*
X319912Y1060755D01*
X320053Y1060897D01*
X320785Y1060165D01*
X320644Y1060024D01*
G37*
G36*
G01X321025Y1060207D02*
X321409Y1060389D01*
X321939Y1059859D01*
X321757Y1059476D01*
X321616Y1059334D01*
X320884Y1060066D01*
X321025Y1060207D01*
G37*
G36*
G01X314341Y1063493D02*
X314724Y1063675D01*
X315255Y1063145D01*
X315073Y1062761D01*
X314931Y1062620D01*
X314199Y1063352D01*
X314341Y1063493D01*
G37*
G36*
G01X313959Y1063309D02*
X313575Y1063127D01*
X313045Y1063657D01*
X313227Y1064041D01*
X313369Y1064182D01*
X314100Y1063451D01*
X313959Y1063309D01*
G37*
G36*
G01X315621Y1061647D02*
X315237Y1061465D01*
X314707Y1061996D01*
X314889Y1062379D01*
X315030Y1062521D01*
X315762Y1061789D01*
X315621Y1061647D01*
G37*
G36*
G01X316003Y1061831D02*
X316386Y1062013D01*
X316916Y1061483D01*
X316734Y1061099D01*
X316593Y1060958D01*
X315861Y1061690D01*
X316003Y1061831D01*
G37*
G36*
G01X317664Y1060170D02*
X318048Y1060352D01*
X318578Y1059821D01*
X318396Y1059438D01*
X318255Y1059296D01*
X317523Y1060028D01*
X317664Y1060170D01*
G37*
G36*
G01X317282Y1059986D02*
X316899Y1059804D01*
X316368Y1060334D01*
X316551Y1060718D01*
X316692Y1060859D01*
X317424Y1060127D01*
X317282Y1059986D01*
G37*
G36*
G01X318944Y1058324D02*
X318561Y1058142D01*
X318030Y1058672D01*
X318212Y1059056D01*
X318354Y1059197D01*
X319086Y1058465D01*
X318944Y1058324D01*
G37*
G36*
G01X319326Y1058508D02*
X319710Y1058690D01*
X320240Y1058160D01*
X320058Y1057776D01*
X319916Y1057635D01*
X319185Y1058366D01*
X319326Y1058508D01*
G37*
G36*
G01X320606Y1056662D02*
X320222Y1056480D01*
X319692Y1057011D01*
X319874Y1057394D01*
X320015Y1057536D01*
X320747Y1056804D01*
X320606Y1056662D01*
G37*
G36*
G01X320988Y1056846D02*
X321371Y1057028D01*
X321902Y1056498D01*
X321720Y1056114D01*
X321578Y1055973D01*
X320846Y1056705D01*
X320988Y1056846D01*
G37*
G36*
G01X322268Y1055001D02*
X321884Y1054819D01*
X321354Y1055349D01*
X321536Y1055733D01*
X321677Y1055874D01*
X322409Y1055142D01*
X322268Y1055001D01*
G37*
G36*
G01X316471Y1062498D02*
X316088Y1062316D01*
X315557Y1062846D01*
X315739Y1063230D01*
X315881Y1063371D01*
X316613Y1062639D01*
X316471Y1062498D01*
G37*
G36*
G01X316853Y1062682D02*
X317237Y1062864D01*
X317767Y1062334D01*
X317585Y1061950D01*
X317443Y1061809D01*
X316712Y1062540D01*
X316853Y1062682D01*
G37*
G36*
G01X318133Y1060836D02*
X317749Y1060654D01*
X317219Y1061184D01*
X317401Y1061568D01*
X317542Y1061710D01*
X318274Y1060978D01*
X318133Y1060836D01*
G37*
G36*
G01X320176Y1059358D02*
X320560Y1059540D01*
X321090Y1059010D01*
X320908Y1058627D01*
X320767Y1058485D01*
X320035Y1059217D01*
X320176Y1059358D01*
G37*
G36*
G01X319795Y1059175D02*
X319411Y1058992D01*
X318881Y1059523D01*
X319063Y1059906D01*
X319204Y1060048D01*
X319936Y1059316D01*
X319795Y1059175D01*
G37*
G36*
G01X321456Y1057513D02*
X321073Y1057331D01*
X320542Y1057861D01*
X320724Y1058245D01*
X320866Y1058386D01*
X321598Y1057654D01*
X321456Y1057513D01*
G37*
G36*
G01X318515Y1061020D02*
X318898Y1061202D01*
X319429Y1060672D01*
X319247Y1060288D01*
X319105Y1060147D01*
X318373Y1060879D01*
X318515Y1061020D01*
G37*
G36*
G01X314771Y1060798D02*
X314388Y1060616D01*
X313857Y1061146D01*
X314039Y1061530D01*
X314181Y1061671D01*
X314913Y1060939D01*
X314771Y1060798D01*
G37*
G36*
G01X313491Y1062643D02*
X313875Y1062826D01*
X314405Y1062295D01*
X314223Y1061912D01*
X314082Y1061770D01*
X313350Y1062502D01*
X313491Y1062643D01*
G37*
G36*
G01X313110Y1062460D02*
X312726Y1062278D01*
X312196Y1062808D01*
X312378Y1063192D01*
X312519Y1063333D01*
X313251Y1062601D01*
X313110Y1062460D01*
G37*
G36*
G01X315153Y1060982D02*
X315537Y1061164D01*
X316067Y1060634D01*
X315885Y1060250D01*
X315743Y1060109D01*
X315012Y1060840D01*
X315153Y1060982D01*
G37*
G36*
G01X316433Y1059136D02*
X316049Y1058954D01*
X315519Y1059484D01*
X315701Y1059868D01*
X315842Y1060010D01*
X316574Y1059278D01*
X316433Y1059136D01*
G37*
G36*
G01X316815Y1059320D02*
X317198Y1059502D01*
X317729Y1058972D01*
X317547Y1058588D01*
X317405Y1058447D01*
X316673Y1059179D01*
X316815Y1059320D01*
G37*
G36*
G01X318095Y1057475D02*
X317711Y1057292D01*
X317181Y1057823D01*
X317363Y1058206D01*
X317504Y1058348D01*
X318236Y1057616D01*
X318095Y1057475D01*
G37*
G36*
G01X319756Y1055813D02*
X319373Y1055631D01*
X318842Y1056161D01*
X319024Y1056545D01*
X319166Y1056686D01*
X319898Y1055954D01*
X319756Y1055813D01*
G37*
G36*
G01X321418Y1054151D02*
X321034Y1053969D01*
X320504Y1054499D01*
X320686Y1054883D01*
X320828Y1055024D01*
X321559Y1054293D01*
X321418Y1054151D01*
G37*
G36*
G01X320138Y1055997D02*
X320522Y1056179D01*
X321052Y1055648D01*
X320870Y1055265D01*
X320729Y1055123D01*
X319997Y1055855D01*
X320138Y1055997D01*
G37*
G36*
G01X318476Y1057658D02*
X318860Y1057840D01*
X319390Y1057310D01*
X319208Y1056927D01*
X319067Y1056785D01*
X318335Y1057517D01*
X318476Y1057658D01*
G37*
G36*
G01X320921Y1078529D02*
X320537Y1078346D01*
X320007Y1078877D01*
X320189Y1079260D01*
X320330Y1079402D01*
X321062Y1078670D01*
X320921Y1078529D01*
G37*
G36*
G01X321302Y1078712D02*
X321686Y1078895D01*
X322216Y1078364D01*
X322034Y1077981D01*
X321893Y1077839D01*
X321161Y1078571D01*
X321302Y1078712D01*
G37*
G36*
G01X321770Y1079378D02*
X321386Y1079196D01*
X320856Y1079726D01*
X321038Y1080110D01*
X321179Y1080251D01*
X321911Y1079519D01*
X321770Y1079378D01*
G37*
G36*
G01X318409Y1079341D02*
X318026Y1079159D01*
X317496Y1079689D01*
X317678Y1080072D01*
X317819Y1080214D01*
X318551Y1079482D01*
X318409Y1079341D01*
G37*
G36*
G01X320071Y1077679D02*
X319688Y1077497D01*
X319157Y1078027D01*
X319339Y1078411D01*
X319481Y1078552D01*
X320213Y1077820D01*
X320071Y1077679D01*
G37*
G36*
G01X320453Y1077863D02*
X320837Y1078045D01*
X321367Y1077515D01*
X321185Y1077131D01*
X321044Y1076990D01*
X320312Y1077721D01*
X320453Y1077863D01*
G37*
G36*
G01X318791Y1079524D02*
X319175Y1079707D01*
X319705Y1079176D01*
X319523Y1078793D01*
X319382Y1078651D01*
X318650Y1079383D01*
X318791Y1079524D01*
G37*
G36*
G01X321733Y1076017D02*
X321350Y1075835D01*
X320819Y1076366D01*
X321001Y1076749D01*
X321143Y1076891D01*
X321875Y1076159D01*
X321733Y1076017D01*
G37*
G36*
G01X314907Y1079916D02*
X315291Y1080098D01*
X315821Y1079568D01*
X315639Y1079184D01*
X315497Y1079043D01*
X314766Y1079774D01*
X314907Y1079916D01*
G37*
G36*
G01X316187Y1078070D02*
X315803Y1077888D01*
X315273Y1078419D01*
X315455Y1078802D01*
X315596Y1078944D01*
X316328Y1078212D01*
X316187Y1078070D01*
G37*
G36*
G01X316569Y1078254D02*
X316952Y1078436D01*
X317483Y1077906D01*
X317301Y1077522D01*
X317159Y1077381D01*
X316427Y1078113D01*
X316569Y1078254D01*
G37*
G36*
G01X317849Y1076409D02*
X317465Y1076226D01*
X316935Y1076757D01*
X317117Y1077140D01*
X317258Y1077282D01*
X317990Y1076550D01*
X317849Y1076409D01*
G37*
G36*
G01X318230Y1076592D02*
X318614Y1076774D01*
X319144Y1076244D01*
X318962Y1075861D01*
X318821Y1075719D01*
X318089Y1076451D01*
X318230Y1076592D01*
G37*
G36*
G01X319892Y1074931D02*
X320276Y1075113D01*
X320806Y1074582D01*
X320624Y1074199D01*
X320483Y1074057D01*
X319751Y1074789D01*
X319892Y1074931D01*
G37*
G36*
G01X321172Y1073085D02*
X320788Y1072903D01*
X320258Y1073433D01*
X320440Y1073817D01*
X320582Y1073958D01*
X321313Y1073227D01*
X321172Y1073085D01*
G37*
G36*
G01X319510Y1074747D02*
X319127Y1074565D01*
X318596Y1075095D01*
X318778Y1075479D01*
X318920Y1075620D01*
X319652Y1074888D01*
X319510Y1074747D01*
G37*
G36*
G01X321554Y1073269D02*
X321937Y1073451D01*
X322468Y1072921D01*
X322286Y1072537D01*
X322144Y1072396D01*
X321412Y1073128D01*
X321554Y1073269D01*
G37*
G36*
G01X311547Y1079880D02*
X311931Y1080062D01*
X312461Y1079531D01*
X312279Y1079148D01*
X312138Y1079006D01*
X311406Y1079738D01*
X311547Y1079880D01*
G37*
G36*
G01X312827Y1078034D02*
X312444Y1077852D01*
X311913Y1078382D01*
X312095Y1078766D01*
X312237Y1078907D01*
X312969Y1078175D01*
X312827Y1078034D01*
G37*
G36*
G01X313209Y1078218D02*
X313593Y1078400D01*
X314123Y1077870D01*
X313941Y1077486D01*
X313799Y1077345D01*
X313068Y1078076D01*
X313209Y1078218D01*
G37*
G36*
G01X314489Y1076372D02*
X314105Y1076190D01*
X313575Y1076721D01*
X313757Y1077104D01*
X313898Y1077246D01*
X314630Y1076514D01*
X314489Y1076372D01*
G37*
G36*
G01X314871Y1076556D02*
X315254Y1076738D01*
X315785Y1076208D01*
X315603Y1075824D01*
X315461Y1075683D01*
X314729Y1076415D01*
X314871Y1076556D01*
G37*
G36*
G01X316151Y1074711D02*
X315767Y1074528D01*
X315237Y1075059D01*
X315419Y1075442D01*
X315560Y1075584D01*
X316292Y1074852D01*
X316151Y1074711D01*
G37*
G36*
G01X316532Y1074894D02*
X316916Y1075076D01*
X317446Y1074546D01*
X317264Y1074163D01*
X317123Y1074021D01*
X316391Y1074753D01*
X316532Y1074894D01*
G37*
G36*
G01X317812Y1073049D02*
X317429Y1072867D01*
X316898Y1073397D01*
X317080Y1073781D01*
X317222Y1073922D01*
X317954Y1073190D01*
X317812Y1073049D01*
G37*
G36*
G01X318194Y1073233D02*
X318578Y1073415D01*
X319108Y1072884D01*
X318926Y1072501D01*
X318785Y1072359D01*
X318053Y1073091D01*
X318194Y1073233D01*
G37*
G36*
G01X319856Y1071571D02*
X320239Y1071753D01*
X320770Y1071223D01*
X320588Y1070839D01*
X320446Y1070698D01*
X319714Y1071430D01*
X319856Y1071571D01*
G37*
G36*
G01X321136Y1069725D02*
X320752Y1069543D01*
X320222Y1070074D01*
X320404Y1070457D01*
X320545Y1070599D01*
X321277Y1069867D01*
X321136Y1069725D01*
G37*
G36*
G01X319474Y1071387D02*
X319090Y1071205D01*
X318560Y1071735D01*
X318742Y1072119D01*
X318884Y1072260D01*
X319615Y1071529D01*
X319474Y1071387D01*
G37*
G36*
G01X321518Y1069909D02*
X321901Y1070091D01*
X322431Y1069561D01*
X322249Y1069177D01*
X322108Y1069036D01*
X321376Y1069768D01*
X321518Y1069909D01*
G37*
G36*
G01X313676Y1078883D02*
X313293Y1078701D01*
X312762Y1079231D01*
X312944Y1079615D01*
X313086Y1079756D01*
X313818Y1079024D01*
X313676Y1078883D01*
G37*
G36*
G01X315338Y1077221D02*
X314954Y1077039D01*
X314424Y1077570D01*
X314606Y1077953D01*
X314747Y1078095D01*
X315479Y1077363D01*
X315338Y1077221D01*
G37*
G36*
G01X314058Y1079067D02*
X314442Y1079249D01*
X314972Y1078719D01*
X314790Y1078335D01*
X314648Y1078194D01*
X313917Y1078925D01*
X314058Y1079067D01*
G37*
G36*
G01X315720Y1077405D02*
X316103Y1077587D01*
X316634Y1077057D01*
X316452Y1076673D01*
X316310Y1076532D01*
X315578Y1077264D01*
X315720Y1077405D01*
G37*
G36*
G01X317000Y1075560D02*
X316616Y1075377D01*
X316086Y1075908D01*
X316268Y1076291D01*
X316409Y1076433D01*
X317141Y1075701D01*
X317000Y1075560D01*
G37*
G36*
G01X317381Y1075743D02*
X317765Y1075925D01*
X318295Y1075395D01*
X318113Y1075012D01*
X317972Y1074870D01*
X317240Y1075602D01*
X317381Y1075743D01*
G37*
G36*
G01X318661Y1073898D02*
X318278Y1073716D01*
X317747Y1074246D01*
X317929Y1074630D01*
X318071Y1074771D01*
X318803Y1074039D01*
X318661Y1073898D01*
G37*
G36*
G01X319043Y1074082D02*
X319427Y1074264D01*
X319957Y1073733D01*
X319775Y1073350D01*
X319634Y1073208D01*
X318902Y1073940D01*
X319043Y1074082D01*
G37*
G36*
G01X321985Y1070574D02*
X321601Y1070392D01*
X321071Y1070923D01*
X321253Y1071306D01*
X321394Y1071448D01*
X322126Y1070716D01*
X321985Y1070574D01*
G37*
G36*
G01X320705Y1072420D02*
X321088Y1072602D01*
X321619Y1072072D01*
X321437Y1071688D01*
X321295Y1071547D01*
X320563Y1072279D01*
X320705Y1072420D01*
G37*
G36*
G01X320323Y1072236D02*
X319939Y1072054D01*
X319409Y1072584D01*
X319591Y1072968D01*
X319733Y1073109D01*
X320464Y1072378D01*
X320323Y1072236D01*
G37*
G36*
G01X311977Y1077184D02*
X311594Y1077002D01*
X311063Y1077532D01*
X311245Y1077916D01*
X311387Y1078057D01*
X312119Y1077325D01*
X311977Y1077184D01*
G37*
G36*
G01X310697Y1079030D02*
X311081Y1079212D01*
X311611Y1078681D01*
X311429Y1078298D01*
X311288Y1078156D01*
X310556Y1078888D01*
X310697Y1079030D01*
G37*
G36*
G01X312359Y1077368D02*
X312743Y1077550D01*
X313273Y1077020D01*
X313091Y1076636D01*
X312949Y1076495D01*
X312218Y1077226D01*
X312359Y1077368D01*
G37*
G36*
G01X310316Y1078846D02*
X309932Y1078664D01*
X309402Y1079194D01*
X309584Y1079578D01*
X309725Y1079719D01*
X310457Y1078987D01*
X310316Y1078846D01*
G37*
G36*
G01X313639Y1075522D02*
X313255Y1075340D01*
X312725Y1075871D01*
X312907Y1076254D01*
X313048Y1076396D01*
X313780Y1075664D01*
X313639Y1075522D01*
G37*
G36*
G01X315301Y1073861D02*
X314917Y1073678D01*
X314387Y1074209D01*
X314569Y1074592D01*
X314710Y1074734D01*
X315442Y1074002D01*
X315301Y1073861D01*
G37*
G36*
G01X314021Y1075706D02*
X314404Y1075888D01*
X314935Y1075358D01*
X314753Y1074974D01*
X314611Y1074833D01*
X313879Y1075565D01*
X314021Y1075706D01*
G37*
G36*
G01X315682Y1074044D02*
X316066Y1074226D01*
X316596Y1073696D01*
X316414Y1073313D01*
X316273Y1073171D01*
X315541Y1073903D01*
X315682Y1074044D01*
G37*
G36*
G01X316962Y1072199D02*
X316579Y1072017D01*
X316048Y1072547D01*
X316230Y1072931D01*
X316372Y1073072D01*
X317104Y1072340D01*
X316962Y1072199D01*
G37*
G36*
G01X318624Y1070537D02*
X318240Y1070355D01*
X317710Y1070885D01*
X317892Y1071269D01*
X318034Y1071410D01*
X318765Y1070679D01*
X318624Y1070537D01*
G37*
G36*
G01X317344Y1072383D02*
X317728Y1072565D01*
X318258Y1072034D01*
X318076Y1071651D01*
X317935Y1071509D01*
X317203Y1072241D01*
X317344Y1072383D01*
G37*
G36*
G01X321947Y1067214D02*
X321564Y1067032D01*
X321033Y1067562D01*
X321216Y1067946D01*
X321357Y1068087D01*
X322089Y1067355D01*
X321947Y1067214D01*
G37*
G36*
G01X320286Y1068875D02*
X319902Y1068693D01*
X319372Y1069224D01*
X319554Y1069607D01*
X319695Y1069749D01*
X320427Y1069017D01*
X320286Y1068875D01*
G37*
G36*
G01X319006Y1070721D02*
X319389Y1070903D01*
X319920Y1070373D01*
X319738Y1069989D01*
X319596Y1069848D01*
X318864Y1070580D01*
X319006Y1070721D01*
G37*
G36*
G01X320668Y1069059D02*
X321051Y1069241D01*
X321581Y1068711D01*
X321399Y1068327D01*
X321258Y1068186D01*
X320526Y1068918D01*
X320668Y1069059D01*
G37*
G36*
G01X312717Y1068516D02*
X313101Y1068698D01*
X313631Y1068168D01*
X313449Y1067784D01*
X313307Y1067643D01*
X312576Y1068374D01*
X312717Y1068516D01*
G37*
G36*
G01X314379Y1066854D02*
X314762Y1067036D01*
X315293Y1066506D01*
X315110Y1066122D01*
X314969Y1065981D01*
X314237Y1066713D01*
X314379Y1066854D01*
G37*
G36*
G01X315659Y1065009D02*
X315275Y1064827D01*
X314745Y1065357D01*
X314927Y1065741D01*
X315068Y1065882D01*
X315800Y1065150D01*
X315659Y1065009D01*
G37*
G36*
G01X313997Y1066670D02*
X313613Y1066488D01*
X313083Y1067019D01*
X313265Y1067402D01*
X313406Y1067544D01*
X314138Y1066812D01*
X313997Y1066670D01*
G37*
G36*
G01X306070Y1075163D02*
X306454Y1075345D01*
X306984Y1074814D01*
X306802Y1074431D01*
X306661Y1074289D01*
X305929Y1075021D01*
X306070Y1075163D01*
G37*
G36*
G01X307350Y1073317D02*
X306966Y1073135D01*
X306436Y1073665D01*
X306618Y1074049D01*
X306760Y1074190D01*
X307491Y1073459D01*
X307350Y1073317D01*
G37*
G36*
G01X311055Y1070178D02*
X311439Y1070360D01*
X311969Y1069829D01*
X311787Y1069446D01*
X311646Y1069304D01*
X310914Y1070036D01*
X311055Y1070178D01*
G37*
G36*
G01X309394Y1071839D02*
X309777Y1072021D01*
X310307Y1071491D01*
X310125Y1071107D01*
X309984Y1070966D01*
X309252Y1071698D01*
X309394Y1071839D01*
G37*
G36*
G01X310673Y1069994D02*
X310290Y1069812D01*
X309759Y1070342D01*
X309942Y1070726D01*
X310083Y1070867D01*
X310815Y1070135D01*
X310673Y1069994D01*
G37*
G36*
G01X307732Y1073501D02*
X308115Y1073683D01*
X308646Y1073153D01*
X308464Y1072769D01*
X308322Y1072628D01*
X307590Y1073360D01*
X307732Y1073501D01*
G37*
G36*
G01X309012Y1071655D02*
X308628Y1071473D01*
X308098Y1072004D01*
X308280Y1072387D01*
X308421Y1072529D01*
X309153Y1071797D01*
X309012Y1071655D01*
G37*
G36*
G01X312335Y1068332D02*
X311951Y1068150D01*
X311421Y1068680D01*
X311603Y1069064D01*
X311745Y1069205D01*
X312477Y1068473D01*
X312335Y1068332D01*
G37*
G36*
G01X316040Y1065192D02*
X316424Y1065375D01*
X316954Y1064844D01*
X316772Y1064461D01*
X316631Y1064319D01*
X315899Y1065051D01*
X316040Y1065192D01*
G37*
G36*
G01X309356Y1068478D02*
X309739Y1068660D01*
X310270Y1068130D01*
X310088Y1067746D01*
X309946Y1067605D01*
X309214Y1068337D01*
X309356Y1068478D01*
G37*
G36*
G01X311017Y1066816D02*
X311401Y1066998D01*
X311931Y1066468D01*
X311749Y1066085D01*
X311608Y1065943D01*
X310876Y1066675D01*
X311017Y1066816D01*
G37*
G36*
G01X312297Y1064971D02*
X311914Y1064789D01*
X311383Y1065319D01*
X311565Y1065703D01*
X311707Y1065844D01*
X312439Y1065112D01*
X312297Y1064971D01*
G37*
G36*
G01X312679Y1065155D02*
X313063Y1065337D01*
X313593Y1064806D01*
X313411Y1064423D01*
X313270Y1064281D01*
X312538Y1065013D01*
X312679Y1065155D01*
G37*
G36*
G01X310636Y1066633D02*
X310252Y1066450D01*
X309722Y1066981D01*
X309904Y1067364D01*
X310045Y1067506D01*
X310777Y1066774D01*
X310636Y1066633D01*
G37*
G36*
G01X307694Y1070140D02*
X308078Y1070322D01*
X308608Y1069792D01*
X308426Y1069408D01*
X308284Y1069267D01*
X307553Y1069998D01*
X307694Y1070140D01*
G37*
G36*
G01X306032Y1071802D02*
X306416Y1071984D01*
X306946Y1071453D01*
X306764Y1071070D01*
X306623Y1070928D01*
X305891Y1071660D01*
X306032Y1071802D01*
G37*
G36*
G01X307312Y1069956D02*
X306929Y1069774D01*
X306398Y1070304D01*
X306580Y1070688D01*
X306722Y1070829D01*
X307454Y1070097D01*
X307312Y1069956D01*
G37*
G36*
G01X308974Y1068294D02*
X308590Y1068112D01*
X308060Y1068643D01*
X308242Y1069026D01*
X308383Y1069168D01*
X309115Y1068436D01*
X308974Y1068294D01*
G37*
G36*
G01X313530Y1066005D02*
X313913Y1066187D01*
X314444Y1065657D01*
X314261Y1065273D01*
X314120Y1065132D01*
X313388Y1065864D01*
X313530Y1066005D01*
G37*
G36*
G01X314810Y1064160D02*
X314426Y1063978D01*
X313896Y1064508D01*
X314078Y1064892D01*
X314219Y1065033D01*
X314951Y1064301D01*
X314810Y1064160D01*
G37*
G36*
G01X313148Y1065821D02*
X312764Y1065639D01*
X312234Y1066170D01*
X312416Y1066553D01*
X312557Y1066695D01*
X313289Y1065963D01*
X313148Y1065821D01*
G37*
G36*
G01X311868Y1067667D02*
X312252Y1067849D01*
X312782Y1067319D01*
X312600Y1066935D01*
X312458Y1066794D01*
X311727Y1067525D01*
X311868Y1067667D01*
G37*
G36*
G01X311486Y1067483D02*
X311102Y1067301D01*
X310572Y1067831D01*
X310754Y1068215D01*
X310896Y1068356D01*
X311628Y1067624D01*
X311486Y1067483D01*
G37*
G36*
G01X308545Y1070990D02*
X308928Y1071172D01*
X309458Y1070642D01*
X309276Y1070258D01*
X309135Y1070117D01*
X308403Y1070849D01*
X308545Y1070990D01*
G37*
G36*
G01X309824Y1069145D02*
X309441Y1068963D01*
X308910Y1069493D01*
X309093Y1069877D01*
X309234Y1070018D01*
X309966Y1069286D01*
X309824Y1069145D01*
G37*
G36*
G01X308163Y1070806D02*
X307779Y1070624D01*
X307249Y1071155D01*
X307431Y1071538D01*
X307572Y1071680D01*
X308304Y1070948D01*
X308163Y1070806D01*
G37*
G36*
G01X306883Y1072652D02*
X307266Y1072834D01*
X307797Y1072304D01*
X307615Y1071920D01*
X307473Y1071779D01*
X306741Y1072511D01*
X306883Y1072652D01*
G37*
G36*
G01X306501Y1072468D02*
X306117Y1072286D01*
X305587Y1072816D01*
X305769Y1073200D01*
X305911Y1073341D01*
X306642Y1072610D01*
X306501Y1072468D01*
G37*
G36*
G01X310206Y1069329D02*
X310590Y1069511D01*
X311120Y1068980D01*
X310938Y1068597D01*
X310797Y1068455D01*
X310065Y1069187D01*
X310206Y1069329D01*
G37*
G36*
G01X315191Y1064343D02*
X315575Y1064526D01*
X316105Y1063995D01*
X315923Y1063612D01*
X315782Y1063470D01*
X315050Y1064202D01*
X315191Y1064343D01*
G37*
G36*
G01X311448Y1064121D02*
X311064Y1063939D01*
X310534Y1064470D01*
X310716Y1064853D01*
X310857Y1064995D01*
X311589Y1064263D01*
X311448Y1064121D01*
G37*
G36*
G01X309786Y1065783D02*
X309402Y1065601D01*
X308872Y1066131D01*
X309054Y1066515D01*
X309196Y1066656D01*
X309928Y1065924D01*
X309786Y1065783D01*
G37*
G36*
G01X311830Y1064305D02*
X312213Y1064487D01*
X312744Y1063957D01*
X312561Y1063573D01*
X312420Y1063432D01*
X311688Y1064164D01*
X311830Y1064305D01*
G37*
G36*
G01X310168Y1065967D02*
X310552Y1066149D01*
X311082Y1065619D01*
X310900Y1065235D01*
X310758Y1065094D01*
X310027Y1065825D01*
X310168Y1065967D01*
G37*
G36*
G01X308124Y1067445D02*
X307741Y1067263D01*
X307210Y1067793D01*
X307393Y1068177D01*
X307534Y1068318D01*
X308266Y1067586D01*
X308124Y1067445D01*
G37*
G36*
G01X308506Y1067629D02*
X308890Y1067811D01*
X309420Y1067280D01*
X309238Y1066897D01*
X309097Y1066755D01*
X308365Y1067487D01*
X308506Y1067629D01*
G37*
G36*
G01X306463Y1069106D02*
X306079Y1068924D01*
X305549Y1069455D01*
X305731Y1069838D01*
X305872Y1069980D01*
X306604Y1069248D01*
X306463Y1069106D01*
G37*
G36*
G01X306845Y1069290D02*
X307228Y1069472D01*
X307758Y1068942D01*
X307576Y1068558D01*
X307435Y1068417D01*
X306703Y1069149D01*
X306845Y1069290D01*
G37*
G36*
G01X319768Y1094958D02*
X320188Y1095021D01*
X320543Y1094360D01*
X320257Y1094046D01*
X320081Y1093951D01*
X319592Y1094863D01*
X319768Y1094958D01*
G37*
G36*
G01X322175Y1090881D02*
X321792Y1090699D01*
X321261Y1091229D01*
X321443Y1091613D01*
X321585Y1091754D01*
X322317Y1091022D01*
X322175Y1090881D01*
G37*
G36*
G01X320824Y1095535D02*
X321243Y1095598D01*
X321597Y1094937D01*
X321312Y1094622D01*
X321136Y1094528D01*
X320647Y1095440D01*
X320824Y1095535D01*
G37*
G36*
G01X318291Y1094325D02*
X317871Y1094261D01*
X317517Y1094923D01*
X317802Y1095237D01*
X317978Y1095331D01*
X318467Y1094419D01*
X318291Y1094325D01*
G37*
G36*
G01X321320Y1090025D02*
X320936Y1089843D01*
X320406Y1090374D01*
X320588Y1090757D01*
X320729Y1090899D01*
X321461Y1090167D01*
X321320Y1090025D01*
G37*
G36*
G01X319400Y1092253D02*
X318980Y1092190D01*
X318626Y1092851D01*
X318912Y1093165D01*
X319088Y1093260D01*
X319577Y1092348D01*
X319400Y1092253D01*
G37*
G36*
G01X321702Y1090209D02*
X322085Y1090391D01*
X322616Y1089861D01*
X322433Y1089477D01*
X322292Y1089336D01*
X321560Y1090068D01*
X321702Y1090209D01*
G37*
G36*
G01X318709Y1094390D02*
X319129Y1094453D01*
X319483Y1093792D01*
X319198Y1093478D01*
X319022Y1093383D01*
X318533Y1094296D01*
X318709Y1094390D01*
G37*
G36*
G01X311401Y1095502D02*
X310981Y1095564D01*
X310834Y1096299D01*
X311198Y1096517D01*
X311394Y1096557D01*
X311597Y1095542D01*
X311401Y1095502D01*
G37*
G36*
G01X313414Y1091551D02*
X313833Y1091615D01*
X314187Y1090953D01*
X313902Y1090639D01*
X313725Y1090545D01*
X313237Y1091457D01*
X313414Y1091551D01*
G37*
G36*
G01X312995Y1091486D02*
X312575Y1091423D01*
X312221Y1092084D01*
X312507Y1092399D01*
X312683Y1092493D01*
X313171Y1091581D01*
X312995Y1091486D01*
G37*
G36*
G01X314103Y1089414D02*
X313683Y1089351D01*
X313330Y1090012D01*
X313615Y1090327D01*
X313792Y1090421D01*
X314280Y1089509D01*
X314103Y1089414D01*
G37*
G36*
G01X316356Y1087060D02*
X316740Y1087242D01*
X317270Y1086712D01*
X317088Y1086328D01*
X316947Y1086187D01*
X316215Y1086919D01*
X316356Y1087060D01*
G37*
G36*
G01X317636Y1085215D02*
X317253Y1085033D01*
X316722Y1085563D01*
X316904Y1085946D01*
X317046Y1086088D01*
X317778Y1085356D01*
X317636Y1085215D01*
G37*
G36*
G01X318018Y1085399D02*
X318402Y1085581D01*
X318932Y1085050D01*
X318750Y1084667D01*
X318608Y1084525D01*
X317877Y1085257D01*
X318018Y1085399D01*
G37*
G36*
G01X321342Y1082076D02*
X321725Y1082258D01*
X322256Y1081727D01*
X322074Y1081344D01*
X321932Y1081202D01*
X321200Y1081934D01*
X321342Y1082076D01*
G37*
G36*
G01X319298Y1083553D02*
X318914Y1083371D01*
X318384Y1083901D01*
X318566Y1084285D01*
X318708Y1084426D01*
X319439Y1083695D01*
X319298Y1083553D01*
G37*
G36*
G01X319680Y1083737D02*
X320063Y1083919D01*
X320594Y1083389D01*
X320412Y1083005D01*
X320270Y1082864D01*
X319538Y1083596D01*
X319680Y1083737D01*
G37*
G36*
G01X320960Y1081892D02*
X320576Y1081710D01*
X320046Y1082240D01*
X320228Y1082623D01*
X320369Y1082765D01*
X321101Y1082033D01*
X320960Y1081892D01*
G37*
G36*
G01X314655Y1085358D02*
X315038Y1085541D01*
X315569Y1085010D01*
X315387Y1084627D01*
X315245Y1084485D01*
X314513Y1085217D01*
X314655Y1085358D01*
G37*
G36*
G01X310187Y1092490D02*
X310607Y1092553D01*
X310960Y1091892D01*
X310675Y1091578D01*
X310499Y1091483D01*
X310010Y1092396D01*
X310187Y1092490D01*
G37*
G36*
G01X309464Y1094973D02*
X309885Y1094912D01*
X310031Y1094176D01*
X309667Y1093958D01*
X309471Y1093919D01*
X309268Y1094934D01*
X309464Y1094973D01*
G37*
G36*
G01X309045Y1095032D02*
X308625Y1095094D01*
X308478Y1095829D01*
X308842Y1096047D01*
X309038Y1096086D01*
X309241Y1095071D01*
X309045Y1095032D01*
G37*
G36*
G01X310877Y1090353D02*
X310457Y1090290D01*
X310103Y1090951D01*
X310388Y1091265D01*
X310565Y1091360D01*
X311053Y1090447D01*
X310877Y1090353D01*
G37*
G36*
G01X311295Y1090418D02*
X311715Y1090481D01*
X312069Y1089820D01*
X311784Y1089506D01*
X311607Y1089411D01*
X311119Y1090324D01*
X311295Y1090418D01*
G37*
G36*
G01X311986Y1088281D02*
X311566Y1088218D01*
X311212Y1088879D01*
X311497Y1089193D01*
X311673Y1089288D01*
X312162Y1088375D01*
X311986Y1088281D01*
G37*
G36*
G01X312404Y1088346D02*
X312824Y1088409D01*
X313178Y1087748D01*
X312893Y1087434D01*
X312716Y1087339D01*
X312228Y1088252D01*
X312404Y1088346D01*
G37*
G36*
G01X314273Y1085174D02*
X313889Y1084992D01*
X313359Y1085523D01*
X313541Y1085906D01*
X313682Y1086048D01*
X314414Y1085316D01*
X314273Y1085174D01*
G37*
G36*
G01X315935Y1083513D02*
X315551Y1083331D01*
X315021Y1083861D01*
X315203Y1084245D01*
X315344Y1084386D01*
X316076Y1083654D01*
X315935Y1083513D01*
G37*
G36*
G01X317597Y1081851D02*
X317213Y1081669D01*
X316683Y1082200D01*
X316865Y1082583D01*
X317006Y1082725D01*
X317738Y1081993D01*
X317597Y1081851D01*
G37*
G36*
G01X316317Y1083697D02*
X316700Y1083879D01*
X317231Y1083349D01*
X317049Y1082965D01*
X316907Y1082824D01*
X316175Y1083555D01*
X316317Y1083697D01*
G37*
G36*
G01X317979Y1082035D02*
X318362Y1082218D01*
X318893Y1081687D01*
X318711Y1081304D01*
X318569Y1081162D01*
X317837Y1081894D01*
X317979Y1082035D01*
G37*
G36*
G01X319641Y1080374D02*
X320024Y1080556D01*
X320554Y1080026D01*
X320372Y1079642D01*
X320231Y1079501D01*
X319499Y1080232D01*
X319641Y1080374D01*
G37*
G36*
G01X319259Y1080190D02*
X318875Y1080008D01*
X318345Y1080538D01*
X318527Y1080922D01*
X318668Y1081063D01*
X319400Y1080331D01*
X319259Y1080190D01*
G37*
G36*
G01X311936Y1090920D02*
X311516Y1090856D01*
X311162Y1091518D01*
X311447Y1091832D01*
X311624Y1091926D01*
X312112Y1091014D01*
X311936Y1090920D01*
G37*
G36*
G01X313044Y1088847D02*
X312624Y1088784D01*
X312270Y1089446D01*
X312556Y1089760D01*
X312732Y1089854D01*
X313221Y1088942D01*
X313044Y1088847D01*
G37*
G36*
G01X315122Y1086024D02*
X314739Y1085842D01*
X314208Y1086372D01*
X314390Y1086756D01*
X314532Y1086897D01*
X315264Y1086166D01*
X315122Y1086024D01*
G37*
G36*
G01X313463Y1088913D02*
X313883Y1088976D01*
X314237Y1088314D01*
X313951Y1088000D01*
X313775Y1087906D01*
X313287Y1088818D01*
X313463Y1088913D01*
G37*
G36*
G01X310224Y1095267D02*
X309804Y1095329D01*
X309657Y1096064D01*
X310021Y1096282D01*
X310217Y1096322D01*
X310420Y1095307D01*
X310224Y1095267D01*
G37*
G36*
G01X311246Y1093057D02*
X311666Y1093120D01*
X312020Y1092459D01*
X311734Y1092144D01*
X311558Y1092050D01*
X311070Y1092963D01*
X311246Y1093057D01*
G37*
G36*
G01X310642Y1095209D02*
X311063Y1095147D01*
X311210Y1094412D01*
X310845Y1094194D01*
X310649Y1094154D01*
X310446Y1095169D01*
X310642Y1095209D01*
G37*
G36*
G01X312354Y1090985D02*
X312774Y1091048D01*
X313128Y1090386D01*
X312843Y1090072D01*
X312666Y1089978D01*
X312178Y1090890D01*
X312354Y1090985D01*
G37*
G36*
G01X317166Y1084546D02*
X317550Y1084729D01*
X318080Y1084198D01*
X317898Y1083815D01*
X317757Y1083673D01*
X317025Y1084405D01*
X317166Y1084546D01*
G37*
G36*
G01X316784Y1084363D02*
X316401Y1084180D01*
X315870Y1084711D01*
X316052Y1085094D01*
X316194Y1085236D01*
X316926Y1084504D01*
X316784Y1084363D01*
G37*
G36*
G01X318446Y1082701D02*
X318063Y1082519D01*
X317532Y1083049D01*
X317714Y1083433D01*
X317856Y1083574D01*
X318588Y1082842D01*
X318446Y1082701D01*
G37*
G36*
G01X315504Y1086208D02*
X315888Y1086390D01*
X316418Y1085860D01*
X316236Y1085476D01*
X316095Y1085335D01*
X315363Y1086067D01*
X315504Y1086208D01*
G37*
G36*
G01X320108Y1081040D02*
X319724Y1080857D01*
X319194Y1081388D01*
X319376Y1081771D01*
X319517Y1081913D01*
X320249Y1081181D01*
X320108Y1081040D01*
G37*
G36*
G01X320490Y1081223D02*
X320873Y1081406D01*
X321404Y1080875D01*
X321222Y1080492D01*
X321080Y1080350D01*
X320348Y1081082D01*
X320490Y1081223D01*
G37*
G36*
G01X318828Y1082885D02*
X319212Y1083067D01*
X319742Y1082537D01*
X319560Y1082153D01*
X319418Y1082012D01*
X318687Y1082743D01*
X318828Y1082885D01*
G37*
G36*
G01X315086Y1082664D02*
X314702Y1082482D01*
X314172Y1083012D01*
X314354Y1083396D01*
X314495Y1083537D01*
X315227Y1082805D01*
X315086Y1082664D01*
G37*
G36*
G01X313806Y1084509D02*
X314189Y1084691D01*
X314720Y1084161D01*
X314538Y1083777D01*
X314396Y1083636D01*
X313664Y1084368D01*
X313806Y1084509D01*
G37*
G36*
G01X313424Y1084325D02*
X313040Y1084143D01*
X312510Y1084674D01*
X312692Y1085057D01*
X312834Y1085199D01*
X313565Y1084467D01*
X313424Y1084325D01*
G37*
G36*
G01X308287Y1094738D02*
X308707Y1094677D01*
X308854Y1093941D01*
X308489Y1093723D01*
X308293Y1093684D01*
X308090Y1094699D01*
X308287Y1094738D01*
G37*
G36*
G01X309818Y1089786D02*
X309398Y1089723D01*
X309044Y1090384D01*
X309329Y1090699D01*
X309506Y1090793D01*
X309994Y1089881D01*
X309818Y1089786D01*
G37*
G36*
G01X309128Y1091923D02*
X309547Y1091987D01*
X309901Y1091325D01*
X309616Y1091011D01*
X309440Y1090917D01*
X308951Y1091829D01*
X309128Y1091923D01*
G37*
G36*
G01X310927Y1087714D02*
X310507Y1087651D01*
X310153Y1088313D01*
X310438Y1088627D01*
X310615Y1088721D01*
X311103Y1087809D01*
X310927Y1087714D01*
G37*
G36*
G01X311346Y1087780D02*
X311766Y1087843D01*
X312119Y1087182D01*
X311834Y1086867D01*
X311658Y1086773D01*
X311169Y1087685D01*
X311346Y1087780D01*
G37*
G36*
G01X310237Y1089852D02*
X310657Y1089915D01*
X311010Y1089254D01*
X310725Y1088939D01*
X310549Y1088845D01*
X310060Y1089757D01*
X310237Y1089852D01*
G37*
G36*
G01X307867Y1094797D02*
X307447Y1094859D01*
X307300Y1095594D01*
X307664Y1095812D01*
X307861Y1095851D01*
X308063Y1094836D01*
X307867Y1094797D01*
G37*
G36*
G01X315468Y1082848D02*
X315851Y1083030D01*
X316382Y1082499D01*
X316200Y1082116D01*
X316058Y1081974D01*
X315326Y1082706D01*
X315468Y1082848D01*
G37*
G36*
G01X316748Y1081002D02*
X316364Y1080820D01*
X315834Y1081350D01*
X316016Y1081734D01*
X316157Y1081875D01*
X316889Y1081144D01*
X316748Y1081002D01*
G37*
G36*
G01X317129Y1081186D02*
X317513Y1081368D01*
X318043Y1080838D01*
X317861Y1080454D01*
X317720Y1080313D01*
X316988Y1081045D01*
X317129Y1081186D01*
G37*
G36*
G01X311584Y1083239D02*
X311967Y1083421D01*
X312498Y1082891D01*
X312315Y1082507D01*
X312174Y1082366D01*
X311442Y1083098D01*
X311584Y1083239D01*
G37*
G36*
G01X312864Y1081394D02*
X312480Y1081212D01*
X311950Y1081742D01*
X312132Y1082126D01*
X312273Y1082267D01*
X313005Y1081535D01*
X312864Y1081394D01*
G37*
G36*
G01X313245Y1081578D02*
X313629Y1081760D01*
X314159Y1081229D01*
X313977Y1080846D01*
X313836Y1080704D01*
X313104Y1081436D01*
X313245Y1081578D01*
G37*
G36*
G01X314525Y1079732D02*
X314142Y1079550D01*
X313611Y1080080D01*
X313793Y1080464D01*
X313935Y1080605D01*
X314667Y1079873D01*
X314525Y1079732D01*
G37*
G36*
G01X309312Y1086588D02*
X309732Y1086651D01*
X310086Y1085990D01*
X309800Y1085675D01*
X309624Y1085581D01*
X309136Y1086494D01*
X309312Y1086588D01*
G37*
G36*
G01X308205Y1088661D02*
X308625Y1088724D01*
X308978Y1088062D01*
X308693Y1087748D01*
X308516Y1087654D01*
X308028Y1088567D01*
X308205Y1088661D01*
G37*
G36*
G01X308894Y1086523D02*
X308474Y1086460D01*
X308120Y1087122D01*
X308406Y1087436D01*
X308582Y1087530D01*
X309070Y1086617D01*
X308894Y1086523D01*
G37*
G36*
G01X307097Y1090733D02*
X307517Y1090796D01*
X307871Y1090135D01*
X307585Y1089821D01*
X307409Y1089726D01*
X306921Y1090639D01*
X307097Y1090733D01*
G37*
G36*
G01X307786Y1088596D02*
X307366Y1088533D01*
X307013Y1089194D01*
X307298Y1089509D01*
X307475Y1089603D01*
X307962Y1088690D01*
X307786Y1088596D01*
G37*
G36*
G01X305915Y1094306D02*
X306335Y1094244D01*
X306481Y1093508D01*
X306116Y1093291D01*
X305920Y1093252D01*
X305718Y1094267D01*
X305915Y1094306D01*
G37*
G36*
G01X309886Y1081541D02*
X310269Y1081723D01*
X310800Y1081193D01*
X310617Y1080809D01*
X310476Y1080668D01*
X309744Y1081400D01*
X309886Y1081541D01*
G37*
G36*
G01X311166Y1079696D02*
X310782Y1079514D01*
X310252Y1080044D01*
X310434Y1080428D01*
X310575Y1080569D01*
X311307Y1079837D01*
X311166Y1079696D01*
G37*
G36*
G01X309504Y1081357D02*
X309120Y1081175D01*
X308590Y1081706D01*
X308772Y1082089D01*
X308913Y1082231D01*
X309645Y1081499D01*
X309504Y1081357D01*
G37*
G36*
G01X307884Y1083319D02*
X307464Y1083256D01*
X307111Y1083918D01*
X307396Y1084232D01*
X307573Y1084326D01*
X308060Y1083413D01*
X307884Y1083319D01*
G37*
G36*
G01X307195Y1085457D02*
X307615Y1085520D01*
X307969Y1084858D01*
X307683Y1084544D01*
X307507Y1084450D01*
X307019Y1085363D01*
X307195Y1085457D01*
G37*
G36*
G01X306776Y1085392D02*
X306356Y1085329D01*
X306003Y1085990D01*
X306288Y1086305D01*
X306465Y1086399D01*
X306953Y1085486D01*
X306776Y1085392D01*
G37*
G36*
G01X306087Y1087529D02*
X306507Y1087592D01*
X306861Y1086931D01*
X306575Y1086617D01*
X306399Y1086522D01*
X305911Y1087435D01*
X306087Y1087529D01*
G37*
G36*
G01X310735Y1082390D02*
X311118Y1082572D01*
X311649Y1082042D01*
X311466Y1081658D01*
X311325Y1081517D01*
X310593Y1082249D01*
X310735Y1082390D01*
G37*
G36*
G01X312015Y1080545D02*
X311631Y1080363D01*
X311101Y1080893D01*
X311283Y1081277D01*
X311424Y1081418D01*
X312156Y1080686D01*
X312015Y1080545D01*
G37*
G36*
G01X308944Y1083885D02*
X308524Y1083822D01*
X308170Y1084483D01*
X308456Y1084798D01*
X308632Y1084892D01*
X309120Y1083979D01*
X308944Y1083885D01*
G37*
G36*
G01X312396Y1080729D02*
X312780Y1080911D01*
X313310Y1080380D01*
X313128Y1079997D01*
X312987Y1079855D01*
X312255Y1080587D01*
X312396Y1080729D01*
G37*
G36*
G01X308254Y1086023D02*
X308674Y1086085D01*
X309027Y1085424D01*
X308742Y1085110D01*
X308565Y1085015D01*
X308077Y1085928D01*
X308254Y1086023D01*
G37*
G36*
G01X307835Y1085957D02*
X307415Y1085895D01*
X307062Y1086556D01*
X307347Y1086870D01*
X307524Y1086965D01*
X308011Y1086052D01*
X307835Y1085957D01*
G37*
G36*
G01X307145Y1088095D02*
X307565Y1088158D01*
X307919Y1087497D01*
X307633Y1087182D01*
X307457Y1087088D01*
X306969Y1088001D01*
X307145Y1088095D01*
G37*
G36*
G01X306039Y1090168D02*
X306458Y1090231D01*
X306812Y1089569D01*
X306526Y1089255D01*
X306350Y1089161D01*
X305862Y1090073D01*
X306039Y1090168D01*
G37*
G36*
G01X306728Y1088030D02*
X306308Y1087967D01*
X305955Y1088629D01*
X306241Y1088943D01*
X306417Y1089037D01*
X306905Y1088124D01*
X306728Y1088030D01*
G37*
G36*
G01X308654Y1080507D02*
X308270Y1080325D01*
X307740Y1080856D01*
X307922Y1081239D01*
X308063Y1081381D01*
X308795Y1080649D01*
X308654Y1080507D01*
G37*
G36*
G01X309036Y1080691D02*
X309419Y1080873D01*
X309950Y1080343D01*
X309767Y1079959D01*
X309626Y1079818D01*
X308894Y1080550D01*
X309036Y1080691D01*
G37*
G36*
G01X306825Y1082753D02*
X306405Y1082690D01*
X306051Y1083352D01*
X306337Y1083666D01*
X306513Y1083760D01*
X307001Y1082847D01*
X306825Y1082753D01*
G37*
G36*
G01X306136Y1084891D02*
X306556Y1084954D01*
X306909Y1084292D01*
X306624Y1083978D01*
X306447Y1083884D01*
X305959Y1084796D01*
X306136Y1084891D01*
G37*
G36*
G01X318428Y1110590D02*
X318028Y1110733D01*
Y1111483D01*
X318428Y1111625D01*
X318628D01*
Y1110590D01*
X318428D01*
G37*
G36*
G01X320522Y1100948D02*
X320942Y1100887D01*
X321089Y1100151D01*
X320725Y1099933D01*
X320529Y1099894D01*
X320326Y1100909D01*
X320522Y1100948D01*
G37*
G36*
G01X320563Y1098702D02*
X320143Y1098764D01*
X319996Y1099499D01*
X320360Y1099717D01*
X320556Y1099757D01*
X320759Y1098742D01*
X320563Y1098702D01*
G37*
G36*
G01X320102Y1101007D02*
X319682Y1101068D01*
X319535Y1101804D01*
X319900Y1102022D01*
X320096Y1102061D01*
X320299Y1101046D01*
X320102Y1101007D01*
G37*
G36*
G01X318828Y1112800D02*
X319228Y1112658D01*
Y1111908D01*
X318828Y1111765D01*
X318628D01*
Y1112800D01*
X318828D01*
G37*
G36*
G01X319601Y1105557D02*
X320021Y1105495D01*
X320168Y1104760D01*
X319804Y1104542D01*
X319607Y1104503D01*
X319405Y1105518D01*
X319601Y1105557D01*
G37*
G36*
G01X320061Y1103252D02*
X320482Y1103191D01*
X320629Y1102456D01*
X320264Y1102237D01*
X320068Y1102198D01*
X319865Y1103213D01*
X320061Y1103252D01*
G37*
G36*
G01X319642Y1103311D02*
X319222Y1103372D01*
X319075Y1104108D01*
X319439Y1104326D01*
X319635Y1104365D01*
X319838Y1103350D01*
X319642Y1103311D01*
G37*
G36*
G01X319140Y1107861D02*
X319560Y1107800D01*
X319707Y1107064D01*
X319343Y1106846D01*
X319147Y1106807D01*
X318944Y1107822D01*
X319140Y1107861D01*
G37*
G36*
G01X319181Y1105616D02*
X318761Y1105677D01*
X318614Y1106412D01*
X318978Y1106630D01*
X319174Y1106670D01*
X319377Y1105655D01*
X319181Y1105616D01*
G37*
G36*
G01X317747Y1100536D02*
X317327Y1100597D01*
X317180Y1101333D01*
X317545Y1101551D01*
X317741Y1101590D01*
X317943Y1100575D01*
X317747Y1100536D01*
G37*
G36*
G01X318208Y1098232D02*
X317788Y1098293D01*
X317641Y1099028D01*
X318005Y1099246D01*
X318201Y1099286D01*
X318404Y1098271D01*
X318208Y1098232D01*
G37*
G36*
G01X318167Y1100477D02*
X318587Y1100416D01*
X318734Y1099680D01*
X318370Y1099462D01*
X318174Y1099423D01*
X317971Y1100438D01*
X318167Y1100477D01*
G37*
G36*
G01X316028Y1110590D02*
X315628Y1110733D01*
Y1111483D01*
X316028Y1111625D01*
X316228D01*
Y1110590D01*
X316028D01*
G37*
G36*
G01X316428Y1112800D02*
X316828Y1112658D01*
Y1111908D01*
X316428Y1111765D01*
X316228D01*
Y1112800D01*
X316428D01*
G37*
G36*
G01X317287Y1102840D02*
X316867Y1102902D01*
X316720Y1103637D01*
X317084Y1103855D01*
X317280Y1103894D01*
X317483Y1102880D01*
X317287Y1102840D01*
G37*
G36*
G01X317246Y1105086D02*
X317666Y1105025D01*
X317813Y1104289D01*
X317449Y1104071D01*
X317253Y1104032D01*
X317050Y1105047D01*
X317246Y1105086D01*
G37*
G36*
G01X316826Y1105145D02*
X316406Y1105206D01*
X316259Y1105942D01*
X316623Y1106160D01*
X316819Y1106199D01*
X317022Y1105184D01*
X316826Y1105145D01*
G37*
G36*
G01X316785Y1107390D02*
X317205Y1107329D01*
X317352Y1106593D01*
X316988Y1106375D01*
X316792Y1106336D01*
X316589Y1107351D01*
X316785Y1107390D01*
G37*
G36*
G01X317706Y1102781D02*
X318127Y1102720D01*
X318274Y1101985D01*
X317909Y1101767D01*
X317713Y1101727D01*
X317510Y1102742D01*
X317706Y1102781D01*
G37*
G36*
G01X318628Y1098173D02*
X319048Y1098111D01*
X319195Y1097376D01*
X318831Y1097158D01*
X318634Y1097118D01*
X318432Y1098133D01*
X318628Y1098173D01*
G37*
G36*
G01X317228Y1110590D02*
X316828Y1110733D01*
Y1111483D01*
X317228Y1111625D01*
X317428D01*
Y1110590D01*
X317228D01*
G37*
G36*
G01X317628Y1112800D02*
X318028Y1112658D01*
Y1111908D01*
X317628Y1111765D01*
X317428D01*
Y1112800D01*
X317628D01*
G37*
G36*
G01X318464Y1103076D02*
X318044Y1103137D01*
X317897Y1103873D01*
X318261Y1104091D01*
X318457Y1104130D01*
X318660Y1103115D01*
X318464Y1103076D01*
G37*
G36*
G01X318423Y1105321D02*
X318843Y1105260D01*
X318990Y1104524D01*
X318626Y1104306D01*
X318430Y1104267D01*
X318227Y1105282D01*
X318423Y1105321D01*
G37*
G36*
G01X318003Y1105380D02*
X317583Y1105441D01*
X317436Y1106177D01*
X317800Y1106395D01*
X317996Y1106434D01*
X318199Y1105419D01*
X318003Y1105380D01*
G37*
G36*
G01X317962Y1107626D02*
X318382Y1107564D01*
X318529Y1106829D01*
X318165Y1106611D01*
X317969Y1106572D01*
X317766Y1107586D01*
X317962Y1107626D01*
G37*
G36*
G01X319386Y1098467D02*
X318965Y1098528D01*
X318818Y1099264D01*
X319183Y1099482D01*
X319379Y1099521D01*
X319582Y1098506D01*
X319386Y1098467D01*
G37*
G36*
G01X319344Y1100712D02*
X319765Y1100651D01*
X319912Y1099916D01*
X319547Y1099698D01*
X319351Y1099658D01*
X319148Y1100673D01*
X319344Y1100712D01*
G37*
G36*
G01X318925Y1100771D02*
X318505Y1100833D01*
X318358Y1101568D01*
X318722Y1101786D01*
X318918Y1101825D01*
X319121Y1100811D01*
X318925Y1100771D01*
G37*
G36*
G01X319805Y1098408D02*
X320225Y1098347D01*
X320372Y1097611D01*
X320008Y1097393D01*
X319812Y1097354D01*
X319609Y1098369D01*
X319805Y1098408D01*
G37*
G36*
G01X318884Y1103017D02*
X319304Y1102956D01*
X319451Y1102220D01*
X319087Y1102002D01*
X318891Y1101963D01*
X318688Y1102978D01*
X318884Y1103017D01*
G37*
G36*
G01X314828Y1110590D02*
X314428Y1110733D01*
Y1111483D01*
X314828Y1111625D01*
X315028D01*
Y1110590D01*
X314828D01*
G37*
G36*
G01X316568Y1100300D02*
X316148Y1100362D01*
X316001Y1101097D01*
X316365Y1101315D01*
X316561Y1101354D01*
X316764Y1100339D01*
X316568Y1100300D01*
G37*
G36*
G01X317028Y1097996D02*
X316608Y1098057D01*
X316461Y1098792D01*
X316825Y1099011D01*
X317022Y1099050D01*
X317224Y1098035D01*
X317028Y1097996D01*
G37*
G36*
G01X316988Y1100241D02*
X317408Y1100180D01*
X317555Y1099444D01*
X317190Y1099226D01*
X316994Y1099187D01*
X316791Y1100202D01*
X316988Y1100241D01*
G37*
G36*
G01X317448Y1097937D02*
X317868Y1097875D01*
X318015Y1097140D01*
X317651Y1096922D01*
X317455Y1096883D01*
X317252Y1097898D01*
X317448Y1097937D01*
G37*
G36*
G01X316067Y1104850D02*
X316487Y1104789D01*
X316634Y1104053D01*
X316270Y1103835D01*
X316074Y1103796D01*
X315871Y1104811D01*
X316067Y1104850D01*
G37*
G36*
G01X316527Y1102546D02*
X316947Y1102484D01*
X317094Y1101749D01*
X316730Y1101531D01*
X316534Y1101492D01*
X316331Y1102506D01*
X316527Y1102546D01*
G37*
G36*
G01X315228Y1112800D02*
X315628Y1112658D01*
Y1111908D01*
X315228Y1111765D01*
X315028D01*
Y1112800D01*
X315228D01*
G37*
G36*
G01X316108Y1102605D02*
X315687Y1102666D01*
X315541Y1103401D01*
X315905Y1103620D01*
X316101Y1103659D01*
X316304Y1102644D01*
X316108Y1102605D01*
G37*
G36*
G01X315647Y1104909D02*
X315227Y1104970D01*
X315080Y1105706D01*
X315445Y1105924D01*
X315641Y1105963D01*
X315843Y1104948D01*
X315647Y1104909D01*
G37*
G36*
G01X315607Y1107155D02*
X316027Y1107093D01*
X316174Y1106358D01*
X315809Y1106140D01*
X315613Y1106100D01*
X315410Y1107115D01*
X315607Y1107155D01*
G37*
G36*
G01X310900Y1100052D02*
X311320Y1099991D01*
X311467Y1099256D01*
X311103Y1099037D01*
X310907Y1098998D01*
X310704Y1100013D01*
X310900Y1100052D01*
G37*
G36*
G01X311360Y1097748D02*
X311780Y1097687D01*
X311927Y1096951D01*
X311563Y1096733D01*
X311367Y1096694D01*
X311164Y1097709D01*
X311360Y1097748D01*
G37*
G36*
G01X310480Y1100111D02*
X310060Y1100173D01*
X309913Y1100908D01*
X310277Y1101126D01*
X310474Y1101165D01*
X310676Y1100151D01*
X310480Y1100111D01*
G37*
G36*
G01X310942Y1097807D02*
X310521Y1097868D01*
X310375Y1098604D01*
X310739Y1098822D01*
X310935Y1098861D01*
X311138Y1097846D01*
X310942Y1097807D01*
G37*
G36*
G01X310440Y1102357D02*
X310860Y1102296D01*
X311007Y1101560D01*
X310642Y1101342D01*
X310446Y1101303D01*
X310243Y1102318D01*
X310440Y1102357D01*
G37*
G36*
G01X309228Y1110936D02*
X309628Y1110793D01*
Y1110043D01*
X309228Y1109901D01*
X309028D01*
Y1110936D01*
X309228D01*
G37*
G36*
G01X308828Y1111076D02*
X308428Y1111219D01*
Y1111969D01*
X308828Y1112111D01*
X309028D01*
Y1111076D01*
X308828D01*
G37*
G36*
G01X309979Y1104661D02*
X310399Y1104600D01*
X310546Y1103865D01*
X310182Y1103646D01*
X309986Y1103607D01*
X309783Y1104622D01*
X309979Y1104661D01*
G37*
G36*
G01X310020Y1102416D02*
X309600Y1102477D01*
X309453Y1103213D01*
X309817Y1103431D01*
X310013Y1103470D01*
X310216Y1102455D01*
X310020Y1102416D01*
G37*
G36*
G01X309561Y1104720D02*
X309140Y1104782D01*
X308993Y1105517D01*
X309358Y1105735D01*
X309554Y1105774D01*
X309757Y1104759D01*
X309561Y1104720D01*
G37*
G36*
G01X308585Y1097337D02*
X308164Y1097398D01*
X308018Y1098134D01*
X308382Y1098352D01*
X308578Y1098391D01*
X308781Y1097376D01*
X308585Y1097337D01*
G37*
G36*
G01X308084Y1101887D02*
X308504Y1101825D01*
X308651Y1101090D01*
X308287Y1100872D01*
X308091Y1100833D01*
X307888Y1101848D01*
X308084Y1101887D01*
G37*
G36*
G01X309004Y1097278D02*
X309424Y1097216D01*
X309571Y1096481D01*
X309207Y1096263D01*
X309011Y1096224D01*
X308808Y1097239D01*
X309004Y1097278D01*
G37*
G36*
G01X308544Y1099582D02*
X308964Y1099521D01*
X309111Y1098785D01*
X308747Y1098567D01*
X308551Y1098528D01*
X308348Y1099543D01*
X308544Y1099582D01*
G37*
G36*
G01X308124Y1099641D02*
X307704Y1099703D01*
X307558Y1100438D01*
X307922Y1100656D01*
X308118Y1100695D01*
X308321Y1099680D01*
X308124Y1099641D01*
G37*
G36*
G01X306828Y1110936D02*
X307228Y1110793D01*
Y1110043D01*
X306828Y1109901D01*
X306628D01*
Y1110936D01*
X306828D01*
G37*
G36*
G01X307624Y1104191D02*
X308044Y1104130D01*
X308191Y1103394D01*
X307827Y1103176D01*
X307631Y1103137D01*
X307428Y1104152D01*
X307624Y1104191D01*
G37*
G36*
G01X307664Y1101946D02*
X307244Y1102007D01*
X307097Y1102743D01*
X307462Y1102961D01*
X307658Y1103000D01*
X307861Y1101985D01*
X307664Y1101946D01*
G37*
G36*
G01X307205Y1104250D02*
X306785Y1104312D01*
X306638Y1105047D01*
X307003Y1105265D01*
X307199Y1105304D01*
X307401Y1104289D01*
X307205Y1104250D01*
G37*
G36*
G01X307164Y1106496D02*
X307584Y1106434D01*
X307731Y1105699D01*
X307367Y1105481D01*
X307170Y1105442D01*
X306968Y1106457D01*
X307164Y1106496D01*
G37*
G36*
G01X306428Y1108726D02*
X306028Y1108869D01*
Y1109619D01*
X306428Y1109761D01*
X306628D01*
Y1108726D01*
X306428D01*
G37*
G36*
G01Y1111076D02*
X306028Y1111219D01*
Y1111969D01*
X306428Y1112111D01*
X306628D01*
Y1111076D01*
X306428D01*
G37*
G36*
G01X309723Y1099817D02*
X310143Y1099756D01*
X310290Y1099021D01*
X309925Y1098803D01*
X309729Y1098763D01*
X309527Y1099778D01*
X309723Y1099817D01*
G37*
G36*
G01X310183Y1097513D02*
X310603Y1097452D01*
X310750Y1096716D01*
X310386Y1096498D01*
X310190Y1096459D01*
X309987Y1097474D01*
X310183Y1097513D01*
G37*
G36*
G01X309303Y1099876D02*
X308883Y1099938D01*
X308736Y1100673D01*
X309100Y1100891D01*
X309296Y1100931D01*
X309499Y1099916D01*
X309303Y1099876D01*
G37*
G36*
G01X309763Y1097572D02*
X309343Y1097633D01*
X309196Y1098369D01*
X309561Y1098587D01*
X309757Y1098626D01*
X309959Y1097611D01*
X309763Y1097572D01*
G37*
G36*
G01X309261Y1102122D02*
X309682Y1102061D01*
X309828Y1101325D01*
X309464Y1101107D01*
X309268Y1101068D01*
X309065Y1102083D01*
X309261Y1102122D01*
G37*
G36*
G01X308802Y1104426D02*
X309222Y1104365D01*
X309369Y1103630D01*
X309005Y1103411D01*
X308809Y1103372D01*
X308606Y1104387D01*
X308802Y1104426D01*
G37*
G36*
G01X308843Y1102181D02*
X308422Y1102242D01*
X308276Y1102978D01*
X308640Y1103196D01*
X308836Y1103235D01*
X309039Y1102220D01*
X308843Y1102181D01*
G37*
G36*
G01X308382Y1104485D02*
X307962Y1104547D01*
X307815Y1105282D01*
X308180Y1105500D01*
X308376Y1105539D01*
X308578Y1104525D01*
X308382Y1104485D01*
G37*
G36*
G01X308342Y1106731D02*
X308762Y1106670D01*
X308909Y1105934D01*
X308544Y1105716D01*
X308348Y1105677D01*
X308146Y1106692D01*
X308342Y1106731D01*
G37*
G36*
G01X308028Y1110936D02*
X308428Y1110793D01*
Y1110043D01*
X308028Y1109901D01*
X307828D01*
Y1110936D01*
X308028D01*
G37*
G36*
G01X307628Y1111076D02*
X307228Y1111219D01*
Y1111969D01*
X307628Y1112111D01*
X307828D01*
Y1111076D01*
X307628D01*
G37*
G36*
G01X306947Y1099406D02*
X306527Y1099468D01*
X306380Y1100203D01*
X306745Y1100421D01*
X306941Y1100460D01*
X307143Y1099445D01*
X306947Y1099406D01*
G37*
G36*
G01X307407Y1097102D02*
X306987Y1097163D01*
X306840Y1097899D01*
X307204Y1098117D01*
X307401Y1098156D01*
X307603Y1097141D01*
X307407Y1097102D01*
G37*
G36*
G01X306907Y1101652D02*
X307327Y1101590D01*
X307474Y1100855D01*
X307109Y1100637D01*
X306913Y1100598D01*
X306711Y1101613D01*
X306907Y1101652D01*
G37*
G36*
G01X307367Y1099347D02*
X307787Y1099286D01*
X307934Y1098550D01*
X307569Y1098332D01*
X307373Y1098293D01*
X307171Y1099308D01*
X307367Y1099347D01*
G37*
G36*
G01X307827Y1097043D02*
X308247Y1096981D01*
X308394Y1096246D01*
X308029Y1096028D01*
X307833Y1095989D01*
X307631Y1097004D01*
X307827Y1097043D01*
G37*
G36*
G01X306027Y1104015D02*
X305607Y1104077D01*
X305460Y1104812D01*
X305825Y1105030D01*
X306021Y1105070D01*
X306223Y1104055D01*
X306027Y1104015D01*
G37*
G36*
G01X306447Y1103956D02*
X306867Y1103895D01*
X307014Y1103159D01*
X306649Y1102941D01*
X306453Y1102902D01*
X306251Y1103917D01*
X306447Y1103956D01*
G37*
G36*
G01X305987Y1106261D02*
X306407Y1106199D01*
X306554Y1105464D01*
X306190Y1105246D01*
X305993Y1105207D01*
X305791Y1106222D01*
X305987Y1106261D01*
G37*
G36*
G01X306487Y1101711D02*
X306067Y1101772D01*
X305920Y1102508D01*
X306285Y1102726D01*
X306481Y1102765D01*
X306683Y1101750D01*
X306487Y1101711D01*
G37*
G36*
G01X305628Y1110936D02*
X306028Y1110793D01*
Y1110043D01*
X305628Y1109901D01*
X305428D01*
Y1110936D01*
X305628D01*
G37*
G36*
G01X322136Y1108592D02*
X321716Y1108654D01*
X321569Y1109389D01*
X321934Y1109607D01*
X322130Y1109646D01*
X322332Y1108631D01*
X322136Y1108592D01*
G37*
G36*
G01X321378Y1108298D02*
X321798Y1108237D01*
X321945Y1107501D01*
X321581Y1107283D01*
X321385Y1107244D01*
X321182Y1108259D01*
X321378Y1108298D01*
G37*
G36*
G01X321419Y1106053D02*
X320998Y1106114D01*
X320852Y1106849D01*
X321216Y1107067D01*
X321412Y1107107D01*
X321615Y1106092D01*
X321419Y1106053D01*
G37*
G36*
G01X321879Y1103748D02*
X321459Y1103809D01*
X321312Y1104545D01*
X321676Y1104763D01*
X321872Y1104802D01*
X322075Y1103787D01*
X321879Y1103748D01*
G37*
G36*
G01X320958Y1108357D02*
X320538Y1108418D01*
X320391Y1109154D01*
X320756Y1109372D01*
X320952Y1109411D01*
X321154Y1108396D01*
X320958Y1108357D01*
G37*
G36*
G01X318428Y1115290D02*
X318028Y1115433D01*
Y1116183D01*
X318428Y1116325D01*
X318628D01*
Y1115290D01*
X318428D01*
G37*
G36*
G01Y1112940D02*
X318028Y1113083D01*
Y1113833D01*
X318428Y1113975D01*
X318628D01*
Y1112940D01*
X318428D01*
G37*
G36*
G01Y1117640D02*
X318028Y1117783D01*
Y1118533D01*
X318428Y1118675D01*
X318628D01*
Y1117640D01*
X318428D01*
G37*
G36*
G01Y1127040D02*
X318028Y1127183D01*
Y1127933D01*
X318428Y1128075D01*
X318628D01*
Y1127040D01*
X318428D01*
G37*
G36*
G01Y1122340D02*
X318028Y1122483D01*
Y1123233D01*
X318428Y1123375D01*
X318628D01*
Y1122340D01*
X318428D01*
G37*
G36*
G01Y1119990D02*
X318028Y1120133D01*
Y1120883D01*
X318428Y1121025D01*
X318628D01*
Y1119990D01*
X318428D01*
G37*
G36*
G01Y1124690D02*
X318028Y1124833D01*
Y1125583D01*
X318428Y1125725D01*
X318628D01*
Y1124690D01*
X318428D01*
G37*
G36*
G01X318828Y1117500D02*
X319228Y1117358D01*
Y1116608D01*
X318828Y1116465D01*
X318628D01*
Y1117500D01*
X318828D01*
G37*
G36*
G01Y1115150D02*
X319228Y1115008D01*
Y1114258D01*
X318828Y1114115D01*
X318628D01*
Y1115150D01*
X318828D01*
G37*
G36*
G01Y1126900D02*
X319228Y1126758D01*
Y1126008D01*
X318828Y1125865D01*
X318628D01*
Y1126900D01*
X318828D01*
G37*
G36*
G01Y1129250D02*
X319228Y1129108D01*
Y1128358D01*
X318828Y1128215D01*
X318628D01*
Y1129250D01*
X318828D01*
G37*
G36*
G01Y1124550D02*
X319228Y1124408D01*
Y1123658D01*
X318828Y1123515D01*
X318628D01*
Y1124550D01*
X318828D01*
G37*
G36*
G01Y1122200D02*
X319228Y1122058D01*
Y1121308D01*
X318828Y1121165D01*
X318628D01*
Y1122200D01*
X318828D01*
G37*
G36*
G01Y1119850D02*
X319228Y1119708D01*
Y1118958D01*
X318828Y1118815D01*
X318628D01*
Y1119850D01*
X318828D01*
G37*
G36*
G01X316028Y1115290D02*
X315628Y1115433D01*
Y1116183D01*
X316028Y1116325D01*
X316228D01*
Y1115290D01*
X316028D01*
G37*
G36*
G01Y1112940D02*
X315628Y1113083D01*
Y1113833D01*
X316028Y1113975D01*
X316228D01*
Y1112940D01*
X316028D01*
G37*
G36*
G01Y1117640D02*
X315628Y1117783D01*
Y1118533D01*
X316028Y1118675D01*
X316228D01*
Y1117640D01*
X316028D01*
G37*
G36*
G01X316428Y1117500D02*
X316828Y1117358D01*
Y1116608D01*
X316428Y1116465D01*
X316228D01*
Y1117500D01*
X316428D01*
G37*
G36*
G01Y1115150D02*
X316828Y1115008D01*
Y1114258D01*
X316428Y1114115D01*
X316228D01*
Y1115150D01*
X316428D01*
G37*
G36*
G01X316028Y1127040D02*
X315628Y1127183D01*
Y1127933D01*
X316028Y1128075D01*
X316228D01*
Y1127040D01*
X316028D01*
G37*
G36*
G01X316428Y1126900D02*
X316828Y1126758D01*
Y1126008D01*
X316428Y1125865D01*
X316228D01*
Y1126900D01*
X316428D01*
G37*
G36*
G01Y1129250D02*
X316828Y1129108D01*
Y1128358D01*
X316428Y1128215D01*
X316228D01*
Y1129250D01*
X316428D01*
G37*
G36*
G01X316028Y1122340D02*
X315628Y1122483D01*
Y1123233D01*
X316028Y1123375D01*
X316228D01*
Y1122340D01*
X316028D01*
G37*
G36*
G01Y1119990D02*
X315628Y1120133D01*
Y1120883D01*
X316028Y1121025D01*
X316228D01*
Y1119990D01*
X316028D01*
G37*
G36*
G01Y1124690D02*
X315628Y1124833D01*
Y1125583D01*
X316028Y1125725D01*
X316228D01*
Y1124690D01*
X316028D01*
G37*
G36*
G01X316428Y1124550D02*
X316828Y1124408D01*
Y1123658D01*
X316428Y1123515D01*
X316228D01*
Y1124550D01*
X316428D01*
G37*
G36*
G01Y1122200D02*
X316828Y1122058D01*
Y1121308D01*
X316428Y1121165D01*
X316228D01*
Y1122200D01*
X316428D01*
G37*
G36*
G01Y1119850D02*
X316828Y1119708D01*
Y1118958D01*
X316428Y1118815D01*
X316228D01*
Y1119850D01*
X316428D01*
G37*
G36*
G01X317228Y1112940D02*
X316828Y1113083D01*
Y1113833D01*
X317228Y1113975D01*
X317428D01*
Y1112940D01*
X317228D01*
G37*
G36*
G01X317628Y1117500D02*
X318028Y1117358D01*
Y1116608D01*
X317628Y1116465D01*
X317428D01*
Y1117500D01*
X317628D01*
G37*
G36*
G01Y1115150D02*
X318028Y1115008D01*
Y1114258D01*
X317628Y1114115D01*
X317428D01*
Y1115150D01*
X317628D01*
G37*
G36*
G01X317228Y1117640D02*
X316828Y1117783D01*
Y1118533D01*
X317228Y1118675D01*
X317428D01*
Y1117640D01*
X317228D01*
G37*
G36*
G01Y1115290D02*
X316828Y1115433D01*
Y1116183D01*
X317228Y1116325D01*
X317428D01*
Y1115290D01*
X317228D01*
G37*
G36*
G01Y1127040D02*
X316828Y1127183D01*
Y1127933D01*
X317228Y1128075D01*
X317428D01*
Y1127040D01*
X317228D01*
G37*
G36*
G01X317628Y1129250D02*
X318028Y1129108D01*
Y1128358D01*
X317628Y1128215D01*
X317428D01*
Y1129250D01*
X317628D01*
G37*
G36*
G01X317228Y1122340D02*
X316828Y1122483D01*
Y1123233D01*
X317228Y1123375D01*
X317428D01*
Y1122340D01*
X317228D01*
G37*
G36*
G01Y1119990D02*
X316828Y1120133D01*
Y1120883D01*
X317228Y1121025D01*
X317428D01*
Y1119990D01*
X317228D01*
G37*
G36*
G01X317628Y1124550D02*
X318028Y1124408D01*
Y1123658D01*
X317628Y1123515D01*
X317428D01*
Y1124550D01*
X317628D01*
G37*
G36*
G01Y1122200D02*
X318028Y1122058D01*
Y1121308D01*
X317628Y1121165D01*
X317428D01*
Y1122200D01*
X317628D01*
G37*
G36*
G01Y1119850D02*
X318028Y1119708D01*
Y1118958D01*
X317628Y1118815D01*
X317428D01*
Y1119850D01*
X317628D01*
G37*
G36*
G01X317228Y1124690D02*
X316828Y1124833D01*
Y1125583D01*
X317228Y1125725D01*
X317428D01*
Y1124690D01*
X317228D01*
G37*
G36*
G01X317628Y1126900D02*
X318028Y1126758D01*
Y1126008D01*
X317628Y1125865D01*
X317428D01*
Y1126900D01*
X317628D01*
G37*
G36*
G01X314828Y1115290D02*
X314428Y1115433D01*
Y1116183D01*
X314828Y1116325D01*
X315028D01*
Y1115290D01*
X314828D01*
G37*
G36*
G01Y1112940D02*
X314428Y1113083D01*
Y1113833D01*
X314828Y1113975D01*
X315028D01*
Y1112940D01*
X314828D01*
G37*
G36*
G01Y1117640D02*
X314428Y1117783D01*
Y1118533D01*
X314828Y1118675D01*
X315028D01*
Y1117640D01*
X314828D01*
G37*
G36*
G01Y1124690D02*
X314428Y1124833D01*
Y1125583D01*
X314828Y1125725D01*
X315028D01*
Y1124690D01*
X314828D01*
G37*
G36*
G01Y1127040D02*
X314428Y1127183D01*
Y1127933D01*
X314828Y1128075D01*
X315028D01*
Y1127040D01*
X314828D01*
G37*
G36*
G01Y1122340D02*
X314428Y1122483D01*
Y1123233D01*
X314828Y1123375D01*
X315028D01*
Y1122340D01*
X314828D01*
G37*
G36*
G01Y1119990D02*
X314428Y1120133D01*
Y1120883D01*
X314828Y1121025D01*
X315028D01*
Y1119990D01*
X314828D01*
G37*
G36*
G01X315228Y1117500D02*
X315628Y1117358D01*
Y1116608D01*
X315228Y1116465D01*
X315028D01*
Y1117500D01*
X315228D01*
G37*
G36*
G01Y1115150D02*
X315628Y1115008D01*
Y1114258D01*
X315228Y1114115D01*
X315028D01*
Y1115150D01*
X315228D01*
G37*
G36*
G01Y1126900D02*
X315628Y1126758D01*
Y1126008D01*
X315228Y1125865D01*
X315028D01*
Y1126900D01*
X315228D01*
G37*
G36*
G01Y1129250D02*
X315628Y1129108D01*
Y1128358D01*
X315228Y1128215D01*
X315028D01*
Y1129250D01*
X315228D01*
G37*
G36*
G01Y1124550D02*
X315628Y1124408D01*
Y1123658D01*
X315228Y1123515D01*
X315028D01*
Y1124550D01*
X315228D01*
G37*
G36*
G01Y1122200D02*
X315628Y1122058D01*
Y1121308D01*
X315228Y1121165D01*
X315028D01*
Y1122200D01*
X315228D01*
G37*
G36*
G01Y1119850D02*
X315628Y1119708D01*
Y1118958D01*
X315228Y1118815D01*
X315028D01*
Y1119850D01*
X315228D01*
G37*
G36*
G01X309228Y1117986D02*
X309628Y1117843D01*
Y1117093D01*
X309228Y1116951D01*
X309028D01*
Y1117986D01*
X309228D01*
G37*
G36*
G01Y1115636D02*
X309628Y1115493D01*
Y1114743D01*
X309228Y1114601D01*
X309028D01*
Y1115636D01*
X309228D01*
G37*
G36*
G01Y1113286D02*
X309628Y1113143D01*
Y1112393D01*
X309228Y1112251D01*
X309028D01*
Y1113286D01*
X309228D01*
G37*
G36*
G01X308828Y1115776D02*
X308428Y1115919D01*
Y1116669D01*
X308828Y1116811D01*
X309028D01*
Y1115776D01*
X308828D01*
G37*
G36*
G01Y1113426D02*
X308428Y1113569D01*
Y1114319D01*
X308828Y1114461D01*
X309028D01*
Y1113426D01*
X308828D01*
G37*
G36*
G01X309228Y1120336D02*
X309628Y1120193D01*
Y1119443D01*
X309228Y1119301D01*
X309028D01*
Y1120336D01*
X309228D01*
G37*
G36*
G01Y1122686D02*
X309628Y1122543D01*
Y1121793D01*
X309228Y1121651D01*
X309028D01*
Y1122686D01*
X309228D01*
G37*
G36*
G01Y1125036D02*
X309628Y1124893D01*
Y1124143D01*
X309228Y1124001D01*
X309028D01*
Y1125036D01*
X309228D01*
G37*
G36*
G01X308828Y1120476D02*
X308428Y1120619D01*
Y1121369D01*
X308828Y1121511D01*
X309028D01*
Y1120476D01*
X308828D01*
G37*
G36*
G01Y1122826D02*
X308428Y1122969D01*
Y1123719D01*
X308828Y1123861D01*
X309028D01*
Y1122826D01*
X308828D01*
G37*
G36*
G01Y1125176D02*
X308428Y1125319D01*
Y1126069D01*
X308828Y1126211D01*
X309028D01*
Y1125176D01*
X308828D01*
G37*
G36*
G01X309228Y1127386D02*
X309628Y1127243D01*
Y1126493D01*
X309228Y1126351D01*
X309028D01*
Y1127386D01*
X309228D01*
G37*
G36*
G01X308828Y1127526D02*
X308428Y1127669D01*
Y1128419D01*
X308828Y1128561D01*
X309028D01*
Y1127526D01*
X308828D01*
G37*
G36*
G01Y1118126D02*
X308428Y1118269D01*
Y1119019D01*
X308828Y1119161D01*
X309028D01*
Y1118126D01*
X308828D01*
G37*
G36*
G01X306828Y1117986D02*
X307228Y1117843D01*
Y1117093D01*
X306828Y1116951D01*
X306628D01*
Y1117986D01*
X306828D01*
G37*
G36*
G01Y1115636D02*
X307228Y1115493D01*
Y1114743D01*
X306828Y1114601D01*
X306628D01*
Y1115636D01*
X306828D01*
G37*
G36*
G01Y1113286D02*
X307228Y1113143D01*
Y1112393D01*
X306828Y1112251D01*
X306628D01*
Y1113286D01*
X306828D01*
G37*
G36*
G01Y1120336D02*
X307228Y1120193D01*
Y1119443D01*
X306828Y1119301D01*
X306628D01*
Y1120336D01*
X306828D01*
G37*
G36*
G01Y1122686D02*
X307228Y1122543D01*
Y1121793D01*
X306828Y1121651D01*
X306628D01*
Y1122686D01*
X306828D01*
G37*
G36*
G01X306428Y1115776D02*
X306028Y1115919D01*
Y1116669D01*
X306428Y1116811D01*
X306628D01*
Y1115776D01*
X306428D01*
G37*
G36*
G01Y1113426D02*
X306028Y1113569D01*
Y1114319D01*
X306428Y1114461D01*
X306628D01*
Y1113426D01*
X306428D01*
G37*
G36*
G01Y1120476D02*
X306028Y1120619D01*
Y1121369D01*
X306428Y1121511D01*
X306628D01*
Y1120476D01*
X306428D01*
G37*
G36*
G01Y1118126D02*
X306028Y1118269D01*
Y1119019D01*
X306428Y1119161D01*
X306628D01*
Y1118126D01*
X306428D01*
G37*
G36*
G01X308028Y1117986D02*
X308428Y1117843D01*
Y1117093D01*
X308028Y1116951D01*
X307828D01*
Y1117986D01*
X308028D01*
G37*
G36*
G01Y1115636D02*
X308428Y1115493D01*
Y1114743D01*
X308028Y1114601D01*
X307828D01*
Y1115636D01*
X308028D01*
G37*
G36*
G01Y1113286D02*
X308428Y1113143D01*
Y1112393D01*
X308028Y1112251D01*
X307828D01*
Y1113286D01*
X308028D01*
G37*
G36*
G01X307628Y1115776D02*
X307228Y1115919D01*
Y1116669D01*
X307628Y1116811D01*
X307828D01*
Y1115776D01*
X307628D01*
G37*
G36*
G01Y1113426D02*
X307228Y1113569D01*
Y1114319D01*
X307628Y1114461D01*
X307828D01*
Y1113426D01*
X307628D01*
G37*
G36*
G01X308028Y1122686D02*
X308428Y1122543D01*
Y1121793D01*
X308028Y1121651D01*
X307828D01*
Y1122686D01*
X308028D01*
G37*
G36*
G01Y1125036D02*
X308428Y1124893D01*
Y1124143D01*
X308028Y1124001D01*
X307828D01*
Y1125036D01*
X308028D01*
G37*
G36*
G01Y1120336D02*
X308428Y1120193D01*
Y1119443D01*
X308028Y1119301D01*
X307828D01*
Y1120336D01*
X308028D01*
G37*
G36*
G01X307628Y1122826D02*
X307228Y1122969D01*
Y1123719D01*
X307628Y1123861D01*
X307828D01*
Y1122826D01*
X307628D01*
G37*
G36*
G01Y1120476D02*
X307228Y1120619D01*
Y1121369D01*
X307628Y1121511D01*
X307828D01*
Y1120476D01*
X307628D01*
G37*
G36*
G01Y1125176D02*
X307228Y1125319D01*
Y1126069D01*
X307628Y1126211D01*
X307828D01*
Y1125176D01*
X307628D01*
G37*
G36*
G01X308028Y1127386D02*
X308428Y1127243D01*
Y1126493D01*
X308028Y1126351D01*
X307828D01*
Y1127386D01*
X308028D01*
G37*
G36*
G01X307628Y1118126D02*
X307228Y1118269D01*
Y1119019D01*
X307628Y1119161D01*
X307828D01*
Y1118126D01*
X307628D01*
G37*
G36*
G01X305628Y1115636D02*
X306028Y1115493D01*
Y1114743D01*
X305628Y1114601D01*
X305428D01*
Y1115636D01*
X305628D01*
G37*
G36*
G01Y1113286D02*
X306028Y1113143D01*
Y1112393D01*
X305628Y1112251D01*
X305428D01*
Y1113286D01*
X305628D01*
G37*
G36*
G01Y1117986D02*
X306028Y1117843D01*
Y1117093D01*
X305628Y1116951D01*
X305428D01*
Y1117986D01*
X305628D01*
G37*
G36*
G01Y1120336D02*
X306028Y1120193D01*
Y1119443D01*
X305628Y1119301D01*
X305428D01*
Y1120336D01*
X305628D01*
G37*
G36*
G01X321828Y1122925D02*
X321428Y1123068D01*
Y1123818D01*
X321828Y1123960D01*
X322028D01*
Y1122925D01*
X321828D01*
G37*
G36*
G01Y1125275D02*
X321428Y1125418D01*
Y1126168D01*
X321828Y1126310D01*
X322028D01*
Y1125275D01*
X321828D01*
G37*
G36*
G01Y1127625D02*
X321428Y1127768D01*
Y1128518D01*
X321828Y1128660D01*
X322028D01*
Y1127625D01*
X321828D01*
G37*
G36*
G01Y1115875D02*
X321428Y1116018D01*
Y1116768D01*
X321828Y1116910D01*
X322028D01*
Y1115875D01*
X321828D01*
G37*
G36*
G01Y1113525D02*
X321428Y1113668D01*
Y1114418D01*
X321828Y1114560D01*
X322028D01*
Y1113525D01*
X321828D01*
G37*
G36*
G01Y1120575D02*
X321428Y1120718D01*
Y1121468D01*
X321828Y1121610D01*
X322028D01*
Y1120575D01*
X321828D01*
G37*
G36*
G01Y1118225D02*
X321428Y1118368D01*
Y1119118D01*
X321828Y1119260D01*
X322028D01*
Y1118225D01*
X321828D01*
G37*
G36*
G01X321028Y1115735D02*
X321428Y1115593D01*
Y1114843D01*
X321028Y1114700D01*
X320828D01*
Y1115735D01*
X321028D01*
G37*
G36*
G01Y1113385D02*
X321428Y1113243D01*
Y1112493D01*
X321028Y1112350D01*
X320828D01*
Y1113385D01*
X321028D01*
G37*
G36*
G01X320628Y1115875D02*
X320228Y1116018D01*
Y1116768D01*
X320628Y1116910D01*
X320828D01*
Y1115875D01*
X320628D01*
G37*
G36*
G01Y1113525D02*
X320228Y1113668D01*
Y1114418D01*
X320628Y1114560D01*
X320828D01*
Y1113525D01*
X320628D01*
G37*
G36*
G01X321028Y1118085D02*
X321428Y1117943D01*
Y1117193D01*
X321028Y1117050D01*
X320828D01*
Y1118085D01*
X321028D01*
G37*
G36*
G01X320628Y1125275D02*
X320228Y1125418D01*
Y1126168D01*
X320628Y1126310D01*
X320828D01*
Y1125275D01*
X320628D01*
G37*
G36*
G01Y1127625D02*
X320228Y1127768D01*
Y1128518D01*
X320628Y1128660D01*
X320828D01*
Y1127625D01*
X320628D01*
G37*
G36*
G01X321028Y1127485D02*
X321428Y1127343D01*
Y1126593D01*
X321028Y1126450D01*
X320828D01*
Y1127485D01*
X321028D01*
G37*
G36*
G01X320628Y1122925D02*
X320228Y1123068D01*
Y1123818D01*
X320628Y1123960D01*
X320828D01*
Y1122925D01*
X320628D01*
G37*
G36*
G01Y1120575D02*
X320228Y1120718D01*
Y1121468D01*
X320628Y1121610D01*
X320828D01*
Y1120575D01*
X320628D01*
G37*
G36*
G01X321028Y1125135D02*
X321428Y1124993D01*
Y1124243D01*
X321028Y1124100D01*
X320828D01*
Y1125135D01*
X321028D01*
G37*
G36*
G01Y1122785D02*
X321428Y1122643D01*
Y1121893D01*
X321028Y1121750D01*
X320828D01*
Y1122785D01*
X321028D01*
G37*
G36*
G01Y1120435D02*
X321428Y1120293D01*
Y1119543D01*
X321028Y1119400D01*
X320828D01*
Y1120435D01*
X321028D01*
G37*
G36*
G01X320628Y1118225D02*
X320228Y1118368D01*
Y1119118D01*
X320628Y1119260D01*
X320828D01*
Y1118225D01*
X320628D01*
G37*
G36*
G01X318428Y1134090D02*
X318028Y1134233D01*
Y1134983D01*
X318428Y1135125D01*
X318628D01*
Y1134090D01*
X318428D01*
G37*
G36*
G01Y1131740D02*
X318028Y1131883D01*
Y1132633D01*
X318428Y1132775D01*
X318628D01*
Y1131740D01*
X318428D01*
G37*
G36*
G01Y1129390D02*
X318028Y1129533D01*
Y1130283D01*
X318428Y1130425D01*
X318628D01*
Y1129390D01*
X318428D01*
G37*
G36*
G01Y1136440D02*
X318028Y1136583D01*
Y1137333D01*
X318428Y1137475D01*
X318628D01*
Y1136440D01*
X318428D01*
G37*
G36*
G01Y1138790D02*
X318028Y1138933D01*
Y1139683D01*
X318428Y1139825D01*
X318628D01*
Y1138790D01*
X318428D01*
G37*
G36*
G01X318828Y1131600D02*
X319228Y1131458D01*
Y1130708D01*
X318828Y1130565D01*
X318628D01*
Y1131600D01*
X318828D01*
G37*
G36*
G01Y1133950D02*
X319228Y1133808D01*
Y1133058D01*
X318828Y1132915D01*
X318628D01*
Y1133950D01*
X318828D01*
G37*
G36*
G01Y1136300D02*
X319228Y1136158D01*
Y1135408D01*
X318828Y1135265D01*
X318628D01*
Y1136300D01*
X318828D01*
G37*
G36*
G01Y1138650D02*
X319228Y1138508D01*
Y1137758D01*
X318828Y1137615D01*
X318628D01*
Y1138650D01*
X318828D01*
G37*
G36*
G01X316028Y1131740D02*
X315628Y1131883D01*
Y1132633D01*
X316028Y1132775D01*
X316228D01*
Y1131740D01*
X316028D01*
G37*
G36*
G01Y1129390D02*
X315628Y1129533D01*
Y1130283D01*
X316028Y1130425D01*
X316228D01*
Y1129390D01*
X316028D01*
G37*
G36*
G01Y1134090D02*
X315628Y1134233D01*
Y1134983D01*
X316028Y1135125D01*
X316228D01*
Y1134090D01*
X316028D01*
G37*
G36*
G01X316428Y1131600D02*
X316828Y1131458D01*
Y1130708D01*
X316428Y1130565D01*
X316228D01*
Y1131600D01*
X316428D01*
G37*
G36*
G01Y1133950D02*
X316828Y1133808D01*
Y1133058D01*
X316428Y1132915D01*
X316228D01*
Y1133950D01*
X316428D01*
G37*
G36*
G01X316028Y1136440D02*
X315628Y1136583D01*
Y1137333D01*
X316028Y1137475D01*
X316228D01*
Y1136440D01*
X316028D01*
G37*
G36*
G01Y1138790D02*
X315628Y1138933D01*
Y1139683D01*
X316028Y1139825D01*
X316228D01*
Y1138790D01*
X316028D01*
G37*
G36*
G01X316428Y1138650D02*
X316828Y1138508D01*
Y1137758D01*
X316428Y1137615D01*
X316228D01*
Y1138650D01*
X316428D01*
G37*
G36*
G01Y1136300D02*
X316828Y1136158D01*
Y1135408D01*
X316428Y1135265D01*
X316228D01*
Y1136300D01*
X316428D01*
G37*
G36*
G01X317228Y1134090D02*
X316828Y1134233D01*
Y1134983D01*
X317228Y1135125D01*
X317428D01*
Y1134090D01*
X317228D01*
G37*
G36*
G01Y1131740D02*
X316828Y1131883D01*
Y1132633D01*
X317228Y1132775D01*
X317428D01*
Y1131740D01*
X317228D01*
G37*
G36*
G01Y1129390D02*
X316828Y1129533D01*
Y1130283D01*
X317228Y1130425D01*
X317428D01*
Y1129390D01*
X317228D01*
G37*
G36*
G01X317628Y1133950D02*
X318028Y1133808D01*
Y1133058D01*
X317628Y1132915D01*
X317428D01*
Y1133950D01*
X317628D01*
G37*
G36*
G01Y1131600D02*
X318028Y1131458D01*
Y1130708D01*
X317628Y1130565D01*
X317428D01*
Y1131600D01*
X317628D01*
G37*
G36*
G01X317228Y1138790D02*
X316828Y1138933D01*
Y1139683D01*
X317228Y1139825D01*
X317428D01*
Y1138790D01*
X317228D01*
G37*
G36*
G01X317628Y1138650D02*
X318028Y1138508D01*
Y1137758D01*
X317628Y1137615D01*
X317428D01*
Y1138650D01*
X317628D01*
G37*
G36*
G01Y1136300D02*
X318028Y1136158D01*
Y1135408D01*
X317628Y1135265D01*
X317428D01*
Y1136300D01*
X317628D01*
G37*
G36*
G01X317228Y1136440D02*
X316828Y1136583D01*
Y1137333D01*
X317228Y1137475D01*
X317428D01*
Y1136440D01*
X317228D01*
G37*
G36*
G01X314828Y1134090D02*
X314428Y1134233D01*
Y1134983D01*
X314828Y1135125D01*
X315028D01*
Y1134090D01*
X314828D01*
G37*
G36*
G01Y1131740D02*
X314428Y1131883D01*
Y1132633D01*
X314828Y1132775D01*
X315028D01*
Y1131740D01*
X314828D01*
G37*
G36*
G01Y1129390D02*
X314428Y1129533D01*
Y1130283D01*
X314828Y1130425D01*
X315028D01*
Y1129390D01*
X314828D01*
G37*
G36*
G01Y1136440D02*
X314428Y1136583D01*
Y1137333D01*
X314828Y1137475D01*
X315028D01*
Y1136440D01*
X314828D01*
G37*
G36*
G01X315228Y1131600D02*
X315628Y1131458D01*
Y1130708D01*
X315228Y1130565D01*
X315028D01*
Y1131600D01*
X315228D01*
G37*
G36*
G01Y1133950D02*
X315628Y1133808D01*
Y1133058D01*
X315228Y1132915D01*
X315028D01*
Y1133950D01*
X315228D01*
G37*
G36*
G01Y1136300D02*
X315628Y1136158D01*
Y1135408D01*
X315228Y1135265D01*
X315028D01*
Y1136300D01*
X315228D01*
G37*
G36*
G01X309228Y1132086D02*
X309628Y1131943D01*
Y1131193D01*
X309228Y1131051D01*
X309028D01*
Y1132086D01*
X309228D01*
G37*
G36*
G01Y1129736D02*
X309628Y1129593D01*
Y1128843D01*
X309228Y1128701D01*
X309028D01*
Y1129736D01*
X309228D01*
G37*
G36*
G01X308828Y1129876D02*
X308428Y1130019D01*
Y1130769D01*
X308828Y1130911D01*
X309028D01*
Y1129876D01*
X308828D01*
G37*
G36*
G01X321828Y1132325D02*
X321428Y1132468D01*
Y1133218D01*
X321828Y1133360D01*
X322028D01*
Y1132325D01*
X321828D01*
G37*
G36*
G01Y1129975D02*
X321428Y1130118D01*
Y1130868D01*
X321828Y1131010D01*
X322028D01*
Y1129975D01*
X321828D01*
G37*
G36*
G01Y1134675D02*
X321428Y1134818D01*
Y1135568D01*
X321828Y1135710D01*
X322028D01*
Y1134675D01*
X321828D01*
G37*
G36*
G01Y1137025D02*
X321428Y1137168D01*
Y1137918D01*
X321828Y1138060D01*
X322028D01*
Y1137025D01*
X321828D01*
G37*
G36*
G01Y1139375D02*
X321428Y1139518D01*
Y1140268D01*
X321828Y1140410D01*
X322028D01*
Y1139375D01*
X321828D01*
G37*
G36*
G01Y1141725D02*
X321428Y1141868D01*
Y1142618D01*
X321828Y1142760D01*
X322028D01*
Y1141725D01*
X321828D01*
G37*
G36*
G01Y1144075D02*
X321428Y1144218D01*
Y1144968D01*
X321828Y1145110D01*
X322028D01*
Y1144075D01*
X321828D01*
G37*
G36*
G01X321028Y1132185D02*
X321428Y1132043D01*
Y1131293D01*
X321028Y1131150D01*
X320828D01*
Y1132185D01*
X321028D01*
G37*
G36*
G01Y1134535D02*
X321428Y1134393D01*
Y1133643D01*
X321028Y1133500D01*
X320828D01*
Y1134535D01*
X321028D01*
G37*
G36*
G01X320628Y1132325D02*
X320228Y1132468D01*
Y1133218D01*
X320628Y1133360D01*
X320828D01*
Y1132325D01*
X320628D01*
G37*
G36*
G01Y1129975D02*
X320228Y1130118D01*
Y1130868D01*
X320628Y1131010D01*
X320828D01*
Y1129975D01*
X320628D01*
G37*
G36*
G01X321028Y1129835D02*
X321428Y1129693D01*
Y1128943D01*
X321028Y1128800D01*
X320828D01*
Y1129835D01*
X321028D01*
G37*
G36*
G01X320628Y1134675D02*
X320228Y1134818D01*
Y1135568D01*
X320628Y1135710D01*
X320828D01*
Y1134675D01*
X320628D01*
G37*
G36*
G01Y1137025D02*
X320228Y1137168D01*
Y1137918D01*
X320628Y1138060D01*
X320828D01*
Y1137025D01*
X320628D01*
G37*
G36*
G01Y1139375D02*
X320228Y1139518D01*
Y1140268D01*
X320628Y1140410D01*
X320828D01*
Y1139375D01*
X320628D01*
G37*
G36*
G01X321028Y1139235D02*
X321428Y1139093D01*
Y1138343D01*
X321028Y1138200D01*
X320828D01*
Y1139235D01*
X321028D01*
G37*
G36*
G01X320628Y1141725D02*
X320228Y1141868D01*
Y1142618D01*
X320628Y1142760D01*
X320828D01*
Y1141725D01*
X320628D01*
G37*
G36*
G01X321028Y1141585D02*
X321428Y1141443D01*
Y1140693D01*
X321028Y1140550D01*
X320828D01*
Y1141585D01*
X321028D01*
G37*
G36*
G01X320628Y1144075D02*
X320228Y1144218D01*
Y1144968D01*
X320628Y1145110D01*
X320828D01*
Y1144075D01*
X320628D01*
G37*
G36*
G01X321028Y1143935D02*
X321428Y1143793D01*
Y1143043D01*
X321028Y1142900D01*
X320828D01*
Y1143935D01*
X321028D01*
G37*
G36*
G01Y1136885D02*
X321428Y1136743D01*
Y1135993D01*
X321028Y1135850D01*
X320828D01*
Y1136885D01*
X321028D01*
G37*
G36*
G01X321828Y1146425D02*
X321428Y1146568D01*
Y1147318D01*
X321828Y1147460D01*
X322028D01*
Y1146425D01*
X321828D01*
G37*
G36*
G01Y1148775D02*
X321428Y1148918D01*
Y1149668D01*
X321828Y1149810D01*
X322028D01*
Y1148775D01*
X321828D01*
G37*
G36*
G01Y1151125D02*
X321428Y1151268D01*
Y1152018D01*
X321828Y1152160D01*
X322028D01*
Y1151125D01*
X321828D01*
G37*
G36*
G01Y1153475D02*
X321428Y1153618D01*
Y1154368D01*
X321828Y1154510D01*
X322028D01*
Y1153475D01*
X321828D01*
G37*
G36*
G01Y1155825D02*
X321428Y1155968D01*
Y1156718D01*
X321828Y1156860D01*
X322028D01*
Y1155825D01*
X321828D01*
G37*
G36*
G01X320628Y1146425D02*
X320228Y1146568D01*
Y1147318D01*
X320628Y1147460D01*
X320828D01*
Y1146425D01*
X320628D01*
G37*
G36*
G01Y1148775D02*
X320228Y1148918D01*
Y1149668D01*
X320628Y1149810D01*
X320828D01*
Y1148775D01*
X320628D01*
G37*
G36*
G01X321028Y1148635D02*
X321428Y1148493D01*
Y1147743D01*
X321028Y1147600D01*
X320828D01*
Y1148635D01*
X321028D01*
G37*
G36*
G01Y1150985D02*
X321428Y1150843D01*
Y1150093D01*
X321028Y1149950D01*
X320828D01*
Y1150985D01*
X321028D01*
G37*
G36*
G01X320628Y1151125D02*
X320228Y1151268D01*
Y1152018D01*
X320628Y1152160D01*
X320828D01*
Y1151125D01*
X320628D01*
G37*
G36*
G01X321028Y1146285D02*
X321428Y1146143D01*
Y1145393D01*
X321028Y1145250D01*
X320828D01*
Y1146285D01*
X321028D01*
G37*
G36*
G01X320628Y1153475D02*
X320228Y1153618D01*
Y1154368D01*
X320628Y1154510D01*
X320828D01*
Y1153475D01*
X320628D01*
G37*
G36*
G01Y1155825D02*
X320228Y1155968D01*
Y1156718D01*
X320628Y1156860D01*
X320828D01*
Y1155825D01*
X320628D01*
G37*
G36*
G01X321028Y1153335D02*
X321428Y1153193D01*
Y1152443D01*
X321028Y1152300D01*
X320828D01*
Y1153335D01*
X321028D01*
G37*
G36*
G01Y1155685D02*
X321428Y1155543D01*
Y1154793D01*
X321028Y1154650D01*
X320828D01*
Y1155685D01*
X321028D01*
G37*
G36*
G01X308840Y1320782D02*
X332453D01*
X336387Y1316848D01*
Y1292740D01*
X339219Y1289908D01*
X360219D01*
X361219Y1288908D01*
Y1283908D01*
X360492Y1283181D01*
X337078D01*
X330219Y1290040D01*
Y1311778D01*
X326615Y1315382D01*
X308790D01*
X308740Y1315432D01*
Y1320682D01*
X308840Y1320782D01*
G37*
G36*
G01X492746Y1425465D02*
X494001D01*
X494364Y1425102D01*
Y1412733D01*
X494369Y1412727D01*
Y1411933D01*
X494937Y1411365D01*
X497057D01*
X497477Y1410945D01*
Y1378385D01*
X498727Y1377135D01*
X514996D01*
X516322Y1378462D01*
X561470D01*
X562485Y1377447D01*
Y1351382D01*
X562025Y1350923D01*
X543970D01*
X543910Y1350982D01*
Y1359079D01*
X544147Y1359315D01*
X549465D01*
X550010Y1359860D01*
Y1360288D01*
X550011Y1360291D01*
G03Y1360300I-798J5D01*
G01Y1362894D01*
X551487Y1364371D01*
Y1371236D01*
X549214Y1373509D01*
X529362D01*
X525909Y1370056D01*
Y1347933D01*
X526250Y1347592D01*
Y1328943D01*
X525432Y1328125D01*
X511842D01*
X511762Y1328204D01*
Y1336261D01*
X512019Y1336517D01*
X517520D01*
X517882Y1336879D01*
Y1337490D01*
X517883Y1337493D01*
G03Y1337502I-798J5D01*
G01Y1339867D01*
G03X517856Y1340069I-799J-4D01*
G01X519325Y1341538D01*
Y1348393D01*
X515897Y1351821D01*
X499458D01*
G03X497316Y1350442I0J-2353D01*
G01X497301Y1350409D01*
X493781Y1346889D01*
Y1319679D01*
X493779Y1319678D01*
Y1319211D01*
X493781Y1319209D01*
Y1315074D01*
X493723Y1314932D01*
X493490Y1314699D01*
X479714D01*
X479645Y1314767D01*
Y1322846D01*
X479891Y1323091D01*
X485191D01*
X485754Y1323654D01*
Y1324064D01*
X485755Y1324067D01*
G03Y1324076I-798J5D01*
G01Y1326441D01*
G03X485747Y1326549I-799J-5D01*
G01X485735Y1326634D01*
Y1327465D01*
X487191Y1328921D01*
Y1335835D01*
X484473Y1338553D01*
X466652D01*
X461653Y1333554D01*
Y1319679D01*
X461651Y1319678D01*
Y1319211D01*
X461653Y1319209D01*
Y1315074D01*
X461595Y1314932D01*
X461362Y1314699D01*
X447586D01*
X447516Y1314768D01*
Y1322845D01*
X447763Y1323091D01*
X452895D01*
X453626Y1323822D01*
Y1324064D01*
X453627Y1324067D01*
G03Y1324076I-798J5D01*
G01Y1326670D01*
X453803Y1326846D01*
Y1327687D01*
X454841Y1328725D01*
Y1334427D01*
X451747Y1337521D01*
X436452D01*
G03X433568Y1337569I-1469J-1597D01*
G01X433057Y1337131D01*
X428640Y1332714D01*
Y1328946D01*
X429525Y1328061D01*
Y1319679D01*
X429523Y1319678D01*
Y1319211D01*
X429525Y1319209D01*
Y1315074D01*
X429467Y1314932D01*
X429234Y1314699D01*
X415458D01*
X415387Y1314769D01*
Y1322844D01*
X415635Y1323091D01*
X420960D01*
X421498Y1323629D01*
Y1324064D01*
X421499Y1324067D01*
G03Y1324076I-798J5D01*
G01Y1326441D01*
G03X421472Y1326643I-799J-4D01*
G01X421675Y1326846D01*
Y1326872D01*
X423114Y1328311D01*
Y1334254D01*
X419847Y1337521D01*
X404578D01*
G03X401737Y1337570I-1448J-1558D01*
G01X401409Y1337283D01*
X397397Y1333271D01*
Y1319679D01*
X397395Y1319678D01*
Y1319211D01*
X397397Y1319209D01*
Y1315074D01*
X397339Y1314932D01*
X397106Y1314699D01*
X383330D01*
X383253Y1314775D01*
Y1322755D01*
X383589Y1323091D01*
X388794D01*
X389370Y1323667D01*
Y1324064D01*
X389371Y1324067D01*
G03Y1324076I-798J5D01*
G01Y1326441D01*
G03X389344Y1326643I-799J-4D01*
G01X391912Y1329211D01*
Y1335499D01*
X390262Y1337149D01*
X382267D01*
X382245Y1337171D01*
X372463D01*
G03X369285I-1589J-1295D01*
G01X366065D01*
X365073Y1336179D01*
Y1328725D01*
X364473Y1328125D01*
X351801D01*
X351373Y1328553D01*
Y1336217D01*
X351491Y1336335D01*
X356855D01*
X357473Y1336953D01*
Y1339853D01*
X359073Y1341453D01*
Y1348818D01*
X357138Y1350753D01*
X340745D01*
G03X338917Y1351711I-1828J-1265D01*
G01X338915D01*
G03X338718Y1351702I3J-2223D01*
G01X338624Y1351694D01*
X337515Y1352803D01*
X335127D01*
X333247Y1350923D01*
X319074D01*
X319017Y1350979D01*
Y1359082D01*
X319251Y1359315D01*
X324664D01*
X325124Y1359775D01*
Y1363482D01*
X326487Y1364845D01*
Y1370845D01*
G03X343808Y1390340I-3987J20985D01*
G01X343813Y1390414D01*
X344744Y1391345D01*
X383696D01*
X398223Y1376818D01*
X447557D01*
X451100Y1380362D01*
X455100Y1384362D01*
X475000D01*
X492318Y1401680D01*
Y1425037D01*
X492746Y1425465D01*
G37*
G36*
G01X309439Y1580678D02*
G03I-720J0D01*
G37*
G36*
G01X314395D02*
G03I-720J0D01*
G37*
G36*
G01X309439Y1575686D02*
G03I-720J0D01*
G37*
G36*
G01X314395D02*
G03I-720J0D01*
G37*
G36*
G01X321499D02*
G03I-720J0D01*
G37*
G36*
G01Y1580678D02*
G03I-720J0D01*
G37*
G36*
G01X309439Y1592590D02*
G03I-720J0D01*
G37*
G36*
G01X314395D02*
G03I-720J0D01*
G37*
G36*
G01X309439Y1587598D02*
G03I-720J0D01*
G37*
G36*
G01X314395D02*
G03I-720J0D01*
G37*
G36*
G01X321499D02*
G03I-720J0D01*
G37*
G36*
G01Y1592590D02*
G03I-720J0D01*
G37*
G36*
G01X307635Y1599884D02*
G03I-720J0D01*
G37*
G36*
G01X319695D02*
G03I-720J0D01*
G37*
G36*
G01X314739D02*
G03I-720J0D01*
G37*
G36*
G01X307635Y1604876D02*
G03I-720J0D01*
G37*
G36*
G01Y1611796D02*
G03I-720J0D01*
G37*
G36*
G01Y1616788D02*
G03I-720J0D01*
G37*
G36*
G01X319695D02*
G03I-720J0D01*
G37*
G36*
G01X314739D02*
G03I-720J0D01*
G37*
G36*
G01X319695Y1604876D02*
G03I-720J0D01*
G37*
G36*
G01Y1611796D02*
G03I-720J0D01*
G37*
G36*
G01X314739Y1604876D02*
G03I-720J0D01*
G37*
G36*
G01Y1611796D02*
G03I-720J0D01*
G37*
G36*
G01X328435Y212069D02*
Y212569D01*
X328665Y212799D01*
X331855D01*
X334537D01*
X334690Y212646D01*
X335748D01*
X336285Y212109D01*
X339285D01*
X339785Y211609D01*
Y210109D01*
X339285Y209609D01*
X335045D01*
X330895D01*
X328435Y212069D01*
G37*
G36*
G01X342340Y225498D02*
X344878D01*
X345125Y225250D01*
X347837D01*
X348710Y224378D01*
Y215749D01*
X329641D01*
X329600Y215790D01*
X324784D01*
X324545Y216029D01*
Y216479D01*
X324755Y216689D01*
X331265D01*
X331354Y216778D01*
X331550D01*
X332386Y217614D01*
Y218914D01*
X332325Y218975D01*
Y218989D01*
X331575Y219739D01*
X331561D01*
X331560Y219740D01*
X326714D01*
X326525Y219929D01*
Y220549D01*
X326655Y220679D01*
X335289D01*
X335297Y220678D01*
G03X335412Y220674I110J1498D01*
G03X335527Y220678I5J1502D01*
G01X335535Y220679D01*
X335995D01*
X336236Y220920D01*
X336391D01*
G03X337279Y221288I0J1255D01*
G01X338524Y222532D01*
X338838D01*
G03X339734Y223422I6J890D01*
G01Y223543D01*
X340584Y224392D01*
X340714D01*
G03X341602Y224761I-1J1256D01*
G01X342340Y225498D01*
G37*
G36*
G01X332480Y705882D02*
G03I-720J0D01*
G37*
G36*
G01X323076Y852647D02*
X323476Y852504D01*
Y851754D01*
X323076Y851611D01*
X322876D01*
Y852647D01*
X323076D01*
G37*
G36*
G01X321876D02*
X322276Y852504D01*
Y851754D01*
X321876Y851611D01*
X321676D01*
Y852647D01*
X321876D01*
G37*
G36*
G01X324276D02*
X324676Y852504D01*
Y851754D01*
X324276Y851611D01*
X324076D01*
Y852647D01*
X324276D01*
G37*
G36*
G01X330276Y852645D02*
X330676Y852502D01*
Y851752D01*
X330276Y851609D01*
X330076D01*
Y852645D01*
X330276D01*
G37*
G36*
G01X332676D02*
X333076Y852502D01*
Y851752D01*
X332676Y851609D01*
X332476D01*
Y852645D01*
X332676D01*
G37*
G36*
G01X331476D02*
X331876Y852502D01*
Y851752D01*
X331476Y851609D01*
X331276D01*
Y852645D01*
X331476D01*
G37*
G36*
G01X322676Y852787D02*
X322276Y852929D01*
Y853679D01*
X322676Y853821D01*
X322876D01*
Y852787D01*
X322676D01*
G37*
G36*
G01X323076Y859697D02*
X323476Y859554D01*
Y858804D01*
X323076Y858661D01*
X322876D01*
Y859697D01*
X323076D01*
G37*
G36*
G01Y857347D02*
X323476Y857204D01*
Y856454D01*
X323076Y856311D01*
X322876D01*
Y857347D01*
X323076D01*
G37*
G36*
G01Y854997D02*
X323476Y854854D01*
Y854104D01*
X323076Y853961D01*
X322876D01*
Y854997D01*
X323076D01*
G37*
G36*
G01X322676Y857487D02*
X322276Y857629D01*
Y858379D01*
X322676Y858521D01*
X322876D01*
Y857487D01*
X322676D01*
G37*
G36*
G01Y855137D02*
X322276Y855279D01*
Y856029D01*
X322676Y856171D01*
X322876D01*
Y855137D01*
X322676D01*
G37*
G36*
G01X321876Y857347D02*
X322276Y857204D01*
Y856454D01*
X321876Y856311D01*
X321676D01*
Y857347D01*
X321876D01*
G37*
G36*
G01Y859697D02*
X322276Y859554D01*
Y858804D01*
X321876Y858661D01*
X321676D01*
Y859697D01*
X321876D01*
G37*
G36*
G01Y854997D02*
X322276Y854854D01*
Y854104D01*
X321876Y853961D01*
X321676D01*
Y854997D01*
X321876D01*
G37*
G36*
G01X323876Y852787D02*
X323476Y852929D01*
Y853679D01*
X323876Y853821D01*
X324076D01*
Y852787D01*
X323876D01*
G37*
G36*
G01X324276Y854997D02*
X324676Y854854D01*
Y854104D01*
X324276Y853961D01*
X324076D01*
Y854997D01*
X324276D01*
G37*
G36*
G01Y857347D02*
X324676Y857204D01*
Y856454D01*
X324276Y856311D01*
X324076D01*
Y857347D01*
X324276D01*
G37*
G36*
G01Y859697D02*
X324676Y859554D01*
Y858804D01*
X324276Y858661D01*
X324076D01*
Y859697D01*
X324276D01*
G37*
G36*
G01X323876Y855137D02*
X323476Y855279D01*
Y856029D01*
X323876Y856171D01*
X324076D01*
Y855137D01*
X323876D01*
G37*
G36*
G01Y857487D02*
X323476Y857629D01*
Y858379D01*
X323876Y858521D01*
X324076D01*
Y857487D01*
X323876D01*
G37*
G36*
G01X329876Y855135D02*
X329476Y855277D01*
Y856027D01*
X329876Y856169D01*
X330076D01*
Y855135D01*
X329876D01*
G37*
G36*
G01X330276Y857345D02*
X330676Y857202D01*
Y856452D01*
X330276Y856309D01*
X330076D01*
Y857345D01*
X330276D01*
G37*
G36*
G01Y859695D02*
X330676Y859552D01*
Y858802D01*
X330276Y858659D01*
X330076D01*
Y859695D01*
X330276D01*
G37*
G36*
G01Y854995D02*
X330676Y854852D01*
Y854102D01*
X330276Y853959D01*
X330076D01*
Y854995D01*
X330276D01*
G37*
G36*
G01X329876Y852785D02*
X329476Y852927D01*
Y853677D01*
X329876Y853819D01*
X330076D01*
Y852785D01*
X329876D01*
G37*
G36*
G01Y857485D02*
X329476Y857627D01*
Y858377D01*
X329876Y858519D01*
X330076D01*
Y857485D01*
X329876D01*
G37*
G36*
G01X332276Y852785D02*
X331876Y852927D01*
Y853677D01*
X332276Y853819D01*
X332476D01*
Y852785D01*
X332276D01*
G37*
G36*
G01Y857485D02*
X331876Y857627D01*
Y858377D01*
X332276Y858519D01*
X332476D01*
Y857485D01*
X332276D01*
G37*
G36*
G01Y855135D02*
X331876Y855277D01*
Y856027D01*
X332276Y856169D01*
X332476D01*
Y855135D01*
X332276D01*
G37*
G36*
G01X332676Y859695D02*
X333076Y859552D01*
Y858802D01*
X332676Y858659D01*
X332476D01*
Y859695D01*
X332676D01*
G37*
G36*
G01Y857345D02*
X333076Y857202D01*
Y856452D01*
X332676Y856309D01*
X332476D01*
Y857345D01*
X332676D01*
G37*
G36*
G01Y854995D02*
X333076Y854852D01*
Y854102D01*
X332676Y853959D01*
X332476D01*
Y854995D01*
X332676D01*
G37*
G36*
G01X331076Y852785D02*
X330676Y852927D01*
Y853677D01*
X331076Y853819D01*
X331276D01*
Y852785D01*
X331076D01*
G37*
G36*
G01Y857485D02*
X330676Y857627D01*
Y858377D01*
X331076Y858519D01*
X331276D01*
Y857485D01*
X331076D01*
G37*
G36*
G01Y855135D02*
X330676Y855277D01*
Y856027D01*
X331076Y856169D01*
X331276D01*
Y855135D01*
X331076D01*
G37*
G36*
G01X331476Y857345D02*
X331876Y857202D01*
Y856452D01*
X331476Y856309D01*
X331276D01*
Y857345D01*
X331476D01*
G37*
G36*
G01Y859695D02*
X331876Y859552D01*
Y858802D01*
X331476Y858659D01*
X331276D01*
Y859695D01*
X331476D01*
G37*
G36*
G01Y854995D02*
X331876Y854852D01*
Y854102D01*
X331476Y853959D01*
X331276D01*
Y854995D01*
X331476D01*
G37*
G36*
G01X333476Y852785D02*
X333076Y852927D01*
Y853677D01*
X333476Y853819D01*
X333676D01*
Y852785D01*
X333476D01*
G37*
G36*
G01X333876Y857345D02*
X334276Y857202D01*
Y856452D01*
X333876Y856309D01*
X333676D01*
Y857345D01*
X333876D01*
G37*
G36*
G01Y854995D02*
X334276Y854852D01*
Y854102D01*
X333876Y853959D01*
X333676D01*
Y854995D01*
X333876D01*
G37*
G36*
G01X333476Y857485D02*
X333076Y857627D01*
Y858377D01*
X333476Y858519D01*
X333676D01*
Y857485D01*
X333476D01*
G37*
G36*
G01Y855135D02*
X333076Y855277D01*
Y856027D01*
X333476Y856169D01*
X333676D01*
Y855135D01*
X333476D01*
G37*
G36*
G01X325411Y899865D02*
X325229Y900249D01*
X325759Y900779D01*
X326143Y900597D01*
X326284Y900455D01*
X325553Y899724D01*
X325411Y899865D01*
G37*
G36*
G01X323750Y898203D02*
X323567Y898587D01*
X324098Y899117D01*
X324481Y898935D01*
X324623Y898794D01*
X323891Y898062D01*
X323750Y898203D01*
G37*
G36*
G01X325595Y899483D02*
X325777Y899100D01*
X325247Y898569D01*
X324863Y898751D01*
X324722Y898893D01*
X325454Y899625D01*
X325595Y899483D01*
G37*
G36*
G01X322088Y896542D02*
X321906Y896925D01*
X322436Y897456D01*
X322820Y897273D01*
X322961Y897132D01*
X322229Y896400D01*
X322088Y896542D01*
G37*
G36*
G01X323933Y897822D02*
X324115Y897438D01*
X323585Y896908D01*
X323201Y897090D01*
X323060Y897231D01*
X323792Y897963D01*
X323933Y897822D01*
G37*
G36*
G01X323970Y894461D02*
X324152Y894078D01*
X323622Y893547D01*
X323238Y893729D01*
X323097Y893871D01*
X323829Y894603D01*
X323970Y894461D01*
G37*
G36*
G01X323786Y894843D02*
X323604Y895227D01*
X324135Y895757D01*
X324518Y895575D01*
X324660Y895434D01*
X323928Y894702D01*
X323786Y894843D01*
G37*
G36*
G01X325448Y896505D02*
X325266Y896888D01*
X325796Y897419D01*
X326180Y897237D01*
X326321Y897095D01*
X325589Y896363D01*
X325448Y896505D01*
G37*
G36*
G01X327110Y898167D02*
X326928Y898550D01*
X327458Y899080D01*
X327842Y898898D01*
X327983Y898757D01*
X327251Y898025D01*
X327110Y898167D01*
G37*
G36*
G01X325632Y896123D02*
X325814Y895739D01*
X325284Y895209D01*
X324900Y895391D01*
X324759Y895533D01*
X325490Y896264D01*
X325632Y896123D01*
G37*
G36*
G01X327294Y897785D02*
X327476Y897401D01*
X326945Y896871D01*
X326562Y897053D01*
X326420Y897194D01*
X327152Y897926D01*
X327294Y897785D01*
G37*
G36*
G01X322125Y893181D02*
X321943Y893565D01*
X322473Y894095D01*
X322856Y893913D01*
X322998Y893772D01*
X322266Y893040D01*
X322125Y893181D01*
G37*
G36*
G01X324599Y897354D02*
X324417Y897737D01*
X324947Y898268D01*
X325331Y898086D01*
X325472Y897944D01*
X324740Y897212D01*
X324599Y897354D01*
G37*
G36*
G01X324783Y896972D02*
X324965Y896588D01*
X324435Y896058D01*
X324051Y896240D01*
X323910Y896382D01*
X324641Y897113D01*
X324783Y896972D01*
G37*
G36*
G01X322937Y895692D02*
X322755Y896076D01*
X323286Y896606D01*
X323669Y896424D01*
X323811Y896283D01*
X323079Y895551D01*
X322937Y895692D01*
G37*
G36*
G01X323121Y895310D02*
X323303Y894927D01*
X322773Y894396D01*
X322389Y894578D01*
X322248Y894720D01*
X322980Y895452D01*
X323121Y895310D01*
G37*
G36*
G01X328143Y896936D02*
X328325Y896552D01*
X327794Y896022D01*
X327411Y896204D01*
X327269Y896345D01*
X328001Y897077D01*
X328143Y896936D01*
G37*
G36*
G01X326481Y895274D02*
X326663Y894890D01*
X326133Y894360D01*
X325749Y894542D01*
X325608Y894684D01*
X326339Y895415D01*
X326481Y895274D01*
G37*
G36*
G01X324819Y893612D02*
X325001Y893229D01*
X324471Y892698D01*
X324087Y892880D01*
X323946Y893022D01*
X324678Y893754D01*
X324819Y893612D01*
G37*
G36*
G01X323157Y891951D02*
X323340Y891567D01*
X322809Y891037D01*
X322426Y891219D01*
X322284Y891360D01*
X323016Y892092D01*
X323157Y891951D01*
G37*
G36*
G01X326297Y895656D02*
X326115Y896039D01*
X326645Y896570D01*
X327029Y896388D01*
X327170Y896246D01*
X326438Y895514D01*
X326297Y895656D01*
G37*
G36*
G01X327959Y897318D02*
X327777Y897701D01*
X328307Y898231D01*
X328691Y898049D01*
X328832Y897908D01*
X328100Y897176D01*
X327959Y897318D01*
G37*
G36*
G01X324635Y893994D02*
X324453Y894378D01*
X324984Y894908D01*
X325367Y894726D01*
X325509Y894585D01*
X324777Y893853D01*
X324635Y893994D01*
G37*
G36*
G01X322974Y892332D02*
X322792Y892716D01*
X323322Y893246D01*
X323705Y893064D01*
X323847Y892923D01*
X323115Y892191D01*
X322974Y892332D01*
G37*
G36*
G01X322986Y915495D02*
X323168Y915111D01*
X322637Y914581D01*
X322254Y914763D01*
X322112Y914904D01*
X322844Y915636D01*
X322986Y915495D01*
G37*
G36*
G01X324647Y917156D02*
X324829Y916773D01*
X324299Y916242D01*
X323915Y916425D01*
X323774Y916566D01*
X324506Y917298D01*
X324647Y917156D01*
G37*
G36*
G01X322802Y915876D02*
X322620Y916260D01*
X323150Y916790D01*
X323534Y916608D01*
X323675Y916467D01*
X322943Y915735D01*
X322802Y915876D01*
G37*
G36*
G01X321953Y916725D02*
X321771Y917109D01*
X322301Y917639D01*
X322685Y917457D01*
X322826Y917316D01*
X322094Y916584D01*
X321953Y916725D01*
G37*
G36*
G01X323835Y914646D02*
X324017Y914262D01*
X323486Y913732D01*
X323103Y913914D01*
X322961Y914055D01*
X323693Y914787D01*
X323835Y914646D01*
G37*
G36*
G01X321989Y913366D02*
X321807Y913749D01*
X322337Y914280D01*
X322721Y914098D01*
X322862Y913956D01*
X322130Y913224D01*
X321989Y913366D01*
G37*
G36*
G01X323651Y915027D02*
X323469Y915411D01*
X323999Y915941D01*
X324383Y915759D01*
X324524Y915618D01*
X323792Y914886D01*
X323651Y915027D01*
G37*
G36*
G01X322841Y910879D02*
X322659Y911263D01*
X323189Y911793D01*
X323573Y911611D01*
X323714Y911469D01*
X322983Y910738D01*
X322841Y910879D01*
G37*
G36*
G01X323025Y910497D02*
X323207Y910114D01*
X322677Y909583D01*
X322293Y909765D01*
X322152Y909907D01*
X322884Y910639D01*
X323025Y910497D01*
G37*
G36*
G01X324503Y912541D02*
X324321Y912924D01*
X324851Y913455D01*
X325235Y913273D01*
X325376Y913131D01*
X324644Y912399D01*
X324503Y912541D01*
G37*
G36*
G01X324687Y912159D02*
X324869Y911775D01*
X324338Y911245D01*
X323955Y911427D01*
X323813Y911568D01*
X324545Y912300D01*
X324687Y912159D01*
G37*
G36*
G01X326348Y913821D02*
X326530Y913437D01*
X326000Y912907D01*
X325616Y913089D01*
X325475Y913230D01*
X326207Y913962D01*
X326348Y913821D01*
G37*
G36*
G01X323061Y907137D02*
X323243Y906754D01*
X322713Y906223D01*
X322329Y906406D01*
X322188Y906547D01*
X322920Y907279D01*
X323061Y907137D01*
G37*
G36*
G01X322877Y907519D02*
X322695Y907903D01*
X323226Y908433D01*
X323609Y908251D01*
X323751Y908110D01*
X323019Y907378D01*
X322877Y907519D01*
G37*
G36*
G01X324539Y909181D02*
X324357Y909565D01*
X324887Y910095D01*
X325271Y909913D01*
X325412Y909771D01*
X324681Y909040D01*
X324539Y909181D01*
G37*
G36*
G01X326201Y910843D02*
X326019Y911226D01*
X326549Y911757D01*
X326933Y911575D01*
X327074Y911433D01*
X326342Y910701D01*
X326201Y910843D01*
G37*
G36*
G01X324723Y908799D02*
X324905Y908416D01*
X324375Y907885D01*
X323991Y908067D01*
X323850Y908209D01*
X324582Y908941D01*
X324723Y908799D01*
G37*
G36*
G01X326385Y910461D02*
X326567Y910077D01*
X326036Y909547D01*
X325653Y909729D01*
X325511Y909870D01*
X326243Y910602D01*
X326385Y910461D01*
G37*
G36*
G01X325536Y911310D02*
X325718Y910926D01*
X325187Y910396D01*
X324804Y910578D01*
X324662Y910719D01*
X325394Y911451D01*
X325536Y911310D01*
G37*
G36*
G01X322028Y908368D02*
X321846Y908752D01*
X322377Y909282D01*
X322760Y909100D01*
X322902Y908959D01*
X322170Y908227D01*
X322028Y908368D01*
G37*
G36*
G01X323690Y910030D02*
X323508Y910414D01*
X324038Y910944D01*
X324422Y910762D01*
X324563Y910620D01*
X323832Y909889D01*
X323690Y910030D01*
G37*
G36*
G01X323874Y909648D02*
X324056Y909265D01*
X323526Y908734D01*
X323142Y908916D01*
X323001Y909058D01*
X323733Y909790D01*
X323874Y909648D01*
G37*
G36*
G01X325352Y911692D02*
X325170Y912075D01*
X325700Y912606D01*
X326084Y912424D01*
X326225Y912282D01*
X325493Y911550D01*
X325352Y911692D01*
G37*
G36*
G01X325388Y908332D02*
X325206Y908716D01*
X325736Y909246D01*
X326120Y909064D01*
X326261Y908922D01*
X325530Y908191D01*
X325388Y908332D01*
G37*
G36*
G01X323726Y906670D02*
X323544Y907054D01*
X324075Y907584D01*
X324458Y907402D01*
X324600Y907261D01*
X323868Y906529D01*
X323726Y906670D01*
G37*
G36*
G01X323910Y906288D02*
X324092Y905905D01*
X323562Y905374D01*
X323178Y905557D01*
X323037Y905698D01*
X323769Y906430D01*
X323910Y906288D01*
G37*
G36*
G01X322065Y905009D02*
X321883Y905392D01*
X322413Y905922D01*
X322797Y905740D01*
X322938Y905599D01*
X322206Y904867D01*
X322065Y905009D01*
G37*
G36*
G01X325572Y907950D02*
X325754Y907567D01*
X325224Y907036D01*
X324840Y907218D01*
X324699Y907360D01*
X325431Y908092D01*
X325572Y907950D01*
G37*
G36*
G01X327234Y909612D02*
X327416Y909228D01*
X326885Y908698D01*
X326502Y908880D01*
X326360Y909021D01*
X327092Y909753D01*
X327234Y909612D01*
G37*
G36*
G01X323649Y928045D02*
X323831Y927662D01*
X323301Y927131D01*
X322917Y927313D01*
X322776Y927455D01*
X323508Y928187D01*
X323649Y928045D01*
G37*
G36*
G01X322949Y918855D02*
X323131Y918471D01*
X322600Y917941D01*
X322217Y918123D01*
X322075Y918264D01*
X322807Y918996D01*
X322949Y918855D01*
G37*
G36*
G01X323798Y918005D02*
X323980Y917622D01*
X323450Y917091D01*
X323066Y917274D01*
X322925Y917415D01*
X323657Y918147D01*
X323798Y918005D01*
G37*
G36*
G01X322764Y932254D02*
X322946Y931870D01*
X322415Y931340D01*
X322032Y931522D01*
X321890Y931663D01*
X322622Y932395D01*
X322764Y932254D01*
G37*
G36*
G01X322800Y928894D02*
X322982Y928511D01*
X322452Y927980D01*
X322068Y928162D01*
X321927Y928304D01*
X322659Y929036D01*
X322800Y928894D01*
G37*
G36*
G01X324862Y940004D02*
X325004Y940404D01*
X325754D01*
X325896Y940004D01*
Y939804D01*
X324862D01*
Y940004D01*
G37*
G36*
G01X322512D02*
X322654Y940404D01*
X323404D01*
X323546Y940004D01*
Y939804D01*
X322512D01*
Y940004D01*
G37*
G36*
G01X324722Y939604D02*
X324579Y939204D01*
X323829D01*
X323686Y939604D01*
Y939804D01*
X324722D01*
Y939604D01*
G37*
G36*
G01X322512Y937604D02*
X322654Y938004D01*
X323404D01*
X323546Y937604D01*
Y937404D01*
X322512D01*
Y937604D01*
G37*
G36*
G01X324862D02*
X325004Y938004D01*
X325754D01*
X325896Y937604D01*
Y937404D01*
X324862D01*
Y937604D01*
G37*
G36*
G01X324722Y937204D02*
X324579Y936804D01*
X323829D01*
X323686Y937204D01*
Y937404D01*
X324722D01*
Y937204D01*
G37*
G36*
G01X322512Y938804D02*
X322654Y939204D01*
X323404D01*
X323546Y938804D01*
Y938604D01*
X322512D01*
Y938804D01*
G37*
G36*
G01X324862D02*
X325004Y939204D01*
X325754D01*
X325896Y938804D01*
Y938604D01*
X324862D01*
Y938804D01*
G37*
G36*
G01X324722Y938404D02*
X324579Y938004D01*
X323829D01*
X323686Y938404D01*
Y938604D01*
X324722D01*
Y938404D01*
G37*
G36*
G01Y936004D02*
X324579Y935604D01*
X323829D01*
X323686Y936004D01*
Y936204D01*
X324722D01*
Y936004D01*
G37*
G36*
G01X324862Y936404D02*
X325004Y936804D01*
X325754D01*
X325896Y936404D01*
Y936204D01*
X324862D01*
Y936404D01*
G37*
G36*
G01X327072Y936004D02*
X326929Y935604D01*
X326179D01*
X326036Y936004D01*
Y936204D01*
X327072D01*
Y936004D01*
G37*
G36*
G01X326348Y954479D02*
X326732Y954661D01*
X327262Y954130D01*
X327080Y953747D01*
X326939Y953605D01*
X326207Y954337D01*
X326348Y954479D01*
G37*
G36*
G01X325966Y954295D02*
X325583Y954113D01*
X325053Y954643D01*
X325235Y955027D01*
X325376Y955168D01*
X326108Y954436D01*
X325966Y954295D01*
G37*
G36*
G01X327628Y952633D02*
X327245Y952451D01*
X326714Y952981D01*
X326896Y953365D01*
X327038Y953506D01*
X327770Y952774D01*
X327628Y952633D01*
G37*
G36*
G01X326311Y951118D02*
X326695Y951300D01*
X327225Y950770D01*
X327043Y950386D01*
X326901Y950245D01*
X326170Y950976D01*
X326311Y951118D01*
G37*
G36*
G01X325929Y950934D02*
X325545Y950752D01*
X325015Y951282D01*
X325197Y951666D01*
X325339Y951807D01*
X326071Y951075D01*
X325929Y950934D01*
G37*
G36*
G01X324650Y952780D02*
X325033Y952962D01*
X325564Y952432D01*
X325382Y952048D01*
X325240Y951906D01*
X324508Y952638D01*
X324650Y952780D01*
G37*
G36*
G01X326779Y951784D02*
X326395Y951601D01*
X325865Y952132D01*
X326047Y952515D01*
X326188Y952657D01*
X326920Y951925D01*
X326779Y951784D01*
G37*
G36*
G01X325117Y953445D02*
X324733Y953263D01*
X324203Y953793D01*
X324385Y954177D01*
X324527Y954318D01*
X325258Y953587D01*
X325117Y953445D01*
G37*
G36*
G01X325499Y953629D02*
X325882Y953811D01*
X326413Y953281D01*
X326231Y952897D01*
X326089Y952756D01*
X325357Y953488D01*
X325499Y953629D01*
G37*
G36*
G01X325462Y950268D02*
X325846Y950450D01*
X326376Y949920D01*
X326194Y949536D01*
X326052Y949395D01*
X325321Y950126D01*
X325462Y950268D01*
G37*
G36*
G01X321704Y1014119D02*
X321846Y1014519D01*
X322596D01*
X322739Y1014119D01*
Y1013919D01*
X321704D01*
Y1014119D01*
G37*
G36*
G01Y1012919D02*
X321846Y1013319D01*
X322596D01*
X322739Y1012919D01*
Y1012719D01*
X321704D01*
Y1012919D01*
G37*
G36*
G01Y1011719D02*
X321846Y1012119D01*
X322596D01*
X322739Y1011719D01*
Y1011519D01*
X321704D01*
Y1011719D01*
G37*
G36*
G01X323914Y1017319D02*
X323772Y1016919D01*
X323022D01*
X322879Y1017319D01*
Y1017519D01*
X323914D01*
Y1017319D01*
G37*
G36*
G01X321704Y1017719D02*
X321846Y1018119D01*
X322596D01*
X322739Y1017719D01*
Y1017519D01*
X321704D01*
Y1017719D01*
G37*
G36*
G01X324054D02*
X324196Y1018119D01*
X324946D01*
X325089Y1017719D01*
Y1017519D01*
X324054D01*
Y1017719D01*
G37*
G36*
G01X321704Y1016519D02*
X321846Y1016919D01*
X322596D01*
X322739Y1016519D01*
Y1016319D01*
X321704D01*
Y1016519D01*
G37*
G36*
G01X323914Y1016119D02*
X323772Y1015719D01*
X323022D01*
X322879Y1016119D01*
Y1016319D01*
X323914D01*
Y1016119D01*
G37*
G36*
G01X321704Y1015319D02*
X321846Y1015719D01*
X322596D01*
X322739Y1015319D01*
Y1015119D01*
X321704D01*
Y1015319D01*
G37*
G36*
G01X323914Y1014919D02*
X323772Y1014519D01*
X323022D01*
X322879Y1014919D01*
Y1015119D01*
X323914D01*
Y1014919D01*
G37*
G36*
G01Y1022119D02*
X323772Y1021719D01*
X323022D01*
X322879Y1022119D01*
Y1022319D01*
X323914D01*
Y1022119D01*
G37*
G36*
G01X321704Y1022519D02*
X321846Y1022919D01*
X322596D01*
X322739Y1022519D01*
Y1022319D01*
X321704D01*
Y1022519D01*
G37*
G36*
G01X326264Y1022119D02*
X326122Y1021719D01*
X325372D01*
X325229Y1022119D01*
Y1022319D01*
X326264D01*
Y1022119D01*
G37*
G36*
G01X326404Y1022519D02*
X326546Y1022919D01*
X327296D01*
X327439Y1022519D01*
Y1022319D01*
X326404D01*
Y1022519D01*
G37*
G36*
G01X324054D02*
X324196Y1022919D01*
X324946D01*
X325089Y1022519D01*
Y1022319D01*
X324054D01*
Y1022519D01*
G37*
G36*
G01X328754D02*
X328896Y1022919D01*
X329646D01*
X329789Y1022519D01*
Y1022319D01*
X328754D01*
Y1022519D01*
G37*
G36*
G01X328614Y1022119D02*
X328472Y1021719D01*
X327722D01*
X327579Y1022119D01*
Y1022319D01*
X328614D01*
Y1022119D01*
G37*
G36*
G01X321704Y1018919D02*
X321846Y1019319D01*
X322596D01*
X322739Y1018919D01*
Y1018719D01*
X321704D01*
Y1018919D01*
G37*
G36*
G01X324054D02*
X324196Y1019319D01*
X324946D01*
X325089Y1018919D01*
Y1018719D01*
X324054D01*
Y1018919D01*
G37*
G36*
G01X323914Y1018519D02*
X323772Y1018119D01*
X323022D01*
X322879Y1018519D01*
Y1018719D01*
X323914D01*
Y1018519D01*
G37*
G36*
G01X321704Y1021319D02*
X321846Y1021719D01*
X322596D01*
X322739Y1021319D01*
Y1021119D01*
X321704D01*
Y1021319D01*
G37*
G36*
G01X323914Y1020919D02*
X323772Y1020519D01*
X323022D01*
X322879Y1020919D01*
Y1021119D01*
X323914D01*
Y1020919D01*
G37*
G36*
G01X324054Y1021319D02*
X324196Y1021719D01*
X324946D01*
X325089Y1021319D01*
Y1021119D01*
X324054D01*
Y1021319D01*
G37*
G36*
G01X326264Y1020919D02*
X326122Y1020519D01*
X325372D01*
X325229Y1020919D01*
Y1021119D01*
X326264D01*
Y1020919D01*
G37*
G36*
G01X321704Y1020119D02*
X321846Y1020519D01*
X322596D01*
X322739Y1020119D01*
Y1019919D01*
X321704D01*
Y1020119D01*
G37*
G36*
G01X323914Y1019719D02*
X323772Y1019319D01*
X323022D01*
X322879Y1019719D01*
Y1019919D01*
X323914D01*
Y1019719D01*
G37*
G36*
G01X324054Y1020119D02*
X324196Y1020519D01*
X324946D01*
X325089Y1020119D01*
Y1019919D01*
X324054D01*
Y1020119D01*
G37*
G36*
G01X326264Y1019719D02*
X326122Y1019319D01*
X325372D01*
X325229Y1019719D01*
Y1019919D01*
X326264D01*
Y1019719D01*
G37*
G36*
G01X322835Y1043496D02*
X322451Y1043314D01*
X321921Y1043844D01*
X322103Y1044228D01*
X322244Y1044369D01*
X322976Y1043637D01*
X322835Y1043496D01*
G37*
G36*
G01X323216Y1043679D02*
X323600Y1043862D01*
X324130Y1043331D01*
X323948Y1042948D01*
X323807Y1042806D01*
X323075Y1043538D01*
X323216Y1043679D01*
G37*
G36*
G01X324496Y1041834D02*
X324113Y1041652D01*
X323582Y1042182D01*
X323764Y1042566D01*
X323906Y1042707D01*
X324638Y1041975D01*
X324496Y1041834D01*
G37*
G36*
G01X322798Y1040135D02*
X322414Y1039953D01*
X321884Y1040484D01*
X322066Y1040867D01*
X322207Y1041009D01*
X322939Y1040277D01*
X322798Y1040135D01*
G37*
G36*
G01X323180Y1040319D02*
X323563Y1040501D01*
X324093Y1039971D01*
X323911Y1039587D01*
X323770Y1039446D01*
X323038Y1040178D01*
X323180Y1040319D01*
G37*
G36*
G01X324459Y1038474D02*
X324076Y1038292D01*
X323545Y1038822D01*
X323728Y1039206D01*
X323869Y1039347D01*
X324601Y1038615D01*
X324459Y1038474D01*
G37*
G36*
G01X322367Y1042830D02*
X322751Y1043013D01*
X323281Y1042482D01*
X323099Y1042099D01*
X322958Y1041957D01*
X322226Y1042689D01*
X322367Y1042830D01*
G37*
G36*
G01X324029Y1041169D02*
X324413Y1041351D01*
X324943Y1040821D01*
X324761Y1040437D01*
X324619Y1040296D01*
X323888Y1041027D01*
X324029Y1041169D01*
G37*
G36*
G01X323647Y1040985D02*
X323264Y1040803D01*
X322733Y1041333D01*
X322915Y1041717D01*
X323057Y1041858D01*
X323789Y1041126D01*
X323647Y1040985D01*
G37*
G36*
G01X323610Y1037625D02*
X323227Y1037443D01*
X322696Y1037973D01*
X322879Y1038357D01*
X323020Y1038498D01*
X323752Y1037766D01*
X323610Y1037625D01*
G37*
G36*
G01X322331Y1039470D02*
X322714Y1039652D01*
X323244Y1039122D01*
X323062Y1038738D01*
X322921Y1038597D01*
X322189Y1039329D01*
X322331Y1039470D01*
G37*
G36*
G01X328164Y1063262D02*
X328548Y1063445D01*
X329078Y1062914D01*
X328896Y1062531D01*
X328755Y1062389D01*
X328023Y1063121D01*
X328164Y1063262D01*
G37*
G36*
G01X327783Y1063079D02*
X327399Y1062897D01*
X326869Y1063427D01*
X327051Y1063811D01*
X327192Y1063952D01*
X327924Y1063220D01*
X327783Y1063079D01*
G37*
G36*
G01X325653Y1064074D02*
X326036Y1064256D01*
X326567Y1063726D01*
X326385Y1063342D01*
X326243Y1063201D01*
X325511Y1063933D01*
X325653Y1064074D01*
G37*
G36*
G01X322687Y1058546D02*
X323071Y1058728D01*
X323601Y1058197D01*
X323419Y1057814D01*
X323278Y1057672D01*
X322546Y1058404D01*
X322687Y1058546D01*
G37*
G36*
G01X324349Y1056884D02*
X324732Y1057066D01*
X325263Y1056536D01*
X325081Y1056152D01*
X324939Y1056011D01*
X324207Y1056743D01*
X324349Y1056884D01*
G37*
G36*
G01X326011Y1055222D02*
X326394Y1055404D01*
X326924Y1054874D01*
X326742Y1054490D01*
X326601Y1054349D01*
X325869Y1055081D01*
X326011Y1055222D01*
G37*
G36*
G01X323967Y1056700D02*
X323583Y1056518D01*
X323053Y1057048D01*
X323235Y1057432D01*
X323377Y1057573D01*
X324108Y1056842D01*
X323967Y1056700D01*
G37*
G36*
G01X325629Y1055038D02*
X325245Y1054856D01*
X324715Y1055387D01*
X324897Y1055770D01*
X325038Y1055912D01*
X325770Y1055180D01*
X325629Y1055038D01*
G37*
G36*
G01X327290Y1053377D02*
X326907Y1053195D01*
X326376Y1053725D01*
X326559Y1054109D01*
X326700Y1054250D01*
X327432Y1053518D01*
X327290Y1053377D01*
G37*
G36*
G01X322649Y1055184D02*
X323033Y1055367D01*
X323563Y1054836D01*
X323381Y1054453D01*
X323240Y1054311D01*
X322508Y1055043D01*
X322649Y1055184D01*
G37*
G36*
G01X324311Y1053523D02*
X324695Y1053705D01*
X325225Y1053175D01*
X325043Y1052791D01*
X324901Y1052650D01*
X324170Y1053381D01*
X324311Y1053523D01*
G37*
G36*
G01X323929Y1053339D02*
X323546Y1053157D01*
X323015Y1053687D01*
X323197Y1054071D01*
X323339Y1054212D01*
X324071Y1053480D01*
X323929Y1053339D01*
G37*
G36*
G01X325591Y1051677D02*
X325207Y1051495D01*
X324677Y1052025D01*
X324859Y1052409D01*
X325000Y1052551D01*
X325732Y1051819D01*
X325591Y1051677D01*
G37*
G36*
G01X321838Y1057697D02*
X322222Y1057879D01*
X322752Y1057348D01*
X322570Y1056965D01*
X322429Y1056823D01*
X321697Y1057555D01*
X321838Y1057697D01*
G37*
G36*
G01X323500Y1056035D02*
X323883Y1056217D01*
X324414Y1055687D01*
X324232Y1055303D01*
X324090Y1055162D01*
X323358Y1055894D01*
X323500Y1056035D01*
G37*
G36*
G01X325162Y1054373D02*
X325545Y1054555D01*
X326075Y1054025D01*
X325893Y1053641D01*
X325752Y1053500D01*
X325020Y1054232D01*
X325162Y1054373D01*
G37*
G36*
G01X323118Y1055851D02*
X322734Y1055669D01*
X322204Y1056199D01*
X322386Y1056583D01*
X322528Y1056724D01*
X323259Y1055993D01*
X323118Y1055851D01*
G37*
G36*
G01X324780Y1054189D02*
X324396Y1054007D01*
X323866Y1054538D01*
X324048Y1054921D01*
X324189Y1055063D01*
X324921Y1054331D01*
X324780Y1054189D01*
G37*
G36*
G01X326441Y1052528D02*
X326058Y1052346D01*
X325527Y1052876D01*
X325710Y1053260D01*
X325851Y1053401D01*
X326583Y1052669D01*
X326441Y1052528D01*
G37*
G36*
G01X324741Y1050828D02*
X324358Y1050646D01*
X323827Y1051176D01*
X324010Y1051560D01*
X324151Y1051701D01*
X324883Y1050969D01*
X324741Y1050828D01*
G37*
G36*
G01X323080Y1052489D02*
X322696Y1052307D01*
X322166Y1052838D01*
X322348Y1053221D01*
X322489Y1053363D01*
X323221Y1052631D01*
X323080Y1052489D01*
G37*
G36*
G01X321800Y1054335D02*
X322183Y1054517D01*
X322714Y1053987D01*
X322532Y1053603D01*
X322390Y1053462D01*
X321658Y1054194D01*
X321800Y1054335D01*
G37*
G36*
G01X323462Y1052673D02*
X323845Y1052855D01*
X324375Y1052325D01*
X324193Y1051941D01*
X324052Y1051800D01*
X323320Y1052532D01*
X323462Y1052673D01*
G37*
G36*
G01X324666Y1078753D02*
X325049Y1078935D01*
X325580Y1078404D01*
X325397Y1078021D01*
X325256Y1077879D01*
X324524Y1078611D01*
X324666Y1078753D01*
G37*
G36*
G01X324284Y1078569D02*
X323900Y1078386D01*
X323370Y1078917D01*
X323552Y1079300D01*
X323693Y1079442D01*
X324425Y1078710D01*
X324284Y1078569D01*
G37*
G36*
G01X326327Y1077091D02*
X326711Y1077273D01*
X327241Y1076743D01*
X327059Y1076359D01*
X326918Y1076218D01*
X326186Y1076950D01*
X326327Y1077091D01*
G37*
G36*
G01X325946Y1076907D02*
X325562Y1076725D01*
X325032Y1077255D01*
X325214Y1077639D01*
X325355Y1077780D01*
X326087Y1077049D01*
X325946Y1076907D01*
G37*
G36*
G01X322582Y1076867D02*
X322199Y1076685D01*
X321669Y1077215D01*
X321851Y1077599D01*
X321992Y1077740D01*
X322724Y1077008D01*
X322582Y1076867D01*
G37*
G36*
G01X322964Y1077051D02*
X323348Y1077233D01*
X323878Y1076703D01*
X323696Y1076319D01*
X323555Y1076178D01*
X322823Y1076909D01*
X322964Y1077051D01*
G37*
G36*
G01X325906Y1073544D02*
X325523Y1073362D01*
X324992Y1073892D01*
X325174Y1074276D01*
X325316Y1074417D01*
X326048Y1073685D01*
X325906Y1073544D01*
G37*
G36*
G01X324244Y1075206D02*
X323861Y1075023D01*
X323330Y1075554D01*
X323512Y1075937D01*
X323654Y1076079D01*
X324386Y1075347D01*
X324244Y1075206D01*
G37*
G36*
G01X324626Y1075389D02*
X325010Y1075572D01*
X325540Y1075041D01*
X325358Y1074658D01*
X325217Y1074516D01*
X324485Y1075248D01*
X324626Y1075389D01*
G37*
G36*
G01X326288Y1073728D02*
X326672Y1073910D01*
X327202Y1073380D01*
X327020Y1072996D01*
X326879Y1072855D01*
X326147Y1073586D01*
X326288Y1073728D01*
G37*
G36*
G01X327568Y1071883D02*
X327185Y1071700D01*
X326654Y1072231D01*
X326836Y1072614D01*
X326978Y1072756D01*
X327710Y1072024D01*
X327568Y1071883D01*
G37*
G36*
G01X323432Y1077716D02*
X323048Y1077534D01*
X322518Y1078065D01*
X322700Y1078448D01*
X322841Y1078590D01*
X323573Y1077858D01*
X323432Y1077716D01*
G37*
G36*
G01X323814Y1077900D02*
X324197Y1078082D01*
X324728Y1077552D01*
X324546Y1077169D01*
X324404Y1077027D01*
X323672Y1077759D01*
X323814Y1077900D01*
G37*
G36*
G01X322152Y1079562D02*
X322535Y1079744D01*
X323066Y1079214D01*
X322884Y1078830D01*
X322742Y1078689D01*
X322010Y1079420D01*
X322152Y1079562D01*
G37*
G36*
G01X325094Y1076055D02*
X324710Y1075873D01*
X324180Y1076403D01*
X324362Y1076787D01*
X324503Y1076928D01*
X325235Y1076196D01*
X325094Y1076055D01*
G37*
G36*
G01X325475Y1076239D02*
X325859Y1076421D01*
X326389Y1075891D01*
X326207Y1075507D01*
X326066Y1075366D01*
X325334Y1076097D01*
X325475Y1076239D01*
G37*
G36*
G01X323395Y1074356D02*
X323011Y1074174D01*
X322481Y1074704D01*
X322663Y1075088D01*
X322804Y1075229D01*
X323536Y1074497D01*
X323395Y1074356D01*
G37*
G36*
G01X322115Y1076201D02*
X322499Y1076383D01*
X323029Y1075853D01*
X322847Y1075470D01*
X322705Y1075328D01*
X321974Y1076060D01*
X322115Y1076201D01*
G37*
G36*
G01X325057Y1072694D02*
X324673Y1072512D01*
X324143Y1073042D01*
X324325Y1073426D01*
X324466Y1073568D01*
X325198Y1072836D01*
X325057Y1072694D01*
G37*
G36*
G01X323777Y1074540D02*
X324160Y1074722D01*
X324691Y1074192D01*
X324509Y1073808D01*
X324367Y1073667D01*
X323635Y1074398D01*
X323777Y1074540D01*
G37*
G36*
G01X326719Y1071033D02*
X326335Y1070851D01*
X325805Y1071381D01*
X325987Y1071765D01*
X326128Y1071906D01*
X326860Y1071174D01*
X326719Y1071033D01*
G37*
G36*
G01X325439Y1072878D02*
X325822Y1073060D01*
X326353Y1072530D01*
X326171Y1072146D01*
X326029Y1072005D01*
X325297Y1072737D01*
X325439Y1072878D01*
G37*
G36*
G01X326539Y1068284D02*
X326923Y1068466D01*
X327453Y1067936D01*
X327271Y1067552D01*
X327129Y1067411D01*
X326398Y1068142D01*
X326539Y1068284D01*
G37*
G36*
G01X326157Y1068100D02*
X325774Y1067918D01*
X325243Y1068448D01*
X325425Y1068832D01*
X325567Y1068973D01*
X326299Y1068241D01*
X326157Y1068100D01*
G37*
G36*
G01X328201Y1066622D02*
X328584Y1066804D01*
X329115Y1066274D01*
X328933Y1065890D01*
X328791Y1065749D01*
X328059Y1066481D01*
X328201Y1066622D01*
G37*
G36*
G01X327819Y1066438D02*
X327435Y1066256D01*
X326905Y1066787D01*
X327087Y1067170D01*
X327228Y1067312D01*
X327960Y1066580D01*
X327819Y1066438D01*
G37*
G36*
G01X329481Y1064777D02*
X329097Y1064595D01*
X328567Y1065125D01*
X328749Y1065509D01*
X328890Y1065650D01*
X329622Y1064918D01*
X329481Y1064777D01*
G37*
G36*
G01X329862Y1064960D02*
X330246Y1065143D01*
X330776Y1064612D01*
X330594Y1064229D01*
X330453Y1064087D01*
X329721Y1064819D01*
X329862Y1064960D01*
G37*
G36*
G01X323216Y1071607D02*
X323599Y1071789D01*
X324129Y1071259D01*
X323947Y1070875D01*
X323806Y1070734D01*
X323074Y1071466D01*
X323216Y1071607D01*
G37*
G36*
G01X324877Y1069946D02*
X325261Y1070128D01*
X325791Y1069597D01*
X325609Y1069214D01*
X325468Y1069072D01*
X324736Y1069804D01*
X324877Y1069946D01*
G37*
G36*
G01X324495Y1069762D02*
X324112Y1069580D01*
X323581Y1070110D01*
X323764Y1070494D01*
X323905Y1070635D01*
X324637Y1069903D01*
X324495Y1069762D01*
G37*
G36*
G01X322834Y1071423D02*
X322450Y1071241D01*
X321920Y1071772D01*
X322102Y1072155D01*
X322243Y1072297D01*
X322975Y1071565D01*
X322834Y1071423D01*
G37*
G36*
G01X322797Y1068064D02*
X322414Y1067882D01*
X321883Y1068412D01*
X322066Y1068796D01*
X322207Y1068937D01*
X322939Y1068205D01*
X322797Y1068064D01*
G37*
G36*
G01X324841Y1066586D02*
X325225Y1066768D01*
X325755Y1066238D01*
X325573Y1065854D01*
X325431Y1065713D01*
X324700Y1066444D01*
X324841Y1066586D01*
G37*
G36*
G01X326503Y1064924D02*
X326886Y1065106D01*
X327417Y1064576D01*
X327235Y1064192D01*
X327093Y1064051D01*
X326361Y1064783D01*
X326503Y1064924D01*
G37*
G36*
G01X324459Y1066402D02*
X324076Y1066220D01*
X323545Y1066750D01*
X323727Y1067134D01*
X323869Y1067275D01*
X324601Y1066543D01*
X324459Y1066402D01*
G37*
G36*
G01X326121Y1064740D02*
X325737Y1064558D01*
X325207Y1065089D01*
X325389Y1065472D01*
X325530Y1065614D01*
X326262Y1064882D01*
X326121Y1064740D01*
G37*
G36*
G01X323179Y1068248D02*
X323563Y1068430D01*
X324093Y1067899D01*
X323911Y1067516D01*
X323770Y1067374D01*
X323038Y1068106D01*
X323179Y1068248D01*
G37*
G36*
G01X326970Y1065589D02*
X326586Y1065407D01*
X326056Y1065938D01*
X326238Y1066321D01*
X326379Y1066463D01*
X327111Y1065731D01*
X326970Y1065589D01*
G37*
G36*
G01X325690Y1067435D02*
X326074Y1067617D01*
X326604Y1067087D01*
X326422Y1066703D01*
X326280Y1066562D01*
X325549Y1067293D01*
X325690Y1067435D01*
G37*
G36*
G01X325308Y1067251D02*
X324925Y1067069D01*
X324394Y1067599D01*
X324576Y1067983D01*
X324718Y1068124D01*
X325450Y1067392D01*
X325308Y1067251D01*
G37*
G36*
G01X327352Y1065773D02*
X327735Y1065955D01*
X328266Y1065425D01*
X328084Y1065041D01*
X327942Y1064900D01*
X327210Y1065632D01*
X327352Y1065773D01*
G37*
G36*
G01X328632Y1063928D02*
X328248Y1063746D01*
X327718Y1064276D01*
X327900Y1064660D01*
X328041Y1064801D01*
X328773Y1064069D01*
X328632Y1063928D01*
G37*
G36*
G01X329013Y1064111D02*
X329397Y1064294D01*
X329927Y1063763D01*
X329745Y1063380D01*
X329604Y1063238D01*
X328872Y1063970D01*
X329013Y1064111D01*
G37*
G36*
G01X322367Y1070758D02*
X322750Y1070940D01*
X323280Y1070410D01*
X323098Y1070026D01*
X322957Y1069885D01*
X322225Y1070617D01*
X322367Y1070758D01*
G37*
G36*
G01X323646Y1068913D02*
X323263Y1068731D01*
X322732Y1069261D01*
X322915Y1069645D01*
X323056Y1069786D01*
X323788Y1069054D01*
X323646Y1068913D01*
G37*
G36*
G01X324028Y1069097D02*
X324412Y1069279D01*
X324942Y1068748D01*
X324760Y1068365D01*
X324619Y1068223D01*
X323887Y1068955D01*
X324028Y1069097D01*
G37*
G36*
G01X323609Y1065552D02*
X323226Y1065370D01*
X322695Y1065900D01*
X322877Y1066284D01*
X323019Y1066425D01*
X323751Y1065693D01*
X323609Y1065552D01*
G37*
G36*
G01X325271Y1063890D02*
X324887Y1063708D01*
X324357Y1064239D01*
X324539Y1064622D01*
X324680Y1064764D01*
X325412Y1064032D01*
X325271Y1063890D01*
G37*
G36*
G01X323991Y1065736D02*
X324375Y1065918D01*
X324905Y1065388D01*
X324723Y1065004D01*
X324581Y1064863D01*
X323850Y1065594D01*
X323991Y1065736D01*
G37*
G36*
G01X322329Y1067398D02*
X322713Y1067580D01*
X323243Y1067049D01*
X323061Y1066666D01*
X322920Y1066524D01*
X322188Y1067256D01*
X322329Y1067398D01*
G37*
G36*
G01X321883Y1096102D02*
X322302Y1096166D01*
X322656Y1095504D01*
X322371Y1095190D01*
X322195Y1095096D01*
X321706Y1096008D01*
X321883Y1096102D01*
G37*
G36*
G01X325535Y1090918D02*
X325152Y1090736D01*
X324622Y1091266D01*
X324804Y1091650D01*
X324945Y1091791D01*
X325677Y1091059D01*
X325535Y1090918D01*
G37*
G36*
G01X325917Y1091102D02*
X326301Y1091284D01*
X326831Y1090753D01*
X326649Y1090370D01*
X326508Y1090228D01*
X325776Y1090960D01*
X325917Y1091102D01*
G37*
G36*
G01X327197Y1089256D02*
X326814Y1089074D01*
X326283Y1089604D01*
X326465Y1089988D01*
X326607Y1090129D01*
X327339Y1089397D01*
X327197Y1089256D01*
G37*
G36*
G01X328859Y1087594D02*
X328475Y1087412D01*
X327945Y1087943D01*
X328127Y1088326D01*
X328268Y1088468D01*
X329000Y1087736D01*
X328859Y1087594D01*
G37*
G36*
G01X329241Y1087778D02*
X329624Y1087960D01*
X330155Y1087430D01*
X329973Y1087046D01*
X329831Y1086905D01*
X329099Y1087637D01*
X329241Y1087778D01*
G37*
G36*
G01X330521Y1085933D02*
X330137Y1085751D01*
X329607Y1086281D01*
X329789Y1086664D01*
X329930Y1086806D01*
X330662Y1086074D01*
X330521Y1085933D01*
G37*
G36*
G01X327579Y1089440D02*
X327963Y1089622D01*
X328493Y1089092D01*
X328311Y1088708D01*
X328169Y1088567D01*
X327438Y1089298D01*
X327579Y1089440D01*
G37*
G36*
G01X330902Y1086116D02*
X331286Y1086299D01*
X331816Y1085768D01*
X331634Y1085385D01*
X331493Y1085243D01*
X330761Y1085975D01*
X330902Y1086116D01*
G37*
G36*
G01X324256Y1092763D02*
X324639Y1092945D01*
X325170Y1092415D01*
X324987Y1092031D01*
X324846Y1091890D01*
X324114Y1092622D01*
X324256Y1092763D01*
G37*
G36*
G01X323874Y1092579D02*
X323490Y1092397D01*
X322960Y1092928D01*
X323142Y1093311D01*
X323283Y1093453D01*
X324015Y1092721D01*
X323874Y1092579D01*
G37*
G36*
G01X332182Y1084271D02*
X331799Y1084089D01*
X331268Y1084619D01*
X331450Y1085003D01*
X331592Y1085144D01*
X332324Y1084412D01*
X332182Y1084271D01*
G37*
G36*
G01X330484Y1082572D02*
X330100Y1082390D01*
X329570Y1082921D01*
X329752Y1083304D01*
X329893Y1083446D01*
X330625Y1082714D01*
X330484Y1082572D01*
G37*
G36*
G01X329204Y1084418D02*
X329588Y1084600D01*
X330118Y1084070D01*
X329936Y1083686D01*
X329794Y1083545D01*
X329062Y1084277D01*
X329204Y1084418D01*
G37*
G36*
G01X328822Y1084234D02*
X328438Y1084052D01*
X327908Y1084582D01*
X328090Y1084966D01*
X328232Y1085107D01*
X328963Y1084376D01*
X328822Y1084234D01*
G37*
G36*
G01X323837Y1089219D02*
X323453Y1089037D01*
X322923Y1089567D01*
X323105Y1089951D01*
X323247Y1090092D01*
X323978Y1089361D01*
X323837Y1089219D01*
G37*
G36*
G01X322557Y1091065D02*
X322941Y1091247D01*
X323471Y1090717D01*
X323289Y1090333D01*
X323148Y1090191D01*
X322416Y1090923D01*
X322557Y1091065D01*
G37*
G36*
G01X325499Y1087558D02*
X325115Y1087375D01*
X324585Y1087906D01*
X324767Y1088289D01*
X324908Y1088431D01*
X325640Y1087699D01*
X325499Y1087558D01*
G37*
G36*
G01X324219Y1089403D02*
X324602Y1089585D01*
X325133Y1089055D01*
X324951Y1088671D01*
X324809Y1088530D01*
X324077Y1089262D01*
X324219Y1089403D01*
G37*
G36*
G01X325880Y1087741D02*
X326264Y1087923D01*
X326794Y1087393D01*
X326612Y1087009D01*
X326471Y1086868D01*
X325739Y1087600D01*
X325880Y1087741D01*
G37*
G36*
G01X327160Y1085896D02*
X326777Y1085714D01*
X326246Y1086244D01*
X326429Y1086628D01*
X326570Y1086769D01*
X327302Y1086037D01*
X327160Y1085896D01*
G37*
G36*
G01X327542Y1086080D02*
X327926Y1086262D01*
X328456Y1085731D01*
X328274Y1085348D01*
X328133Y1085206D01*
X327401Y1085938D01*
X327542Y1086080D01*
G37*
G36*
G01X331333Y1083421D02*
X330949Y1083239D01*
X330419Y1083770D01*
X330601Y1084153D01*
X330742Y1084295D01*
X331474Y1083563D01*
X331333Y1083421D01*
G37*
G36*
G01X330053Y1085267D02*
X330437Y1085449D01*
X330967Y1084919D01*
X330785Y1084535D01*
X330643Y1084394D01*
X329911Y1085126D01*
X330053Y1085267D01*
G37*
G36*
G01X328009Y1086745D02*
X327626Y1086563D01*
X327095Y1087093D01*
X327278Y1087477D01*
X327419Y1087618D01*
X328151Y1086886D01*
X328009Y1086745D01*
G37*
G36*
G01X328391Y1086929D02*
X328775Y1087111D01*
X329305Y1086580D01*
X329123Y1086197D01*
X328982Y1086055D01*
X328250Y1086787D01*
X328391Y1086929D01*
G37*
G36*
G01X329671Y1085083D02*
X329287Y1084901D01*
X328757Y1085431D01*
X328939Y1085815D01*
X329081Y1085956D01*
X329812Y1085225D01*
X329671Y1085083D01*
G37*
G36*
G01X323024Y1091730D02*
X322641Y1091548D01*
X322110Y1092078D01*
X322292Y1092462D01*
X322434Y1092603D01*
X323166Y1091871D01*
X323024Y1091730D01*
G37*
G36*
G01X323406Y1091914D02*
X323790Y1092096D01*
X324320Y1091566D01*
X324138Y1091182D01*
X323997Y1091040D01*
X323265Y1091772D01*
X323406Y1091914D01*
G37*
G36*
G01X324686Y1090068D02*
X324302Y1089886D01*
X323772Y1090416D01*
X323954Y1090800D01*
X324096Y1090941D01*
X324827Y1090210D01*
X324686Y1090068D01*
G37*
G36*
G01X325068Y1090252D02*
X325451Y1090434D01*
X325982Y1089904D01*
X325800Y1089520D01*
X325658Y1089379D01*
X324926Y1090111D01*
X325068Y1090252D01*
G37*
G36*
G01X326348Y1088407D02*
X325964Y1088224D01*
X325434Y1088755D01*
X325616Y1089138D01*
X325757Y1089280D01*
X326489Y1088548D01*
X326348Y1088407D01*
G37*
G36*
G01X326729Y1088590D02*
X327113Y1088772D01*
X327643Y1088242D01*
X327461Y1087858D01*
X327320Y1087717D01*
X326588Y1088449D01*
X326729Y1088590D01*
G37*
G36*
G01X326687Y1085224D02*
X327070Y1085406D01*
X327601Y1084876D01*
X327419Y1084492D01*
X327277Y1084351D01*
X326545Y1085083D01*
X326687Y1085224D01*
G37*
G36*
G01X327967Y1083379D02*
X327583Y1083197D01*
X327053Y1083727D01*
X327235Y1084110D01*
X327376Y1084252D01*
X328108Y1083520D01*
X327967Y1083379D01*
G37*
G36*
G01X329628Y1081717D02*
X329245Y1081535D01*
X328714Y1082065D01*
X328896Y1082449D01*
X329038Y1082590D01*
X329770Y1081858D01*
X329628Y1081717D01*
G37*
G36*
G01X328348Y1083562D02*
X328732Y1083745D01*
X329262Y1083214D01*
X329080Y1082831D01*
X328939Y1082689D01*
X328207Y1083421D01*
X328348Y1083562D01*
G37*
G36*
G01X324643Y1086702D02*
X324260Y1086520D01*
X323729Y1087050D01*
X323911Y1087434D01*
X324053Y1087575D01*
X324785Y1086843D01*
X324643Y1086702D01*
G37*
G36*
G01X322981Y1088364D02*
X322598Y1088182D01*
X322068Y1088712D01*
X322250Y1089096D01*
X322391Y1089237D01*
X323123Y1088505D01*
X322981Y1088364D01*
G37*
G36*
G01X323363Y1088548D02*
X323747Y1088730D01*
X324277Y1088199D01*
X324095Y1087816D01*
X323954Y1087674D01*
X323222Y1088406D01*
X323363Y1088548D01*
G37*
G36*
G01X325025Y1086886D02*
X325409Y1087068D01*
X325939Y1086538D01*
X325757Y1086154D01*
X325615Y1086013D01*
X324884Y1086744D01*
X325025Y1086886D01*
G37*
G36*
G01X326305Y1085040D02*
X325921Y1084858D01*
X325391Y1085389D01*
X325573Y1085772D01*
X325714Y1085914D01*
X326446Y1085182D01*
X326305Y1085040D01*
G37*
G36*
G01X323004Y1080414D02*
X323387Y1080596D01*
X323918Y1080066D01*
X323736Y1079682D01*
X323594Y1079541D01*
X322862Y1080273D01*
X323004Y1080414D01*
G37*
G36*
G01X322622Y1080230D02*
X322238Y1080048D01*
X321708Y1080578D01*
X321890Y1080962D01*
X322031Y1081103D01*
X322763Y1080372D01*
X322622Y1080230D01*
G37*
G36*
G01X334401Y1109699D02*
X333980Y1109760D01*
X333833Y1110495D01*
X334197Y1110714D01*
X334393Y1110753D01*
X334597Y1109738D01*
X334401Y1109699D01*
G37*
G36*
G01X334358Y1111944D02*
X334778Y1111883D01*
X334926Y1111148D01*
X334562Y1110929D01*
X334365Y1110890D01*
X334162Y1111905D01*
X334358Y1111944D01*
G37*
G36*
G01X334821Y1109640D02*
X335241Y1109579D01*
X335388Y1108844D01*
X335024Y1108625D01*
X334828Y1108586D01*
X334625Y1109601D01*
X334821Y1109640D01*
G37*
G36*
G01X332430Y1109162D02*
X332850Y1109100D01*
X332997Y1108365D01*
X332633Y1108147D01*
X332436Y1108108D01*
X332234Y1109122D01*
X332430Y1109162D01*
G37*
G36*
G01X332010Y1109221D02*
X331590Y1109282D01*
X331443Y1110017D01*
X331807Y1110235D01*
X332003Y1110275D01*
X332206Y1109260D01*
X332010Y1109221D01*
G37*
G36*
G01X331969Y1111466D02*
X332389Y1111405D01*
X332536Y1110669D01*
X332172Y1110451D01*
X331976Y1110412D01*
X331773Y1111427D01*
X331969Y1111466D01*
G37*
G36*
G01X333155Y1111704D02*
X333575Y1111643D01*
X333723Y1110907D01*
X333359Y1110689D01*
X333163Y1110649D01*
X332959Y1111664D01*
X333155Y1111704D01*
G37*
G36*
G01X333617Y1109399D02*
X334037Y1109338D01*
X334185Y1108603D01*
X333821Y1108385D01*
X333624Y1108345D01*
X333421Y1109360D01*
X333617Y1109399D01*
G37*
G36*
G01X333197Y1109458D02*
X332777Y1109519D01*
X332630Y1110255D01*
X332994Y1110473D01*
X333190Y1110512D01*
X333393Y1109497D01*
X333197Y1109458D01*
G37*
G36*
G01X330832Y1108985D02*
X330412Y1109046D01*
X330264Y1109781D01*
X330629Y1110000D01*
X330825Y1110039D01*
X331028Y1109024D01*
X330832Y1108985D01*
G37*
G36*
G01X330790Y1111230D02*
X331211Y1111169D01*
X331358Y1110434D01*
X330993Y1110215D01*
X330797Y1110176D01*
X330594Y1111191D01*
X330790Y1111230D01*
G37*
G36*
G01X331251Y1108926D02*
X331672Y1108865D01*
X331819Y1108129D01*
X331454Y1107911D01*
X331258Y1107872D01*
X331055Y1108887D01*
X331251Y1108926D01*
G37*
G36*
G01X325415Y1104454D02*
X324995Y1104515D01*
X324848Y1105251D01*
X325212Y1105469D01*
X325408Y1105508D01*
X325611Y1104494D01*
X325415Y1104454D01*
G37*
G36*
G01X324492Y1109063D02*
X324072Y1109124D01*
X323925Y1109859D01*
X324289Y1110078D01*
X324485Y1110117D01*
X324689Y1109102D01*
X324492Y1109063D01*
G37*
G36*
G01X325373Y1106700D02*
X325794Y1106639D01*
X325941Y1105903D01*
X325577Y1105685D01*
X325380Y1105646D01*
X325177Y1106661D01*
X325373Y1106700D01*
G37*
G36*
G01X324912Y1109004D02*
X325332Y1108943D01*
X325480Y1108208D01*
X325115Y1107989D01*
X324919Y1107950D01*
X324716Y1108965D01*
X324912Y1109004D01*
G37*
G36*
G01X324954Y1106759D02*
X324534Y1106820D01*
X324386Y1107555D01*
X324751Y1107773D01*
X324947Y1107813D01*
X325150Y1106798D01*
X324954Y1106759D01*
G37*
G36*
G01X325835Y1104396D02*
X326255Y1104334D01*
X326402Y1103599D01*
X326038Y1103381D01*
X325842Y1103341D01*
X325639Y1104356D01*
X325835Y1104396D01*
G37*
G36*
G01X325876Y1102150D02*
X325456Y1102211D01*
X325309Y1102947D01*
X325673Y1103165D01*
X325869Y1103204D01*
X326072Y1102189D01*
X325876Y1102150D01*
G37*
G36*
G01X323941Y1101621D02*
X324361Y1101560D01*
X324508Y1100824D01*
X324144Y1100606D01*
X323948Y1100567D01*
X323744Y1101582D01*
X323941Y1101621D01*
G37*
G36*
G01X324402Y1099317D02*
X324822Y1099255D01*
X324969Y1098520D01*
X324605Y1098302D01*
X324409Y1098262D01*
X324206Y1099277D01*
X324402Y1099317D01*
G37*
G36*
G01X323982Y1099375D02*
X323562Y1099437D01*
X323415Y1100172D01*
X323779Y1100390D01*
X323975Y1100429D01*
X324178Y1099414D01*
X323982Y1099375D01*
G37*
G36*
G01X323479Y1103925D02*
X323899Y1103864D01*
X324047Y1103128D01*
X323682Y1102910D01*
X323486Y1102871D01*
X323283Y1103886D01*
X323479Y1103925D01*
G37*
G36*
G01X323059Y1103984D02*
X322639Y1104045D01*
X322492Y1104781D01*
X322856Y1104999D01*
X323053Y1105038D01*
X323255Y1104023D01*
X323059Y1103984D01*
G37*
G36*
G01X323018Y1106229D02*
X323438Y1106168D01*
X323585Y1105433D01*
X323221Y1105214D01*
X323025Y1105175D01*
X322822Y1106190D01*
X323018Y1106229D01*
G37*
G36*
G01X322556Y1108534D02*
X322976Y1108472D01*
X323124Y1107737D01*
X322759Y1107519D01*
X322563Y1107479D01*
X322360Y1108494D01*
X322556Y1108534D01*
G37*
G36*
G01X322598Y1106288D02*
X322178Y1106349D01*
X322031Y1107085D01*
X322395Y1107303D01*
X322591Y1107342D01*
X322794Y1106327D01*
X322598Y1106288D01*
G37*
G36*
G01X323521Y1101680D02*
X323100Y1101741D01*
X322954Y1102476D01*
X323318Y1102695D01*
X323514Y1102734D01*
X323717Y1101719D01*
X323521Y1101680D01*
G37*
G36*
G01X325160Y1099611D02*
X324740Y1099672D01*
X324592Y1100407D01*
X324957Y1100625D01*
X325153Y1100665D01*
X325356Y1099650D01*
X325160Y1099611D01*
G37*
G36*
G01X325118Y1101856D02*
X325538Y1101795D01*
X325686Y1101059D01*
X325321Y1100841D01*
X325125Y1100802D01*
X324922Y1101817D01*
X325118Y1101856D01*
G37*
G36*
G01X323314Y1108827D02*
X322894Y1108889D01*
X322747Y1109624D01*
X323111Y1109842D01*
X323307Y1109882D01*
X323510Y1108867D01*
X323314Y1108827D01*
G37*
G36*
G01X324657Y1104160D02*
X325077Y1104099D01*
X325224Y1103364D01*
X324860Y1103145D01*
X324664Y1103106D01*
X324461Y1104121D01*
X324657Y1104160D01*
G37*
G36*
G01X324698Y1101915D02*
X324278Y1101976D01*
X324131Y1102711D01*
X324495Y1102930D01*
X324691Y1102969D01*
X324895Y1101954D01*
X324698Y1101915D01*
G37*
G36*
G01X324237Y1104219D02*
X323817Y1104280D01*
X323670Y1105016D01*
X324034Y1105234D01*
X324230Y1105273D01*
X324433Y1104258D01*
X324237Y1104219D01*
G37*
G36*
G01X324195Y1106465D02*
X324615Y1106403D01*
X324763Y1105668D01*
X324399Y1105450D01*
X324202Y1105410D01*
X323999Y1106425D01*
X324195Y1106465D01*
G37*
G36*
G01X323734Y1108769D02*
X324154Y1108708D01*
X324301Y1107972D01*
X323937Y1107754D01*
X323741Y1107715D01*
X323538Y1108729D01*
X323734Y1108769D01*
G37*
G36*
G01X323776Y1106523D02*
X323355Y1106584D01*
X323208Y1107320D01*
X323572Y1107538D01*
X323768Y1107577D01*
X323972Y1106563D01*
X323776Y1106523D01*
G37*
G36*
G01X323219Y1099080D02*
X323639Y1099019D01*
X323786Y1098283D01*
X323422Y1098065D01*
X323226Y1098026D01*
X323023Y1099041D01*
X323219Y1099080D01*
G37*
G36*
G01X322759Y1101385D02*
X323179Y1101323D01*
X323326Y1100588D01*
X322962Y1100370D01*
X322766Y1100331D01*
X322563Y1101345D01*
X322759Y1101385D01*
G37*
G36*
G01X322800Y1099139D02*
X322379Y1099200D01*
X322232Y1099936D01*
X322597Y1100154D01*
X322793Y1100193D01*
X322996Y1099178D01*
X322800Y1099139D01*
G37*
G36*
G01X322299Y1103689D02*
X322719Y1103628D01*
X322866Y1102892D01*
X322501Y1102674D01*
X322305Y1102635D01*
X322102Y1103650D01*
X322299Y1103689D01*
G37*
G36*
G01X321838Y1105994D02*
X322258Y1105932D01*
X322405Y1105197D01*
X322041Y1104979D01*
X321845Y1104939D01*
X321642Y1105954D01*
X321838Y1105994D01*
G37*
G36*
G01X322339Y1101444D02*
X321919Y1101505D01*
X321772Y1102240D01*
X322137Y1102459D01*
X322333Y1102498D01*
X322535Y1101483D01*
X322339Y1101444D01*
G37*
G36*
G01X333828Y1125190D02*
X333428Y1125333D01*
Y1126083D01*
X333828Y1126225D01*
X334028D01*
Y1125190D01*
X333828D01*
G37*
G36*
G01X334228Y1127400D02*
X334628Y1127258D01*
Y1126508D01*
X334228Y1126365D01*
X334028D01*
Y1127400D01*
X334228D01*
G37*
G36*
G01X333828Y1127540D02*
X333428Y1127683D01*
Y1128433D01*
X333828Y1128575D01*
X334028D01*
Y1127540D01*
X333828D01*
G37*
G36*
G01X334228Y1125050D02*
X334628Y1124908D01*
Y1124158D01*
X334228Y1124015D01*
X334028D01*
Y1125050D01*
X334228D01*
G37*
G36*
G01X333828Y1122840D02*
X333428Y1122983D01*
Y1123733D01*
X333828Y1123875D01*
X334028D01*
Y1122840D01*
X333828D01*
G37*
G36*
G01X334228Y1118000D02*
X334628Y1117858D01*
Y1117108D01*
X334228Y1116965D01*
X334028D01*
Y1118000D01*
X334228D01*
G37*
G36*
G01Y1115650D02*
X334628Y1115508D01*
Y1114758D01*
X334228Y1114615D01*
X334028D01*
Y1115650D01*
X334228D01*
G37*
G36*
G01X333828Y1115790D02*
X333428Y1115933D01*
Y1116683D01*
X333828Y1116825D01*
X334028D01*
Y1115790D01*
X333828D01*
G37*
G36*
G01Y1113440D02*
X333428Y1113583D01*
Y1114333D01*
X333828Y1114475D01*
X334028D01*
Y1113440D01*
X333828D01*
G37*
G36*
G01X334228Y1122700D02*
X334628Y1122558D01*
Y1121808D01*
X334228Y1121665D01*
X334028D01*
Y1122700D01*
X334228D01*
G37*
G36*
G01Y1120350D02*
X334628Y1120208D01*
Y1119458D01*
X334228Y1119315D01*
X334028D01*
Y1120350D01*
X334228D01*
G37*
G36*
G01X333828Y1120490D02*
X333428Y1120633D01*
Y1121383D01*
X333828Y1121525D01*
X334028D01*
Y1120490D01*
X333828D01*
G37*
G36*
G01Y1118140D02*
X333428Y1118283D01*
Y1119033D01*
X333828Y1119175D01*
X334028D01*
Y1118140D01*
X333828D01*
G37*
G36*
G01X331428Y1125190D02*
X331028Y1125333D01*
Y1126083D01*
X331428Y1126225D01*
X331628D01*
Y1125190D01*
X331428D01*
G37*
G36*
G01Y1127540D02*
X331028Y1127683D01*
Y1128433D01*
X331428Y1128575D01*
X331628D01*
Y1127540D01*
X331428D01*
G37*
G36*
G01Y1122840D02*
X331028Y1122983D01*
Y1123733D01*
X331428Y1123875D01*
X331628D01*
Y1122840D01*
X331428D01*
G37*
G36*
G01Y1115790D02*
X331028Y1115933D01*
Y1116683D01*
X331428Y1116825D01*
X331628D01*
Y1115790D01*
X331428D01*
G37*
G36*
G01Y1113440D02*
X331028Y1113583D01*
Y1114333D01*
X331428Y1114475D01*
X331628D01*
Y1113440D01*
X331428D01*
G37*
G36*
G01Y1120490D02*
X331028Y1120633D01*
Y1121383D01*
X331428Y1121525D01*
X331628D01*
Y1120490D01*
X331428D01*
G37*
G36*
G01Y1118140D02*
X331028Y1118283D01*
Y1119033D01*
X331428Y1119175D01*
X331628D01*
Y1118140D01*
X331428D01*
G37*
G36*
G01X331828Y1127400D02*
X332228Y1127258D01*
Y1126508D01*
X331828Y1126365D01*
X331628D01*
Y1127400D01*
X331828D01*
G37*
G36*
G01Y1125050D02*
X332228Y1124908D01*
Y1124158D01*
X331828Y1124015D01*
X331628D01*
Y1125050D01*
X331828D01*
G37*
G36*
G01Y1118000D02*
X332228Y1117858D01*
Y1117108D01*
X331828Y1116965D01*
X331628D01*
Y1118000D01*
X331828D01*
G37*
G36*
G01Y1115650D02*
X332228Y1115508D01*
Y1114758D01*
X331828Y1114615D01*
X331628D01*
Y1115650D01*
X331828D01*
G37*
G36*
G01Y1122700D02*
X332228Y1122558D01*
Y1121808D01*
X331828Y1121665D01*
X331628D01*
Y1122700D01*
X331828D01*
G37*
G36*
G01Y1120350D02*
X332228Y1120208D01*
Y1119458D01*
X331828Y1119315D01*
X331628D01*
Y1120350D01*
X331828D01*
G37*
G36*
G01X333028Y1127400D02*
X333428Y1127258D01*
Y1126508D01*
X333028Y1126365D01*
X332828D01*
Y1127400D01*
X333028D01*
G37*
G36*
G01X332628Y1122840D02*
X332228Y1122983D01*
Y1123733D01*
X332628Y1123875D01*
X332828D01*
Y1122840D01*
X332628D01*
G37*
G36*
G01X333028Y1125050D02*
X333428Y1124908D01*
Y1124158D01*
X333028Y1124015D01*
X332828D01*
Y1125050D01*
X333028D01*
G37*
G36*
G01X332628Y1125190D02*
X332228Y1125333D01*
Y1126083D01*
X332628Y1126225D01*
X332828D01*
Y1125190D01*
X332628D01*
G37*
G36*
G01Y1127540D02*
X332228Y1127683D01*
Y1128433D01*
X332628Y1128575D01*
X332828D01*
Y1127540D01*
X332628D01*
G37*
G36*
G01X333028Y1115650D02*
X333428Y1115508D01*
Y1114758D01*
X333028Y1114615D01*
X332828D01*
Y1115650D01*
X333028D01*
G37*
G36*
G01X332628Y1115790D02*
X332228Y1115933D01*
Y1116683D01*
X332628Y1116825D01*
X332828D01*
Y1115790D01*
X332628D01*
G37*
G36*
G01Y1113440D02*
X332228Y1113583D01*
Y1114333D01*
X332628Y1114475D01*
X332828D01*
Y1113440D01*
X332628D01*
G37*
G36*
G01X333028Y1118000D02*
X333428Y1117858D01*
Y1117108D01*
X333028Y1116965D01*
X332828D01*
Y1118000D01*
X333028D01*
G37*
G36*
G01X332628Y1120490D02*
X332228Y1120633D01*
Y1121383D01*
X332628Y1121525D01*
X332828D01*
Y1120490D01*
X332628D01*
G37*
G36*
G01X333028Y1122700D02*
X333428Y1122558D01*
Y1121808D01*
X333028Y1121665D01*
X332828D01*
Y1122700D01*
X333028D01*
G37*
G36*
G01Y1120350D02*
X333428Y1120208D01*
Y1119458D01*
X333028Y1119315D01*
X332828D01*
Y1120350D01*
X333028D01*
G37*
G36*
G01X332628Y1118140D02*
X332228Y1118283D01*
Y1119033D01*
X332628Y1119175D01*
X332828D01*
Y1118140D01*
X332628D01*
G37*
G36*
G01X330228Y1125190D02*
X329828Y1125333D01*
Y1126083D01*
X330228Y1126225D01*
X330428D01*
Y1125190D01*
X330228D01*
G37*
G36*
G01X330628Y1125050D02*
X331028Y1124908D01*
Y1124158D01*
X330628Y1124015D01*
X330428D01*
Y1125050D01*
X330628D01*
G37*
G36*
G01X330228Y1122840D02*
X329828Y1122983D01*
Y1123733D01*
X330228Y1123875D01*
X330428D01*
Y1122840D01*
X330228D01*
G37*
G36*
G01X330628Y1127400D02*
X331028Y1127258D01*
Y1126508D01*
X330628Y1126365D01*
X330428D01*
Y1127400D01*
X330628D01*
G37*
G36*
G01X330228Y1127540D02*
X329828Y1127683D01*
Y1128433D01*
X330228Y1128575D01*
X330428D01*
Y1127540D01*
X330228D01*
G37*
G36*
G01X330628Y1115650D02*
X331028Y1115508D01*
Y1114758D01*
X330628Y1114615D01*
X330428D01*
Y1115650D01*
X330628D01*
G37*
G36*
G01Y1118000D02*
X331028Y1117858D01*
Y1117108D01*
X330628Y1116965D01*
X330428D01*
Y1118000D01*
X330628D01*
G37*
G36*
G01X330228Y1113440D02*
X329828Y1113583D01*
Y1114333D01*
X330228Y1114475D01*
X330428D01*
Y1113440D01*
X330228D01*
G37*
G36*
G01Y1115790D02*
X329828Y1115933D01*
Y1116683D01*
X330228Y1116825D01*
X330428D01*
Y1115790D01*
X330228D01*
G37*
G36*
G01Y1118140D02*
X329828Y1118283D01*
Y1119033D01*
X330228Y1119175D01*
X330428D01*
Y1118140D01*
X330228D01*
G37*
G36*
G01X330628Y1120350D02*
X331028Y1120208D01*
Y1119458D01*
X330628Y1119315D01*
X330428D01*
Y1120350D01*
X330628D01*
G37*
G36*
G01Y1122700D02*
X331028Y1122558D01*
Y1121808D01*
X330628Y1121665D01*
X330428D01*
Y1122700D01*
X330628D01*
G37*
G36*
G01X330228Y1120490D02*
X329828Y1120633D01*
Y1121383D01*
X330228Y1121525D01*
X330428D01*
Y1120490D01*
X330228D01*
G37*
G36*
G01X324228Y1125275D02*
X323828Y1125418D01*
Y1126168D01*
X324228Y1126310D01*
X324428D01*
Y1125275D01*
X324228D01*
G37*
G36*
G01X324628Y1127485D02*
X325028Y1127343D01*
Y1126593D01*
X324628Y1126450D01*
X324428D01*
Y1127485D01*
X324628D01*
G37*
G36*
G01X324228Y1127625D02*
X323828Y1127768D01*
Y1128518D01*
X324228Y1128660D01*
X324428D01*
Y1127625D01*
X324228D01*
G37*
G36*
G01X324628Y1125135D02*
X325028Y1124993D01*
Y1124243D01*
X324628Y1124100D01*
X324428D01*
Y1125135D01*
X324628D01*
G37*
G36*
G01X324228Y1122925D02*
X323828Y1123068D01*
Y1123818D01*
X324228Y1123960D01*
X324428D01*
Y1122925D01*
X324228D01*
G37*
G36*
G01X324628Y1118085D02*
X325028Y1117943D01*
Y1117193D01*
X324628Y1117050D01*
X324428D01*
Y1118085D01*
X324628D01*
G37*
G36*
G01Y1115735D02*
X325028Y1115593D01*
Y1114843D01*
X324628Y1114700D01*
X324428D01*
Y1115735D01*
X324628D01*
G37*
G36*
G01Y1113385D02*
X325028Y1113243D01*
Y1112493D01*
X324628Y1112350D01*
X324428D01*
Y1113385D01*
X324628D01*
G37*
G36*
G01X324228Y1115875D02*
X323828Y1116018D01*
Y1116768D01*
X324228Y1116910D01*
X324428D01*
Y1115875D01*
X324228D01*
G37*
G36*
G01Y1113525D02*
X323828Y1113668D01*
Y1114418D01*
X324228Y1114560D01*
X324428D01*
Y1113525D01*
X324228D01*
G37*
G36*
G01X324628Y1122785D02*
X325028Y1122643D01*
Y1121893D01*
X324628Y1121750D01*
X324428D01*
Y1122785D01*
X324628D01*
G37*
G36*
G01Y1120435D02*
X325028Y1120293D01*
Y1119543D01*
X324628Y1119400D01*
X324428D01*
Y1120435D01*
X324628D01*
G37*
G36*
G01X324228Y1120575D02*
X323828Y1120718D01*
Y1121468D01*
X324228Y1121610D01*
X324428D01*
Y1120575D01*
X324228D01*
G37*
G36*
G01Y1118225D02*
X323828Y1118368D01*
Y1119118D01*
X324228Y1119260D01*
X324428D01*
Y1118225D01*
X324228D01*
G37*
G36*
G01X322228Y1127485D02*
X322628Y1127343D01*
Y1126593D01*
X322228Y1126450D01*
X322028D01*
Y1127485D01*
X322228D01*
G37*
G36*
G01Y1125135D02*
X322628Y1124993D01*
Y1124243D01*
X322228Y1124100D01*
X322028D01*
Y1125135D01*
X322228D01*
G37*
G36*
G01Y1118085D02*
X322628Y1117943D01*
Y1117193D01*
X322228Y1117050D01*
X322028D01*
Y1118085D01*
X322228D01*
G37*
G36*
G01Y1115735D02*
X322628Y1115593D01*
Y1114843D01*
X322228Y1114700D01*
X322028D01*
Y1115735D01*
X322228D01*
G37*
G36*
G01Y1113385D02*
X322628Y1113243D01*
Y1112493D01*
X322228Y1112350D01*
X322028D01*
Y1113385D01*
X322228D01*
G37*
G36*
G01Y1122785D02*
X322628Y1122643D01*
Y1121893D01*
X322228Y1121750D01*
X322028D01*
Y1122785D01*
X322228D01*
G37*
G36*
G01Y1120435D02*
X322628Y1120293D01*
Y1119543D01*
X322228Y1119400D01*
X322028D01*
Y1120435D01*
X322228D01*
G37*
G36*
G01X323028Y1125275D02*
X322628Y1125418D01*
Y1126168D01*
X323028Y1126310D01*
X323228D01*
Y1125275D01*
X323028D01*
G37*
G36*
G01X323428Y1127485D02*
X323828Y1127343D01*
Y1126593D01*
X323428Y1126450D01*
X323228D01*
Y1127485D01*
X323428D01*
G37*
G36*
G01X323028Y1127625D02*
X322628Y1127768D01*
Y1128518D01*
X323028Y1128660D01*
X323228D01*
Y1127625D01*
X323028D01*
G37*
G36*
G01X323428Y1125135D02*
X323828Y1124993D01*
Y1124243D01*
X323428Y1124100D01*
X323228D01*
Y1125135D01*
X323428D01*
G37*
G36*
G01X323028Y1122925D02*
X322628Y1123068D01*
Y1123818D01*
X323028Y1123960D01*
X323228D01*
Y1122925D01*
X323028D01*
G37*
G36*
G01X323428Y1118085D02*
X323828Y1117943D01*
Y1117193D01*
X323428Y1117050D01*
X323228D01*
Y1118085D01*
X323428D01*
G37*
G36*
G01Y1115735D02*
X323828Y1115593D01*
Y1114843D01*
X323428Y1114700D01*
X323228D01*
Y1115735D01*
X323428D01*
G37*
G36*
G01Y1113385D02*
X323828Y1113243D01*
Y1112493D01*
X323428Y1112350D01*
X323228D01*
Y1113385D01*
X323428D01*
G37*
G36*
G01X323028Y1115875D02*
X322628Y1116018D01*
Y1116768D01*
X323028Y1116910D01*
X323228D01*
Y1115875D01*
X323028D01*
G37*
G36*
G01Y1113525D02*
X322628Y1113668D01*
Y1114418D01*
X323028Y1114560D01*
X323228D01*
Y1113525D01*
X323028D01*
G37*
G36*
G01X323428Y1122785D02*
X323828Y1122643D01*
Y1121893D01*
X323428Y1121750D01*
X323228D01*
Y1122785D01*
X323428D01*
G37*
G36*
G01Y1120435D02*
X323828Y1120293D01*
Y1119543D01*
X323428Y1119400D01*
X323228D01*
Y1120435D01*
X323428D01*
G37*
G36*
G01X323028Y1120575D02*
X322628Y1120718D01*
Y1121468D01*
X323028Y1121610D01*
X323228D01*
Y1120575D01*
X323028D01*
G37*
G36*
G01Y1118225D02*
X322628Y1118368D01*
Y1119118D01*
X323028Y1119260D01*
X323228D01*
Y1118225D01*
X323028D01*
G37*
G36*
G01X334228Y1132100D02*
X334628Y1131958D01*
Y1131208D01*
X334228Y1131065D01*
X334028D01*
Y1132100D01*
X334228D01*
G37*
G36*
G01Y1134450D02*
X334628Y1134308D01*
Y1133558D01*
X334228Y1133415D01*
X334028D01*
Y1134450D01*
X334228D01*
G37*
G36*
G01Y1129750D02*
X334628Y1129608D01*
Y1128858D01*
X334228Y1128715D01*
X334028D01*
Y1129750D01*
X334228D01*
G37*
G36*
G01X333828Y1132240D02*
X333428Y1132383D01*
Y1133133D01*
X333828Y1133275D01*
X334028D01*
Y1132240D01*
X333828D01*
G37*
G36*
G01Y1129890D02*
X333428Y1130033D01*
Y1130783D01*
X333828Y1130925D01*
X334028D01*
Y1129890D01*
X333828D01*
G37*
G36*
G01Y1134590D02*
X333428Y1134733D01*
Y1135483D01*
X333828Y1135625D01*
X334028D01*
Y1134590D01*
X333828D01*
G37*
G36*
G01X334228Y1139150D02*
X334628Y1139008D01*
Y1138258D01*
X334228Y1138115D01*
X334028D01*
Y1139150D01*
X334228D01*
G37*
G36*
G01X333828Y1139290D02*
X333428Y1139433D01*
Y1140183D01*
X333828Y1140325D01*
X334028D01*
Y1139290D01*
X333828D01*
G37*
G36*
G01Y1136940D02*
X333428Y1137083D01*
Y1137833D01*
X333828Y1137975D01*
X334028D01*
Y1136940D01*
X333828D01*
G37*
G36*
G01X334228Y1141500D02*
X334628Y1141358D01*
Y1140608D01*
X334228Y1140465D01*
X334028D01*
Y1141500D01*
X334228D01*
G37*
G36*
G01X333828Y1141640D02*
X333428Y1141783D01*
Y1142533D01*
X333828Y1142675D01*
X334028D01*
Y1141640D01*
X333828D01*
G37*
G36*
G01X334228Y1143850D02*
X334628Y1143708D01*
Y1142958D01*
X334228Y1142815D01*
X334028D01*
Y1143850D01*
X334228D01*
G37*
G36*
G01X333828Y1143990D02*
X333428Y1144133D01*
Y1144883D01*
X333828Y1145025D01*
X334028D01*
Y1143990D01*
X333828D01*
G37*
G36*
G01X334228Y1136800D02*
X334628Y1136658D01*
Y1135908D01*
X334228Y1135765D01*
X334028D01*
Y1136800D01*
X334228D01*
G37*
G36*
G01X331428Y1132240D02*
X331028Y1132383D01*
Y1133133D01*
X331428Y1133275D01*
X331628D01*
Y1132240D01*
X331428D01*
G37*
G36*
G01Y1129890D02*
X331028Y1130033D01*
Y1130783D01*
X331428Y1130925D01*
X331628D01*
Y1129890D01*
X331428D01*
G37*
G36*
G01Y1134590D02*
X331028Y1134733D01*
Y1135483D01*
X331428Y1135625D01*
X331628D01*
Y1134590D01*
X331428D01*
G37*
G36*
G01Y1143990D02*
X331028Y1144133D01*
Y1144883D01*
X331428Y1145025D01*
X331628D01*
Y1143990D01*
X331428D01*
G37*
G36*
G01Y1139290D02*
X331028Y1139433D01*
Y1140183D01*
X331428Y1140325D01*
X331628D01*
Y1139290D01*
X331428D01*
G37*
G36*
G01Y1136940D02*
X331028Y1137083D01*
Y1137833D01*
X331428Y1137975D01*
X331628D01*
Y1136940D01*
X331428D01*
G37*
G36*
G01Y1141640D02*
X331028Y1141783D01*
Y1142533D01*
X331428Y1142675D01*
X331628D01*
Y1141640D01*
X331428D01*
G37*
G36*
G01X331828Y1132100D02*
X332228Y1131958D01*
Y1131208D01*
X331828Y1131065D01*
X331628D01*
Y1132100D01*
X331828D01*
G37*
G36*
G01Y1134450D02*
X332228Y1134308D01*
Y1133558D01*
X331828Y1133415D01*
X331628D01*
Y1134450D01*
X331828D01*
G37*
G36*
G01Y1129750D02*
X332228Y1129608D01*
Y1128858D01*
X331828Y1128715D01*
X331628D01*
Y1129750D01*
X331828D01*
G37*
G36*
G01Y1143850D02*
X332228Y1143708D01*
Y1142958D01*
X331828Y1142815D01*
X331628D01*
Y1143850D01*
X331828D01*
G37*
G36*
G01Y1136800D02*
X332228Y1136658D01*
Y1135908D01*
X331828Y1135765D01*
X331628D01*
Y1136800D01*
X331828D01*
G37*
G36*
G01Y1139150D02*
X332228Y1139008D01*
Y1138258D01*
X331828Y1138115D01*
X331628D01*
Y1139150D01*
X331828D01*
G37*
G36*
G01Y1141500D02*
X332228Y1141358D01*
Y1140608D01*
X331828Y1140465D01*
X331628D01*
Y1141500D01*
X331828D01*
G37*
G36*
G01X333028Y1132100D02*
X333428Y1131958D01*
Y1131208D01*
X333028Y1131065D01*
X332828D01*
Y1132100D01*
X333028D01*
G37*
G36*
G01Y1134450D02*
X333428Y1134308D01*
Y1133558D01*
X333028Y1133415D01*
X332828D01*
Y1134450D01*
X333028D01*
G37*
G36*
G01Y1129750D02*
X333428Y1129608D01*
Y1128858D01*
X333028Y1128715D01*
X332828D01*
Y1129750D01*
X333028D01*
G37*
G36*
G01X332628Y1132240D02*
X332228Y1132383D01*
Y1133133D01*
X332628Y1133275D01*
X332828D01*
Y1132240D01*
X332628D01*
G37*
G36*
G01Y1129890D02*
X332228Y1130033D01*
Y1130783D01*
X332628Y1130925D01*
X332828D01*
Y1129890D01*
X332628D01*
G37*
G36*
G01Y1134590D02*
X332228Y1134733D01*
Y1135483D01*
X332628Y1135625D01*
X332828D01*
Y1134590D01*
X332628D01*
G37*
G36*
G01Y1143990D02*
X332228Y1144133D01*
Y1144883D01*
X332628Y1145025D01*
X332828D01*
Y1143990D01*
X332628D01*
G37*
G36*
G01X333028Y1139150D02*
X333428Y1139008D01*
Y1138258D01*
X333028Y1138115D01*
X332828D01*
Y1139150D01*
X333028D01*
G37*
G36*
G01Y1141500D02*
X333428Y1141358D01*
Y1140608D01*
X333028Y1140465D01*
X332828D01*
Y1141500D01*
X333028D01*
G37*
G36*
G01Y1143850D02*
X333428Y1143708D01*
Y1142958D01*
X333028Y1142815D01*
X332828D01*
Y1143850D01*
X333028D01*
G37*
G36*
G01Y1136800D02*
X333428Y1136658D01*
Y1135908D01*
X333028Y1135765D01*
X332828D01*
Y1136800D01*
X333028D01*
G37*
G36*
G01X332628Y1139290D02*
X332228Y1139433D01*
Y1140183D01*
X332628Y1140325D01*
X332828D01*
Y1139290D01*
X332628D01*
G37*
G36*
G01Y1136940D02*
X332228Y1137083D01*
Y1137833D01*
X332628Y1137975D01*
X332828D01*
Y1136940D01*
X332628D01*
G37*
G36*
G01Y1141640D02*
X332228Y1141783D01*
Y1142533D01*
X332628Y1142675D01*
X332828D01*
Y1141640D01*
X332628D01*
G37*
G36*
G01X330628Y1132100D02*
X331028Y1131958D01*
Y1131208D01*
X330628Y1131065D01*
X330428D01*
Y1132100D01*
X330628D01*
G37*
G36*
G01X330228Y1134590D02*
X329828Y1134733D01*
Y1135483D01*
X330228Y1135625D01*
X330428D01*
Y1134590D01*
X330228D01*
G37*
G36*
G01X330628Y1129750D02*
X331028Y1129608D01*
Y1128858D01*
X330628Y1128715D01*
X330428D01*
Y1129750D01*
X330628D01*
G37*
G36*
G01X330228Y1129890D02*
X329828Y1130033D01*
Y1130783D01*
X330228Y1130925D01*
X330428D01*
Y1129890D01*
X330228D01*
G37*
G36*
G01Y1132240D02*
X329828Y1132383D01*
Y1133133D01*
X330228Y1133275D01*
X330428D01*
Y1132240D01*
X330228D01*
G37*
G36*
G01X330628Y1134450D02*
X331028Y1134308D01*
Y1133558D01*
X330628Y1133415D01*
X330428D01*
Y1134450D01*
X330628D01*
G37*
G36*
G01Y1143850D02*
X331028Y1143708D01*
Y1142958D01*
X330628Y1142815D01*
X330428D01*
Y1143850D01*
X330628D01*
G37*
G36*
G01X330228Y1143990D02*
X329828Y1144133D01*
Y1144883D01*
X330228Y1145025D01*
X330428D01*
Y1143990D01*
X330228D01*
G37*
G36*
G01X330628Y1141500D02*
X331028Y1141358D01*
Y1140608D01*
X330628Y1140465D01*
X330428D01*
Y1141500D01*
X330628D01*
G37*
G36*
G01X330228Y1141640D02*
X329828Y1141783D01*
Y1142533D01*
X330228Y1142675D01*
X330428D01*
Y1141640D01*
X330228D01*
G37*
G36*
G01X330628Y1139150D02*
X331028Y1139008D01*
Y1138258D01*
X330628Y1138115D01*
X330428D01*
Y1139150D01*
X330628D01*
G37*
G36*
G01X330228Y1136940D02*
X329828Y1137083D01*
Y1137833D01*
X330228Y1137975D01*
X330428D01*
Y1136940D01*
X330228D01*
G37*
G36*
G01Y1139290D02*
X329828Y1139433D01*
Y1140183D01*
X330228Y1140325D01*
X330428D01*
Y1139290D01*
X330228D01*
G37*
G36*
G01X330628Y1136800D02*
X331028Y1136658D01*
Y1135908D01*
X330628Y1135765D01*
X330428D01*
Y1136800D01*
X330628D01*
G37*
G36*
G01X324628Y1132185D02*
X325028Y1132043D01*
Y1131293D01*
X324628Y1131150D01*
X324428D01*
Y1132185D01*
X324628D01*
G37*
G36*
G01Y1134535D02*
X325028Y1134393D01*
Y1133643D01*
X324628Y1133500D01*
X324428D01*
Y1134535D01*
X324628D01*
G37*
G36*
G01Y1129835D02*
X325028Y1129693D01*
Y1128943D01*
X324628Y1128800D01*
X324428D01*
Y1129835D01*
X324628D01*
G37*
G36*
G01X324228Y1132325D02*
X323828Y1132468D01*
Y1133218D01*
X324228Y1133360D01*
X324428D01*
Y1132325D01*
X324228D01*
G37*
G36*
G01Y1129975D02*
X323828Y1130118D01*
Y1130868D01*
X324228Y1131010D01*
X324428D01*
Y1129975D01*
X324228D01*
G37*
G36*
G01Y1134675D02*
X323828Y1134818D01*
Y1135568D01*
X324228Y1135710D01*
X324428D01*
Y1134675D01*
X324228D01*
G37*
G36*
G01Y1139375D02*
X323828Y1139518D01*
Y1140268D01*
X324228Y1140410D01*
X324428D01*
Y1139375D01*
X324228D01*
G37*
G36*
G01X324628Y1141585D02*
X325028Y1141443D01*
Y1140693D01*
X324628Y1140550D01*
X324428D01*
Y1141585D01*
X324628D01*
G37*
G36*
G01X324228Y1141725D02*
X323828Y1141868D01*
Y1142618D01*
X324228Y1142760D01*
X324428D01*
Y1141725D01*
X324228D01*
G37*
G36*
G01X324628Y1143935D02*
X325028Y1143793D01*
Y1143043D01*
X324628Y1142900D01*
X324428D01*
Y1143935D01*
X324628D01*
G37*
G36*
G01X324228Y1144075D02*
X323828Y1144218D01*
Y1144968D01*
X324228Y1145110D01*
X324428D01*
Y1144075D01*
X324228D01*
G37*
G36*
G01X324628Y1136885D02*
X325028Y1136743D01*
Y1135993D01*
X324628Y1135850D01*
X324428D01*
Y1136885D01*
X324628D01*
G37*
G36*
G01Y1139235D02*
X325028Y1139093D01*
Y1138343D01*
X324628Y1138200D01*
X324428D01*
Y1139235D01*
X324628D01*
G37*
G36*
G01X324228Y1137025D02*
X323828Y1137168D01*
Y1137918D01*
X324228Y1138060D01*
X324428D01*
Y1137025D01*
X324228D01*
G37*
G36*
G01X322228Y1132185D02*
X322628Y1132043D01*
Y1131293D01*
X322228Y1131150D01*
X322028D01*
Y1132185D01*
X322228D01*
G37*
G36*
G01Y1134535D02*
X322628Y1134393D01*
Y1133643D01*
X322228Y1133500D01*
X322028D01*
Y1134535D01*
X322228D01*
G37*
G36*
G01Y1129835D02*
X322628Y1129693D01*
Y1128943D01*
X322228Y1128800D01*
X322028D01*
Y1129835D01*
X322228D01*
G37*
G36*
G01Y1139235D02*
X322628Y1139093D01*
Y1138343D01*
X322228Y1138200D01*
X322028D01*
Y1139235D01*
X322228D01*
G37*
G36*
G01Y1141585D02*
X322628Y1141443D01*
Y1140693D01*
X322228Y1140550D01*
X322028D01*
Y1141585D01*
X322228D01*
G37*
G36*
G01Y1143935D02*
X322628Y1143793D01*
Y1143043D01*
X322228Y1142900D01*
X322028D01*
Y1143935D01*
X322228D01*
G37*
G36*
G01Y1136885D02*
X322628Y1136743D01*
Y1135993D01*
X322228Y1135850D01*
X322028D01*
Y1136885D01*
X322228D01*
G37*
G36*
G01X323428Y1132185D02*
X323828Y1132043D01*
Y1131293D01*
X323428Y1131150D01*
X323228D01*
Y1132185D01*
X323428D01*
G37*
G36*
G01Y1134535D02*
X323828Y1134393D01*
Y1133643D01*
X323428Y1133500D01*
X323228D01*
Y1134535D01*
X323428D01*
G37*
G36*
G01Y1129835D02*
X323828Y1129693D01*
Y1128943D01*
X323428Y1128800D01*
X323228D01*
Y1129835D01*
X323428D01*
G37*
G36*
G01X323028Y1132325D02*
X322628Y1132468D01*
Y1133218D01*
X323028Y1133360D01*
X323228D01*
Y1132325D01*
X323028D01*
G37*
G36*
G01Y1129975D02*
X322628Y1130118D01*
Y1130868D01*
X323028Y1131010D01*
X323228D01*
Y1129975D01*
X323028D01*
G37*
G36*
G01Y1134675D02*
X322628Y1134818D01*
Y1135568D01*
X323028Y1135710D01*
X323228D01*
Y1134675D01*
X323028D01*
G37*
G36*
G01X323428Y1139235D02*
X323828Y1139093D01*
Y1138343D01*
X323428Y1138200D01*
X323228D01*
Y1139235D01*
X323428D01*
G37*
G36*
G01X323028Y1137025D02*
X322628Y1137168D01*
Y1137918D01*
X323028Y1138060D01*
X323228D01*
Y1137025D01*
X323028D01*
G37*
G36*
G01Y1139375D02*
X322628Y1139518D01*
Y1140268D01*
X323028Y1140410D01*
X323228D01*
Y1139375D01*
X323028D01*
G37*
G36*
G01X323428Y1141585D02*
X323828Y1141443D01*
Y1140693D01*
X323428Y1140550D01*
X323228D01*
Y1141585D01*
X323428D01*
G37*
G36*
G01X323028Y1141725D02*
X322628Y1141868D01*
Y1142618D01*
X323028Y1142760D01*
X323228D01*
Y1141725D01*
X323028D01*
G37*
G36*
G01X323428Y1143935D02*
X323828Y1143793D01*
Y1143043D01*
X323428Y1142900D01*
X323228D01*
Y1143935D01*
X323428D01*
G37*
G36*
G01X323028Y1144075D02*
X322628Y1144218D01*
Y1144968D01*
X323028Y1145110D01*
X323228D01*
Y1144075D01*
X323028D01*
G37*
G36*
G01X323428Y1136885D02*
X323828Y1136743D01*
Y1135993D01*
X323428Y1135850D01*
X323228D01*
Y1136885D01*
X323428D01*
G37*
G36*
G01X334228Y1148550D02*
X334628Y1148408D01*
Y1147658D01*
X334228Y1147515D01*
X334028D01*
Y1148550D01*
X334228D01*
G37*
G36*
G01Y1150900D02*
X334628Y1150758D01*
Y1150008D01*
X334228Y1149865D01*
X334028D01*
Y1150900D01*
X334228D01*
G37*
G36*
G01X333828Y1146340D02*
X333428Y1146483D01*
Y1147233D01*
X333828Y1147375D01*
X334028D01*
Y1146340D01*
X333828D01*
G37*
G36*
G01Y1148690D02*
X333428Y1148833D01*
Y1149583D01*
X333828Y1149725D01*
X334028D01*
Y1148690D01*
X333828D01*
G37*
G36*
G01Y1151040D02*
X333428Y1151183D01*
Y1151933D01*
X333828Y1152075D01*
X334028D01*
Y1151040D01*
X333828D01*
G37*
G36*
G01X334228Y1146200D02*
X334628Y1146058D01*
Y1145308D01*
X334228Y1145165D01*
X334028D01*
Y1146200D01*
X334228D01*
G37*
G36*
G01Y1153250D02*
X334628Y1153108D01*
Y1152358D01*
X334228Y1152215D01*
X334028D01*
Y1153250D01*
X334228D01*
G37*
G36*
G01Y1155600D02*
X334628Y1155458D01*
Y1154708D01*
X334228Y1154565D01*
X334028D01*
Y1155600D01*
X334228D01*
G37*
G36*
G01X333828Y1153390D02*
X333428Y1153533D01*
Y1154283D01*
X333828Y1154425D01*
X334028D01*
Y1153390D01*
X333828D01*
G37*
G36*
G01Y1155740D02*
X333428Y1155883D01*
Y1156633D01*
X333828Y1156775D01*
X334028D01*
Y1155740D01*
X333828D01*
G37*
G36*
G01X334228Y1157950D02*
X334628Y1157808D01*
Y1157058D01*
X334228Y1156915D01*
X334028D01*
Y1157950D01*
X334228D01*
G37*
G36*
G01X333828Y1158090D02*
X333428Y1158233D01*
Y1158983D01*
X333828Y1159125D01*
X334028D01*
Y1158090D01*
X333828D01*
G37*
G36*
G01X334228Y1160300D02*
X334628Y1160158D01*
Y1159408D01*
X334228Y1159265D01*
X334028D01*
Y1160300D01*
X334228D01*
G37*
G36*
G01X333828Y1160440D02*
X333428Y1160583D01*
Y1161333D01*
X333828Y1161475D01*
X334028D01*
Y1160440D01*
X333828D01*
G37*
G36*
G01X331428Y1146340D02*
X331028Y1146483D01*
Y1147233D01*
X331428Y1147375D01*
X331628D01*
Y1146340D01*
X331428D01*
G37*
G36*
G01Y1148690D02*
X331028Y1148833D01*
Y1149583D01*
X331428Y1149725D01*
X331628D01*
Y1148690D01*
X331428D01*
G37*
G36*
G01Y1151040D02*
X331028Y1151183D01*
Y1151933D01*
X331428Y1152075D01*
X331628D01*
Y1151040D01*
X331428D01*
G37*
G36*
G01Y1155740D02*
X331028Y1155883D01*
Y1156633D01*
X331428Y1156775D01*
X331628D01*
Y1155740D01*
X331428D01*
G37*
G36*
G01Y1158090D02*
X331028Y1158233D01*
Y1158983D01*
X331428Y1159125D01*
X331628D01*
Y1158090D01*
X331428D01*
G37*
G36*
G01Y1160440D02*
X331028Y1160583D01*
Y1161333D01*
X331428Y1161475D01*
X331628D01*
Y1160440D01*
X331428D01*
G37*
G36*
G01Y1153390D02*
X331028Y1153533D01*
Y1154283D01*
X331428Y1154425D01*
X331628D01*
Y1153390D01*
X331428D01*
G37*
G36*
G01X331828Y1146200D02*
X332228Y1146058D01*
Y1145308D01*
X331828Y1145165D01*
X331628D01*
Y1146200D01*
X331828D01*
G37*
G36*
G01Y1148550D02*
X332228Y1148408D01*
Y1147658D01*
X331828Y1147515D01*
X331628D01*
Y1148550D01*
X331828D01*
G37*
G36*
G01Y1150900D02*
X332228Y1150758D01*
Y1150008D01*
X331828Y1149865D01*
X331628D01*
Y1150900D01*
X331828D01*
G37*
G36*
G01Y1157950D02*
X332228Y1157808D01*
Y1157058D01*
X331828Y1156915D01*
X331628D01*
Y1157950D01*
X331828D01*
G37*
G36*
G01Y1160300D02*
X332228Y1160158D01*
Y1159408D01*
X331828Y1159265D01*
X331628D01*
Y1160300D01*
X331828D01*
G37*
G36*
G01Y1153250D02*
X332228Y1153108D01*
Y1152358D01*
X331828Y1152215D01*
X331628D01*
Y1153250D01*
X331828D01*
G37*
G36*
G01Y1155600D02*
X332228Y1155458D01*
Y1154708D01*
X331828Y1154565D01*
X331628D01*
Y1155600D01*
X331828D01*
G37*
G36*
G01X333028Y1146200D02*
X333428Y1146058D01*
Y1145308D01*
X333028Y1145165D01*
X332828D01*
Y1146200D01*
X333028D01*
G37*
G36*
G01X332628Y1146340D02*
X332228Y1146483D01*
Y1147233D01*
X332628Y1147375D01*
X332828D01*
Y1146340D01*
X332628D01*
G37*
G36*
G01Y1148690D02*
X332228Y1148833D01*
Y1149583D01*
X332628Y1149725D01*
X332828D01*
Y1148690D01*
X332628D01*
G37*
G36*
G01Y1151040D02*
X332228Y1151183D01*
Y1151933D01*
X332628Y1152075D01*
X332828D01*
Y1151040D01*
X332628D01*
G37*
G36*
G01X333028Y1148550D02*
X333428Y1148408D01*
Y1147658D01*
X333028Y1147515D01*
X332828D01*
Y1148550D01*
X333028D01*
G37*
G36*
G01Y1150900D02*
X333428Y1150758D01*
Y1150008D01*
X333028Y1149865D01*
X332828D01*
Y1150900D01*
X333028D01*
G37*
G36*
G01X332628Y1153390D02*
X332228Y1153533D01*
Y1154283D01*
X332628Y1154425D01*
X332828D01*
Y1153390D01*
X332628D01*
G37*
G36*
G01Y1155740D02*
X332228Y1155883D01*
Y1156633D01*
X332628Y1156775D01*
X332828D01*
Y1155740D01*
X332628D01*
G37*
G36*
G01Y1158090D02*
X332228Y1158233D01*
Y1158983D01*
X332628Y1159125D01*
X332828D01*
Y1158090D01*
X332628D01*
G37*
G36*
G01Y1160440D02*
X332228Y1160583D01*
Y1161333D01*
X332628Y1161475D01*
X332828D01*
Y1160440D01*
X332628D01*
G37*
G36*
G01X333028Y1153250D02*
X333428Y1153108D01*
Y1152358D01*
X333028Y1152215D01*
X332828D01*
Y1153250D01*
X333028D01*
G37*
G36*
G01Y1155600D02*
X333428Y1155458D01*
Y1154708D01*
X333028Y1154565D01*
X332828D01*
Y1155600D01*
X333028D01*
G37*
G36*
G01Y1157950D02*
X333428Y1157808D01*
Y1157058D01*
X333028Y1156915D01*
X332828D01*
Y1157950D01*
X333028D01*
G37*
G36*
G01Y1160300D02*
X333428Y1160158D01*
Y1159408D01*
X333028Y1159265D01*
X332828D01*
Y1160300D01*
X333028D01*
G37*
G36*
G01X330628Y1150900D02*
X331028Y1150758D01*
Y1150008D01*
X330628Y1149865D01*
X330428D01*
Y1150900D01*
X330628D01*
G37*
G36*
G01Y1148550D02*
X331028Y1148408D01*
Y1147658D01*
X330628Y1147515D01*
X330428D01*
Y1148550D01*
X330628D01*
G37*
G36*
G01X330228Y1148690D02*
X329828Y1148833D01*
Y1149583D01*
X330228Y1149725D01*
X330428D01*
Y1148690D01*
X330228D01*
G37*
G36*
G01Y1146340D02*
X329828Y1146483D01*
Y1147233D01*
X330228Y1147375D01*
X330428D01*
Y1146340D01*
X330228D01*
G37*
G36*
G01Y1151040D02*
X329828Y1151183D01*
Y1151933D01*
X330228Y1152075D01*
X330428D01*
Y1151040D01*
X330228D01*
G37*
G36*
G01X330628Y1146200D02*
X331028Y1146058D01*
Y1145308D01*
X330628Y1145165D01*
X330428D01*
Y1146200D01*
X330628D01*
G37*
G36*
G01X330228Y1158090D02*
X329828Y1158233D01*
Y1158983D01*
X330228Y1159125D01*
X330428D01*
Y1158090D01*
X330228D01*
G37*
G36*
G01X330628Y1155600D02*
X331028Y1155458D01*
Y1154708D01*
X330628Y1154565D01*
X330428D01*
Y1155600D01*
X330628D01*
G37*
G36*
G01Y1153250D02*
X331028Y1153108D01*
Y1152358D01*
X330628Y1152215D01*
X330428D01*
Y1153250D01*
X330628D01*
G37*
G36*
G01X330228Y1155740D02*
X329828Y1155883D01*
Y1156633D01*
X330228Y1156775D01*
X330428D01*
Y1155740D01*
X330228D01*
G37*
G36*
G01Y1153390D02*
X329828Y1153533D01*
Y1154283D01*
X330228Y1154425D01*
X330428D01*
Y1153390D01*
X330228D01*
G37*
G36*
G01X330628Y1160300D02*
X331028Y1160158D01*
Y1159408D01*
X330628Y1159265D01*
X330428D01*
Y1160300D01*
X330628D01*
G37*
G36*
G01X330228Y1160440D02*
X329828Y1160583D01*
Y1161333D01*
X330228Y1161475D01*
X330428D01*
Y1160440D01*
X330228D01*
G37*
G36*
G01X330628Y1157950D02*
X331028Y1157808D01*
Y1157058D01*
X330628Y1156915D01*
X330428D01*
Y1157950D01*
X330628D01*
G37*
G36*
G01X324628Y1146285D02*
X325028Y1146143D01*
Y1145393D01*
X324628Y1145250D01*
X324428D01*
Y1146285D01*
X324628D01*
G37*
G36*
G01Y1148635D02*
X325028Y1148493D01*
Y1147743D01*
X324628Y1147600D01*
X324428D01*
Y1148635D01*
X324628D01*
G37*
G36*
G01Y1150985D02*
X325028Y1150843D01*
Y1150093D01*
X324628Y1149950D01*
X324428D01*
Y1150985D01*
X324628D01*
G37*
G36*
G01X324228Y1146425D02*
X323828Y1146568D01*
Y1147318D01*
X324228Y1147460D01*
X324428D01*
Y1146425D01*
X324228D01*
G37*
G36*
G01Y1148775D02*
X323828Y1148918D01*
Y1149668D01*
X324228Y1149810D01*
X324428D01*
Y1148775D01*
X324228D01*
G37*
G36*
G01Y1151125D02*
X323828Y1151268D01*
Y1152018D01*
X324228Y1152160D01*
X324428D01*
Y1151125D01*
X324228D01*
G37*
G36*
G01X324628Y1153335D02*
X325028Y1153193D01*
Y1152443D01*
X324628Y1152300D01*
X324428D01*
Y1153335D01*
X324628D01*
G37*
G36*
G01Y1155685D02*
X325028Y1155543D01*
Y1154793D01*
X324628Y1154650D01*
X324428D01*
Y1155685D01*
X324628D01*
G37*
G36*
G01X324228Y1153475D02*
X323828Y1153618D01*
Y1154368D01*
X324228Y1154510D01*
X324428D01*
Y1153475D01*
X324228D01*
G37*
G36*
G01Y1155825D02*
X323828Y1155968D01*
Y1156718D01*
X324228Y1156860D01*
X324428D01*
Y1155825D01*
X324228D01*
G37*
G36*
G01X324628Y1158035D02*
X325028Y1157893D01*
Y1157143D01*
X324628Y1157000D01*
X324428D01*
Y1158035D01*
X324628D01*
G37*
G36*
G01X324228Y1158175D02*
X323828Y1158318D01*
Y1159068D01*
X324228Y1159210D01*
X324428D01*
Y1158175D01*
X324228D01*
G37*
G36*
G01X324628Y1160385D02*
X325028Y1160243D01*
Y1159493D01*
X324628Y1159350D01*
X324428D01*
Y1160385D01*
X324628D01*
G37*
G36*
G01X324228Y1160525D02*
X323828Y1160668D01*
Y1161418D01*
X324228Y1161560D01*
X324428D01*
Y1160525D01*
X324228D01*
G37*
G36*
G01X322228Y1148635D02*
X322628Y1148493D01*
Y1147743D01*
X322228Y1147600D01*
X322028D01*
Y1148635D01*
X322228D01*
G37*
G36*
G01Y1150985D02*
X322628Y1150843D01*
Y1150093D01*
X322228Y1149950D01*
X322028D01*
Y1150985D01*
X322228D01*
G37*
G36*
G01Y1146285D02*
X322628Y1146143D01*
Y1145393D01*
X322228Y1145250D01*
X322028D01*
Y1146285D01*
X322228D01*
G37*
G36*
G01Y1153335D02*
X322628Y1153193D01*
Y1152443D01*
X322228Y1152300D01*
X322028D01*
Y1153335D01*
X322228D01*
G37*
G36*
G01Y1155685D02*
X322628Y1155543D01*
Y1154793D01*
X322228Y1154650D01*
X322028D01*
Y1155685D01*
X322228D01*
G37*
G36*
G01Y1158035D02*
X322628Y1157893D01*
Y1157143D01*
X322228Y1157000D01*
X322028D01*
Y1158035D01*
X322228D01*
G37*
G36*
G01X323428Y1148635D02*
X323828Y1148493D01*
Y1147743D01*
X323428Y1147600D01*
X323228D01*
Y1148635D01*
X323428D01*
G37*
G36*
G01Y1150985D02*
X323828Y1150843D01*
Y1150093D01*
X323428Y1149950D01*
X323228D01*
Y1150985D01*
X323428D01*
G37*
G36*
G01X323028Y1146425D02*
X322628Y1146568D01*
Y1147318D01*
X323028Y1147460D01*
X323228D01*
Y1146425D01*
X323028D01*
G37*
G36*
G01Y1148775D02*
X322628Y1148918D01*
Y1149668D01*
X323028Y1149810D01*
X323228D01*
Y1148775D01*
X323028D01*
G37*
G36*
G01Y1151125D02*
X322628Y1151268D01*
Y1152018D01*
X323028Y1152160D01*
X323228D01*
Y1151125D01*
X323028D01*
G37*
G36*
G01X323428Y1146285D02*
X323828Y1146143D01*
Y1145393D01*
X323428Y1145250D01*
X323228D01*
Y1146285D01*
X323428D01*
G37*
G36*
G01Y1153335D02*
X323828Y1153193D01*
Y1152443D01*
X323428Y1152300D01*
X323228D01*
Y1153335D01*
X323428D01*
G37*
G36*
G01Y1155685D02*
X323828Y1155543D01*
Y1154793D01*
X323428Y1154650D01*
X323228D01*
Y1155685D01*
X323428D01*
G37*
G36*
G01X323028Y1153475D02*
X322628Y1153618D01*
Y1154368D01*
X323028Y1154510D01*
X323228D01*
Y1153475D01*
X323028D01*
G37*
G36*
G01Y1155825D02*
X322628Y1155968D01*
Y1156718D01*
X323028Y1156860D01*
X323228D01*
Y1155825D01*
X323028D01*
G37*
G36*
G01X323428Y1158035D02*
X323828Y1157893D01*
Y1157143D01*
X323428Y1157000D01*
X323228D01*
Y1158035D01*
X323428D01*
G37*
G36*
G01X323028Y1158175D02*
X322628Y1158318D01*
Y1159068D01*
X323028Y1159210D01*
X323228D01*
Y1158175D01*
X323028D01*
G37*
G36*
G01X323428Y1160385D02*
X323828Y1160243D01*
Y1159493D01*
X323428Y1159350D01*
X323228D01*
Y1160385D01*
X323428D01*
G37*
G36*
G01X333828Y1167490D02*
X333428Y1167633D01*
Y1168383D01*
X333828Y1168525D01*
X334028D01*
Y1167490D01*
X333828D01*
G37*
G36*
G01X334228Y1162650D02*
X334628Y1162508D01*
Y1161758D01*
X334228Y1161615D01*
X334028D01*
Y1162650D01*
X334228D01*
G37*
G36*
G01Y1165000D02*
X334628Y1164858D01*
Y1164108D01*
X334228Y1163965D01*
X334028D01*
Y1165000D01*
X334228D01*
G37*
G36*
G01Y1167350D02*
X334628Y1167208D01*
Y1166458D01*
X334228Y1166315D01*
X334028D01*
Y1167350D01*
X334228D01*
G37*
G36*
G01X333828Y1162790D02*
X333428Y1162933D01*
Y1163683D01*
X333828Y1163825D01*
X334028D01*
Y1162790D01*
X333828D01*
G37*
G36*
G01Y1165140D02*
X333428Y1165283D01*
Y1166033D01*
X333828Y1166175D01*
X334028D01*
Y1165140D01*
X333828D01*
G37*
G36*
G01X331428Y1162790D02*
X331028Y1162933D01*
Y1163683D01*
X331428Y1163825D01*
X331628D01*
Y1162790D01*
X331428D01*
G37*
G36*
G01Y1165140D02*
X331028Y1165283D01*
Y1166033D01*
X331428Y1166175D01*
X331628D01*
Y1165140D01*
X331428D01*
G37*
G36*
G01Y1167490D02*
X331028Y1167633D01*
Y1168383D01*
X331428Y1168525D01*
X331628D01*
Y1167490D01*
X331428D01*
G37*
G36*
G01X331828Y1162650D02*
X332228Y1162508D01*
Y1161758D01*
X331828Y1161615D01*
X331628D01*
Y1162650D01*
X331828D01*
G37*
G36*
G01Y1165000D02*
X332228Y1164858D01*
Y1164108D01*
X331828Y1163965D01*
X331628D01*
Y1165000D01*
X331828D01*
G37*
G36*
G01Y1167350D02*
X332228Y1167208D01*
Y1166458D01*
X331828Y1166315D01*
X331628D01*
Y1167350D01*
X331828D01*
G37*
G36*
G01X332628Y1162790D02*
X332228Y1162933D01*
Y1163683D01*
X332628Y1163825D01*
X332828D01*
Y1162790D01*
X332628D01*
G37*
G36*
G01Y1165140D02*
X332228Y1165283D01*
Y1166033D01*
X332628Y1166175D01*
X332828D01*
Y1165140D01*
X332628D01*
G37*
G36*
G01Y1167490D02*
X332228Y1167633D01*
Y1168383D01*
X332628Y1168525D01*
X332828D01*
Y1167490D01*
X332628D01*
G37*
G36*
G01X333028Y1162650D02*
X333428Y1162508D01*
Y1161758D01*
X333028Y1161615D01*
X332828D01*
Y1162650D01*
X333028D01*
G37*
G36*
G01Y1165000D02*
X333428Y1164858D01*
Y1164108D01*
X333028Y1163965D01*
X332828D01*
Y1165000D01*
X333028D01*
G37*
G36*
G01Y1167350D02*
X333428Y1167208D01*
Y1166458D01*
X333028Y1166315D01*
X332828D01*
Y1167350D01*
X333028D01*
G37*
G36*
G01X330628D02*
X331028Y1167208D01*
Y1166458D01*
X330628Y1166315D01*
X330428D01*
Y1167350D01*
X330628D01*
G37*
G36*
G01Y1165000D02*
X331028Y1164858D01*
Y1164108D01*
X330628Y1163965D01*
X330428D01*
Y1165000D01*
X330628D01*
G37*
G36*
G01Y1162650D02*
X331028Y1162508D01*
Y1161758D01*
X330628Y1161615D01*
X330428D01*
Y1162650D01*
X330628D01*
G37*
G36*
G01X330228Y1167490D02*
X329828Y1167633D01*
Y1168383D01*
X330228Y1168525D01*
X330428D01*
Y1167490D01*
X330228D01*
G37*
G36*
G01Y1165140D02*
X329828Y1165283D01*
Y1166033D01*
X330228Y1166175D01*
X330428D01*
Y1165140D01*
X330228D01*
G37*
G36*
G01Y1162790D02*
X329828Y1162933D01*
Y1163683D01*
X330228Y1163825D01*
X330428D01*
Y1162790D01*
X330228D01*
G37*
G36*
G01X324628Y1162735D02*
X325028Y1162593D01*
Y1161843D01*
X324628Y1161700D01*
X324428D01*
Y1162735D01*
X324628D01*
G37*
G36*
G01X392719Y1270908D02*
Y1274908D01*
X390719Y1276908D01*
X372219D01*
X369719Y1279408D01*
Y1295643D01*
X367548Y1297814D01*
X338625D01*
X337719Y1296908D01*
Y1292908D01*
X339719Y1290908D01*
X361219D01*
X362219Y1289908D01*
Y1279994D01*
X372205Y1270008D01*
X391819D01*
X392719Y1270908D01*
G37*
G36*
G01X326455Y1575686D02*
G03I-720J0D01*
G37*
G36*
G01Y1580678D02*
G03I-720J0D01*
G37*
G36*
G01X333559D02*
G03I-720J0D01*
G37*
G36*
G01X338515D02*
G03I-720J0D01*
G37*
G36*
G01X333559Y1575686D02*
G03I-720J0D01*
G37*
G36*
G01X338515D02*
G03I-720J0D01*
G37*
G36*
G01X326455Y1587598D02*
G03I-720J0D01*
G37*
G36*
G01Y1592590D02*
G03I-720J0D01*
G37*
G36*
G01X333559D02*
G03I-720J0D01*
G37*
G36*
G01X338515D02*
G03I-720J0D01*
G37*
G36*
G01X333559Y1587598D02*
G03I-720J0D01*
G37*
G36*
G01X338515D02*
G03I-720J0D01*
G37*
G36*
G01X326799Y1599884D02*
G03I-720J0D01*
G37*
G36*
G01X331755D02*
G03I-720J0D01*
G37*
G36*
G01X338859D02*
G03I-720J0D01*
G37*
G36*
G01X326799Y1604876D02*
G03I-720J0D01*
G37*
G36*
G01Y1611796D02*
G03I-720J0D01*
G37*
G36*
G01X331755Y1604876D02*
G03I-720J0D01*
G37*
G36*
G01Y1611796D02*
G03I-720J0D01*
G37*
G36*
G01X326799Y1616788D02*
G03I-720J0D01*
G37*
G36*
G01X331755D02*
G03I-720J0D01*
G37*
G36*
G01X338859D02*
G03I-720J0D01*
G37*
G36*
G01Y1604876D02*
G03I-720J0D01*
G37*
G36*
G01Y1611796D02*
G03I-720J0D01*
G37*
G36*
G01X346589Y192716D02*
G03I-720J0D01*
G37*
G36*
G01X348707Y755362D02*
G03I-707J0D01*
G37*
G36*
G01X345619Y1575686D02*
G03I-720J0D01*
G37*
G36*
G01X350575D02*
G03I-720J0D01*
G37*
G36*
G01X345619Y1580678D02*
G03I-720J0D01*
G37*
G36*
G01X350575D02*
G03I-720J0D01*
G37*
G36*
G01X345619Y1587598D02*
G03I-720J0D01*
G37*
G36*
G01X350575D02*
G03I-720J0D01*
G37*
G36*
G01X345619Y1592590D02*
G03I-720J0D01*
G37*
G36*
G01X350575D02*
G03I-720J0D01*
G37*
G36*
G01X343815Y1599884D02*
G03I-720J0D01*
G37*
G36*
G01X350919D02*
G03I-720J0D01*
G37*
G36*
G01X343815Y1616788D02*
G03I-720J0D01*
G37*
G36*
G01Y1604876D02*
G03I-720J0D01*
G37*
G36*
G01Y1611796D02*
G03I-720J0D01*
G37*
G36*
G01X350919Y1604876D02*
G03I-720J0D01*
G37*
G36*
G01Y1611796D02*
G03I-720J0D01*
G37*
G36*
G01Y1616788D02*
G03I-720J0D01*
G37*
G36*
G01X356970Y216342D02*
G03I-720J0D01*
G37*
G36*
G01X358929Y208169D02*
G03I-720J0D01*
G37*
G36*
G01X370410Y431812D02*
G03I-720J0D01*
G37*
G36*
G01X366690Y444662D02*
G03I-720J0D01*
G37*
G36*
G01X357679Y1580678D02*
G03I-720J0D01*
G37*
G36*
G01X362635D02*
G03I-720J0D01*
G37*
G36*
G01X357679Y1575592D02*
G03I-720J0D01*
G37*
G36*
G01X362635D02*
G03I-720J0D01*
G37*
G36*
G01X369739Y1575686D02*
G03I-720J0D01*
G37*
G36*
G01Y1580678D02*
G03I-720J0D01*
G37*
G36*
G01X355875Y1599884D02*
G03I-720J0D01*
G37*
G36*
G01X357679Y1592590D02*
G03I-720J0D01*
G37*
G36*
G01X362635D02*
G03I-720J0D01*
G37*
G36*
G01X357679Y1587598D02*
G03I-720J0D01*
G37*
G36*
G01X362635D02*
G03I-720J0D01*
G37*
G36*
G01X367935Y1599790D02*
G03I-720J0D01*
G37*
G36*
G01X362979D02*
G03I-720J0D01*
G37*
G36*
G01X369739Y1587598D02*
G03I-720J0D01*
G37*
G36*
G01Y1592590D02*
G03I-720J0D01*
G37*
G36*
G01X355875Y1604876D02*
G03I-720J0D01*
G37*
G36*
G01Y1611796D02*
G03I-720J0D01*
G37*
G36*
G01Y1616788D02*
G03I-720J0D01*
G37*
G36*
G01X367935D02*
G03I-720J0D01*
G37*
G36*
G01X362979D02*
G03I-720J0D01*
G37*
G36*
G01X367935Y1604876D02*
G03I-720J0D01*
G37*
G36*
G01Y1611796D02*
G03I-720J0D01*
G37*
G36*
G01X362979Y1604876D02*
G03I-720J0D01*
G37*
G36*
G01Y1611796D02*
G03I-720J0D01*
G37*
G36*
G01X376050Y121182D02*
G03I-720J0D01*
G37*
G36*
G01X375701Y131433D02*
G03I-720J0D01*
G37*
G36*
G01X386240Y429262D02*
G03I-720J0D01*
G37*
G36*
G01X373910Y438342D02*
G03I-720J0D01*
G37*
G36*
G01X385230Y438662D02*
G03I-720J0D01*
G37*
G36*
G01X386450Y460922D02*
G03I-720J0D01*
G37*
G36*
G01X383580Y471122D02*
G03I-720J0D01*
G37*
G36*
G01X423426Y1270008D02*
X394619D01*
X393719Y1270908D01*
Y1275384D01*
X391195Y1277908D01*
X373219D01*
X370719Y1280408D01*
Y1283908D01*
X371419Y1284608D01*
X398798D01*
X398856Y1284550D01*
X402053D01*
X402719Y1283884D01*
Y1278884D01*
X404695Y1276908D01*
X422872D01*
X424372Y1275408D01*
Y1270951D01*
X423426Y1270008D01*
G37*
G36*
G01X381650Y1531402D02*
G03I-720J0D01*
G37*
G36*
G01X384930Y1534152D02*
G03I-720J0D01*
G37*
G36*
G01X374695Y1575686D02*
G03I-720J0D01*
G37*
G36*
G01Y1580678D02*
G03I-720J0D01*
G37*
G36*
G01Y1587598D02*
G03I-720J0D01*
G37*
G36*
G01Y1592590D02*
G03I-720J0D01*
G37*
G36*
G01X379995Y1599884D02*
G03I-720J0D01*
G37*
G36*
G01X375039D02*
G03I-720J0D01*
G37*
G36*
G01X379995Y1604876D02*
G03I-720J0D01*
G37*
G36*
G01Y1611796D02*
G03I-720J0D01*
G37*
G36*
G01X375039Y1604876D02*
G03I-720J0D01*
G37*
G36*
G01Y1611796D02*
G03I-720J0D01*
G37*
G36*
G01X379995Y1616788D02*
G03I-720J0D01*
G37*
G36*
G01X375039D02*
G03I-720J0D01*
G37*
G36*
G01X394550Y62062D02*
G03I-720J0D01*
G37*
G36*
G01X400520Y59662D02*
G03I-720J0D01*
G37*
G36*
G01X403980Y439352D02*
G03I-720J0D01*
G37*
G36*
G01X391870Y445302D02*
G03I-720J0D01*
G37*
G36*
G01X397290Y472602D02*
G03I-720J0D01*
G37*
G36*
G01X392080Y495712D02*
G03I-720J0D01*
G37*
G36*
G01X403500Y499372D02*
G03I-720J0D01*
G37*
G36*
G01X395580Y518812D02*
G03I-720J0D01*
G37*
G36*
G01X403920Y572622D02*
G03I-720J0D01*
G37*
G36*
G01X392090Y1424782D02*
G03I-720J0D01*
G37*
G36*
G01X395630Y1632364D02*
G03I-720J0D01*
G37*
G36*
G01Y1637320D02*
G03I-720J0D01*
G37*
G36*
G01X402737Y1671745D02*
G03I-491J0D01*
G37*
G36*
G01X404520Y59662D02*
G03I-720J0D01*
G37*
G36*
G01X413650Y62572D02*
G03I-720J0D01*
G37*
G36*
G01X408210Y216912D02*
G03I-720J0D01*
G37*
G36*
G01X413540Y231922D02*
G03I-720J0D01*
G37*
G36*
G01X410810Y241932D02*
G03I-720J0D01*
G37*
G36*
G01X417730Y439352D02*
G03I-720J0D01*
G37*
G36*
G01X415850Y480202D02*
G03I-720J0D01*
G37*
G36*
G01X404445Y938600D02*
X405365D01*
X406764Y937201D01*
X411344D01*
X411739Y936806D01*
Y933999D01*
X409953Y932212D01*
X409875Y932134D01*
Y930170D01*
X409613Y929908D01*
X409472Y930045D01*
G03X408569Y930409I-903J-938D01*
G03X407522Y929880I0J-1301D01*
G01X406655D01*
X406631Y929886D01*
G03X406308Y929927I-324J-1260D01*
G03X405985Y929886I1J-1301D01*
G01X405961Y929880D01*
X404307D01*
X404060Y930127D01*
Y938215D01*
X404445Y938600D01*
G37*
G36*
G01X413647Y937365D02*
X415447D01*
X416047Y936765D01*
Y934365D01*
X417994Y932418D01*
X428465D01*
X428961Y931922D01*
Y928449D01*
X426433Y925921D01*
X419830D01*
G02X419453Y926456I0J400D01*
G03X419530Y926896I-1224J441D01*
G03X418229Y928197I-1301J0D01*
G03X417090Y927525I0J-1301D01*
G01X417033Y927422D01*
X411353D01*
X410886Y927889D01*
Y932009D01*
X413047Y934170D01*
Y936765D01*
X413647Y937365D01*
G37*
G36*
G01X404771Y966581D02*
X427344D01*
X427675Y966250D01*
Y961650D01*
X427249Y961224D01*
X408209D01*
X407625Y960640D01*
Y952836D01*
X408375Y952086D01*
X427139D01*
X427645Y951580D01*
Y946840D01*
X427219Y946414D01*
X406429D01*
X405205Y945190D01*
X404095D01*
X403861Y945424D01*
Y946804D01*
X403912Y946923D01*
G03X404031Y947508I-1382J586D01*
G01Y949621D01*
G03X403684Y950580I-1501J-1D01*
G01Y952957D01*
G03X404031Y953916I-1154J960D01*
G01Y956030D01*
G03X403684Y956989I-1501J-1D01*
G01Y959531D01*
G03X403931Y960326I-1156J795D01*
G03X403892Y960653I-1402J-1D01*
G01X403887Y960675D01*
Y962436D01*
G03X403684Y963149I-1357J-1D01*
G01Y965494D01*
X404771Y966581D01*
G37*
G36*
G01X417796Y937263D02*
X428369D01*
X428664Y936967D01*
Y933613D01*
X428408Y933357D01*
X418299D01*
X417513Y934143D01*
Y936980D01*
X417796Y937263D01*
G37*
G36*
G01X404361Y943260D02*
X406591Y945490D01*
X411767D01*
X412467Y944790D01*
Y938854D01*
X411907Y938294D01*
X406965D01*
X404361Y940898D01*
Y943260D01*
G37*
G36*
G01X404665Y1009888D02*
X427237D01*
X427625Y1009500D01*
Y1005120D01*
X427177Y1004672D01*
X408507D01*
X407495Y1003660D01*
Y996469D01*
X408605Y995359D01*
X427376D01*
X427695Y995040D01*
Y990530D01*
X427342Y990177D01*
X408492D01*
X407535Y989220D01*
Y981995D01*
X408455Y981075D01*
X427400D01*
X427675Y980800D01*
Y976200D01*
X427228Y975753D01*
X406629D01*
X406603Y975779D01*
X404204D01*
X404007Y975976D01*
Y976393D01*
X403982Y976418D01*
Y996621D01*
G03X404357Y997574I-1021J952D01*
G01Y999631D01*
X404358Y999635D01*
G03X404359Y999684I-1396J53D01*
G03X403982Y1000638I-1397J0D01*
G01Y1003030D01*
G03X404359Y1003984I-1020J954D01*
G01Y1006093D01*
G03X403982Y1007047I-1397J0D01*
G01Y1009205D01*
X404665Y1009888D01*
G37*
G36*
G01X405609Y974774D02*
X411843D01*
X412543Y974074D01*
Y968138D01*
X411983Y967578D01*
X407744D01*
X407738Y967584D01*
X406188D01*
X403630Y970142D01*
Y972450D01*
G03X403812Y972924I-1100J694D01*
G01X403822Y972987D01*
X405609Y974774D01*
G37*
G36*
G01X404910Y1018151D02*
X415764D01*
X416114Y1017801D01*
Y1016157D01*
G02X415590Y1015776I-400J-1D01*
G03X415185Y1015841I-406J-1236D01*
G03Y1013239I0J-1301D01*
G03X415590Y1013304I-1J1301D01*
G02X416114Y1012923I124J-380D01*
G01Y1011534D01*
X415554Y1010974D01*
X405575D01*
X404525Y1012024D01*
Y1017766D01*
X404910Y1018151D01*
G37*
G36*
G01X427077Y1024488D02*
X427655Y1023910D01*
Y1019120D01*
X427367Y1018832D01*
X404973D01*
X404454Y1019351D01*
Y1035886D01*
X404950Y1036382D01*
X408754D01*
X409179Y1035957D01*
Y1031494D01*
X408576Y1030891D01*
X408554D01*
X408246Y1030583D01*
Y1025388D01*
X409146Y1024488D01*
X427077D01*
G37*
G36*
G01X409392Y1030163D02*
X410195Y1030966D01*
X421599D01*
X423714Y1028851D01*
Y1025703D01*
X423655Y1025644D01*
X409734D01*
X409392Y1025986D01*
Y1030163D01*
G37*
G36*
G01X455773Y1270008D02*
X426442D01*
X425544Y1270906D01*
Y1275906D01*
X423542Y1277908D01*
X405219D01*
X403719Y1279408D01*
Y1283908D01*
X404419Y1284608D01*
X431145D01*
X431203Y1284550D01*
X434400D01*
X435219Y1283731D01*
Y1278731D01*
X437042Y1276908D01*
X455219D01*
X456719Y1275408D01*
Y1270951D01*
X455773Y1270008D01*
G37*
G36*
G01X418874Y1403989D02*
X436074D01*
X436274Y1404189D01*
Y1421389D01*
X436074Y1421589D01*
X418874D01*
X418674Y1421389D01*
Y1404189D01*
X418874Y1403989D01*
G37*
G36*
G01X410723Y1670244D02*
G03I-491J0D01*
G37*
G36*
G01X418033Y1738108D02*
X685314D01*
G02X685500Y1737984I1J-200D01*
G01X685663Y1737584D01*
X685638Y1737466D01*
X685595Y1737423D01*
G03X684394Y1736176I22078J-22466D01*
G02X684246Y1736110I-149J134D01*
G01X609913D01*
X609882Y1736121D01*
G03X609252Y1736222I-629J-1909D01*
G03X608622Y1736121I-1J-2010D01*
G01X608591Y1736110D01*
X594165D01*
X594134Y1736121D01*
G03X593504Y1736222I-629J-1909D01*
G03X592874Y1736121I-1J-2010D01*
G01X592843Y1736110D01*
X578417D01*
X578386Y1736121D01*
G03X577756Y1736222I-629J-1909D01*
G03X577126Y1736121I-1J-2010D01*
G01X577095Y1736110D01*
X563866D01*
X563813Y1736126D01*
X563788Y1736142D01*
G03X563516Y1736222I-272J-421D01*
G01X560500D01*
G03X560228Y1736142I0J-501D01*
G01X560203Y1736126D01*
X560150Y1736110D01*
X542984D01*
X542953Y1736121D01*
G03X542323Y1736222I-629J-1909D01*
G03X541693Y1736121I-1J-2010D01*
G01X541662Y1736110D01*
X527236D01*
X527205Y1736121D01*
G03X526575Y1736222I-629J-1909D01*
G03X525945Y1736121I-1J-2010D01*
G01X525914Y1736110D01*
X511488D01*
X511457Y1736121D01*
G03X510827Y1736222I-629J-1909D01*
G03X510197Y1736121I-1J-2010D01*
G01X510166Y1736110D01*
X496937D01*
X496884Y1736126D01*
X496859Y1736142D01*
G03X496588Y1736222I-272J-421D01*
G01X493570D01*
G03X493299Y1736142I1J-501D01*
G01X493274Y1736126D01*
X493221Y1736110D01*
X419101D01*
G02X418953Y1736176I1J200D01*
G03X417752Y1737423I-23279J-21219D01*
G01X417709Y1737466D01*
X417684Y1737584D01*
X417847Y1737984D01*
G02X418033Y1738108I185J-76D01*
G37*
G36*
G01X431700Y132672D02*
G03I-720J0D01*
G37*
G36*
G01X422930Y221452D02*
G03I-720J0D01*
G37*
G36*
G01X421430Y242482D02*
G03I-720J0D01*
G37*
G36*
G01X425969Y338061D02*
G03I-720J0D01*
G37*
G36*
G01X425700Y439462D02*
G03I-720J0D01*
G37*
G36*
G01X428510Y500862D02*
G03I-720J0D01*
G37*
G36*
G01X428600Y506442D02*
G03I-720J0D01*
G37*
G36*
G01X429230Y515842D02*
G03I-720J0D01*
G37*
G36*
G01X451120Y338812D02*
G03I-720J0D01*
G37*
G36*
G01X485827Y1276908D02*
X469219D01*
X467719Y1278408D01*
Y1283408D01*
X466577Y1284550D01*
X436861D01*
X436219Y1283908D01*
Y1279408D01*
X437719Y1277908D01*
X455719D01*
X457721Y1275906D01*
Y1270906D01*
X458619Y1270008D01*
X486719D01*
X487327Y1270616D01*
Y1275408D01*
X485827Y1276908D01*
G37*
G36*
G01X461020Y303662D02*
G03I-720J0D01*
G37*
G36*
G01X469210Y340572D02*
G03I-720J0D01*
G37*
G36*
G01X456046Y520389D02*
G03I-720J0D01*
G37*
G36*
G01X463573Y943039D02*
X465835D01*
X465862Y943031D01*
G03X466115Y942996I247J855D01*
G01X467240D01*
X467674Y942562D01*
Y941277D01*
X468595Y940356D01*
X476287D01*
X477103Y939540D01*
Y938155D01*
X477100Y938137D01*
G03X477077Y937896I1278J-244D01*
G03X477100Y937655I1301J3D01*
G01X477103Y937637D01*
Y934046D01*
X477093Y934016D01*
G03X477027Y933598I1286J-417D01*
G03X477093Y933180I1352J-1D01*
G01X477103Y933150D01*
Y931747D01*
X477100Y931729D01*
G03X477077Y931488I1278J-244D01*
G03X477100Y931247I1301J3D01*
G01X477103Y931229D01*
Y927637D01*
X477093Y927607D01*
G03X477064Y927504I1286J-418D01*
G01X477051Y927449D01*
X475198Y925596D01*
X453235D01*
X452281Y926550D01*
Y936886D01*
X452565Y937170D01*
X455051D01*
X460920Y943039D01*
X461835D01*
X461862Y943031D01*
G03X462115Y942996I247J855D01*
G01X463293D01*
G03X463546Y943031I6J890D01*
G01X463573Y943039D01*
G37*
G36*
G01X473650Y967950D02*
X476883D01*
X477163Y967670D01*
Y966233D01*
X477145Y966193D01*
G03X477027Y965640I1234J-552D01*
G03X477145Y965087I1352J-1D01*
G01X477163Y965047D01*
Y963996D01*
X477152Y963964D01*
G03X477077Y963530I1226J-435D01*
G03X477152Y963096I1301J1D01*
G01X477163Y963064D01*
Y959825D01*
X477145Y959785D01*
G03X477027Y959232I1234J-552D01*
G03X477145Y958679I1352J-1D01*
G01X477163Y958639D01*
Y957588D01*
X477152Y957556D01*
G03X477077Y957122I1226J-435D01*
G03X477152Y956688I1301J1D01*
G01X477163Y956656D01*
Y953416D01*
X477145Y953376D01*
G03X477027Y952823I1234J-552D01*
G03X477145Y952270I1352J-1D01*
G01X477163Y952230D01*
Y951179D01*
X477152Y951147D01*
G03X477077Y950713I1226J-435D01*
G03X477152Y950279I1301J1D01*
G01X477163Y950247D01*
Y949177D01*
X478870Y947470D01*
Y946003D01*
G02X478448Y945604I-400J0D01*
G03X478378Y945606I-72J-1300D01*
G03X477090Y944491I0J-1301D01*
G01X477065Y944320D01*
X475328D01*
X473019Y946629D01*
X454026D01*
X453665Y946990D01*
Y951980D01*
X453759Y952074D01*
X471724D01*
X472016Y952366D01*
X472907Y953258D01*
Y960648D01*
X472185Y961370D01*
X454909D01*
X453685Y962594D01*
Y966530D01*
X453895Y966740D01*
X472440D01*
X473650Y967950D01*
G37*
G36*
G01X465645Y945920D02*
X472445D01*
X474995Y943370D01*
Y941300D01*
X474765Y941070D01*
X468590D01*
X468375Y941285D01*
Y942470D01*
X468176Y942670D01*
Y942770D01*
X467405Y943540D01*
X465534D01*
X465525Y943550D01*
Y945800D01*
X465645Y945920D01*
G37*
G36*
G01X472820Y1024575D02*
X476615D01*
X476870Y1024320D01*
Y976329D01*
X476342Y975801D01*
X472139D01*
X472120Y975782D01*
X456083D01*
X453535Y978330D01*
Y981660D01*
X453796Y981921D01*
X456916D01*
X457747Y981090D01*
X471902D01*
X472903Y982092D01*
Y989360D01*
X471919Y990344D01*
X454878D01*
X453685Y991537D01*
Y995620D01*
X453885Y995820D01*
X455537D01*
X455871Y995486D01*
X472245D01*
X473075Y996316D01*
Y1003836D01*
X472305Y1004606D01*
X454099D01*
X453645Y1005060D01*
Y1009808D01*
X453704Y1009867D01*
Y1009869D01*
X453795Y1009960D01*
X471835D01*
X472755Y1010880D01*
Y1018245D01*
X471982Y1019018D01*
X454151D01*
X453525Y1019644D01*
Y1023784D01*
X454315Y1024574D01*
X472819D01*
X472820Y1024575D01*
G37*
G36*
G01X467575Y1025570D02*
X457375D01*
X456575Y1026370D01*
Y1029270D01*
X457175Y1029870D01*
X458825D01*
X459845Y1030890D01*
X467545D01*
X467775Y1030660D01*
Y1025770D01*
X467575Y1025570D01*
G37*
G36*
G01X473520Y299462D02*
G03I-720J0D01*
G37*
G36*
G01X485520Y307362D02*
G03I-720J0D01*
G37*
G36*
G01X477460Y309272D02*
G03I-720J0D01*
G37*
G36*
G01X480460Y300202D02*
G03I-720J0D01*
G37*
G36*
G01X474590Y506622D02*
G03I-720J0D01*
G37*
G36*
G01X474940Y572782D02*
G03I-720J0D01*
G37*
G36*
G01X472660Y597532D02*
G03I-720J0D01*
G37*
G36*
G01X469290Y974755D02*
X476891D01*
X477181Y974465D01*
Y972677D01*
X477161Y972636D01*
G03X477027Y972049I1219J-587D01*
G03X477155Y971475I1351J0D01*
G01X477174Y971434D01*
Y970431D01*
X477161Y970397D01*
G03X477078Y969939I1218J-457D01*
G03X477161Y969481I1301J-1D01*
G01X477174Y969447D01*
Y968739D01*
X476995Y968560D01*
X472728D01*
X471733Y967565D01*
X469785D01*
X469783Y967568D01*
X468977D01*
X468617Y967928D01*
Y970122D01*
X468045Y970694D01*
Y971688D01*
X469091Y972734D01*
Y974556D01*
X469290Y974755D01*
G37*
G36*
G01X477068Y1025463D02*
X469107D01*
X468361Y1026209D01*
Y1033266D01*
X468785Y1033690D01*
X476785D01*
X477353Y1033122D01*
Y1025748D01*
X477068Y1025463D01*
G37*
G36*
G01X486511Y1284608D02*
X469419D01*
X468719Y1283908D01*
Y1278908D01*
X469719Y1277908D01*
X495468D01*
X500668Y1283108D01*
X518719D01*
X519653Y1284042D01*
Y1289165D01*
X518909Y1289908D01*
X491811D01*
X486511Y1284608D01*
G37*
G36*
G01X485188Y1419096D02*
X485476Y1418808D01*
X486916Y1417368D01*
Y1417071D01*
X487643Y1416344D01*
X488121D01*
X491026D01*
X491157Y1416213D01*
Y1415808D01*
X491151Y1415802D01*
Y1415677D01*
X491032Y1415558D01*
X490907D01*
X486907D01*
X486157Y1416308D01*
X485657D01*
X484016Y1417948D01*
Y1418416D01*
X484696Y1419096D01*
X485188D01*
G37*
G36*
G01X476663Y1443163D02*
X476908Y1443408D01*
X515728D01*
X516682Y1444362D01*
X535750D01*
X536637Y1443475D01*
Y1438628D01*
X529496Y1431487D01*
X509190D01*
X503164Y1437513D01*
X476805D01*
X476663Y1437655D01*
Y1443163D01*
G37*
G36*
G01X476895Y1457697D02*
X478936Y1459738D01*
X532498D01*
X532557Y1459679D01*
X534209Y1458027D01*
X534268Y1457968D01*
Y1448075D01*
X534262Y1448069D01*
Y1446260D01*
X534203Y1446201D01*
X533646Y1445644D01*
X533587Y1445585D01*
X515880D01*
G03X515738Y1445526I0J-200D01*
G01X515099Y1444887D01*
X515040Y1444828D01*
X477328D01*
X477269Y1444887D01*
X476895Y1445261D01*
X476836Y1445320D01*
Y1457638D01*
X476895Y1457697D01*
G37*
G36*
G01X485053Y1575686D02*
G03I-720J0D01*
G37*
G36*
G01Y1580678D02*
G03I-720J0D01*
G37*
G36*
G01X477949D02*
G03I-720J0D01*
G37*
G36*
G01X472993D02*
G03I-720J0D01*
G37*
G36*
G01Y1575686D02*
G03I-720J0D01*
G37*
G36*
G01X477949D02*
G03I-720J0D01*
G37*
G36*
G01X483249Y1599884D02*
G03I-720J0D01*
G37*
G36*
G01X478293D02*
G03I-720J0D01*
G37*
G36*
G01X485053Y1587598D02*
G03I-720J0D01*
G37*
G36*
G01Y1592590D02*
G03I-720J0D01*
G37*
G36*
G01X472993D02*
G03I-720J0D01*
G37*
G36*
G01X477949D02*
G03I-720J0D01*
G37*
G36*
G01Y1587598D02*
G03I-720J0D01*
G37*
G36*
G01X472993D02*
G03I-720J0D01*
G37*
G36*
G01X483249Y1616788D02*
G03I-720J0D01*
G37*
G36*
G01X478293D02*
G03I-720J0D01*
G37*
G36*
G01Y1611796D02*
G03I-720J0D01*
G37*
G36*
G01X483249D02*
G03I-720J0D01*
G37*
G36*
G01X478293Y1604876D02*
G03I-720J0D01*
G37*
G36*
G01X483249D02*
G03I-720J0D01*
G37*
G36*
G01X887008Y142878D02*
X1011024D01*
G02X1022898Y131004I0J-11874D01*
G03X1022904Y127139I1291667J73D01*
G02Y127067I-11881J-36D01*
G01Y109413D01*
X1022853Y109303D01*
X1022831Y109280D01*
G03X1021644Y107932I23037J-21482D01*
G01X1021616Y107898D01*
X1021462Y107826D01*
G02X1021397Y107837I0J200D01*
G01X1021040Y107965D01*
G02X1020908Y108153I68J188D01*
G01Y127067D01*
G02X1020898Y131004I774993J3937D01*
G03X1011024Y140878I-9874J0D01*
G01X887008D01*
G03X877134Y131004I0J-9874D01*
G03X877124Y127067I774993J-3937D01*
G01Y54252D01*
G02X871260Y48388I-5864J0D01*
G01X774417D01*
G03X764533Y38504I0J-9884D01*
G01Y26050D01*
X764542D01*
Y24724D01*
G02X762606Y22788I-1936J0D01*
G01X500402D01*
G02X498466Y24724I0J1936D01*
G01Y26050D01*
X498475D01*
Y30482D01*
G02X498723Y30676I200J0D01*
G01X498768Y30665D01*
X498789Y30654D01*
G03X499473Y30489I685J1339D01*
G01X499475D01*
G03X499978Y30576I-1J1503D01*
G02X500163Y30549I67J-189D01*
G03X500346Y30401I2355J2725D01*
G03X500371Y30382I2192J2858D01*
G01X500391Y30367D01*
X500472Y30208D01*
Y27156D01*
X500465Y27149D01*
Y24787D01*
X762536D01*
Y30209D01*
X762617Y30367D01*
X762648Y30391D01*
G03Y36143I-2169J2876D01*
G01X762617Y36167D01*
X762536Y36325D01*
Y38504D01*
G02X762876Y41326I11881J0D01*
G02X762925Y41407I191J-60D01*
G01X764150Y42632D01*
G03X764576Y43660I-1030J1029D01*
G01Y45100D01*
G02X764601Y45196I200J-1D01*
G02X774417Y50384I9816J-6692D01*
G01X871260D01*
G03X875128Y54252I0J3868D01*
G01Y127067D01*
X875134Y131004D01*
G02X887008Y142878I11874J0D01*
G37*
G36*
G01X497520Y113692D02*
X514690D01*
X515980Y112402D01*
Y104988D01*
X515957Y104945D01*
G03X515788Y104252I1333J-692D01*
G03X515957Y103559I1502J-1D01*
G01X515980Y103516D01*
Y94436D01*
X515834Y94395D01*
G03X515129Y93963I402J-1447D01*
G02X514572Y93932I-294J271D01*
G03X513586Y94301I-986J-1133D01*
G03X512402Y93723I0J-1502D01*
G02X511774Y93719I-316J246D01*
G03X510600Y94284I-1174J-937D01*
G03X509825Y94068I1J-1502D01*
G02X509522Y94240I-103J171D01*
G01Y94558D01*
X509616Y94617D01*
G03X509852Y95042I-265J425D01*
G01Y97107D01*
X510328Y97584D01*
Y102962D01*
X510718Y103352D01*
X512328D01*
X513402Y104426D01*
Y106765D01*
X512074Y108094D01*
X508455D01*
X506525Y110024D01*
X503405D01*
X501888Y108507D01*
Y107053D01*
G02X501499Y106653I-400J0D01*
G03Y103651I41J-1501D01*
G02X501888Y103251I-11J-400D01*
G01Y95575D01*
X501145Y94832D01*
X501070D01*
Y94757D01*
X500926Y94613D01*
Y92447D01*
X501725Y91648D01*
X504093D01*
X505035Y92590D01*
X507845D01*
X508418Y93163D01*
G02X509100Y92860I283J-283D01*
G03X509098Y92782I1500J-77D01*
G03X510600Y91280I1502J0D01*
G03X511922Y92068I0J1503D01*
G02X512273Y92070I176J-95D01*
G03X512330Y91976I1312J731D01*
G01Y89722D01*
X510520Y87912D01*
X504796D01*
G03X503875Y88174I-922J-1490D01*
G03X502954Y87912I1J-1752D01*
G01X499140D01*
X498436Y88616D01*
X498421Y88659D01*
G03X497494Y89586I-1419J-492D01*
G01X497451Y89601D01*
X497070Y89982D01*
Y113242D01*
X497520Y113692D01*
G37*
G36*
G01X490700Y250512D02*
G03I-720J0D01*
G37*
G36*
G01X492794Y300306D02*
G03I-720J0D01*
G37*
G36*
G01X491401Y1420815D02*
X490969Y1420383D01*
X489892D01*
X488966Y1421309D01*
Y1424535D01*
Y1424752D01*
X489441Y1425227D01*
X489445Y1425223D01*
X491169D01*
X491401Y1424991D01*
Y1420815D01*
G37*
G36*
G01X499037Y1417225D02*
X506707D01*
X507067Y1417585D01*
Y1421555D01*
X507213Y1421701D01*
Y1423855D01*
Y1426243D01*
X506662Y1426794D01*
X505327D01*
X504803Y1426269D01*
Y1420185D01*
X504429Y1419811D01*
X503854Y1419236D01*
X499061D01*
X498839Y1419014D01*
Y1417423D01*
X499037Y1417225D01*
G37*
G36*
G01X490888Y1417348D02*
X488383D01*
X487513Y1418218D01*
X486649Y1419082D01*
X485261Y1420470D01*
X484717Y1421014D01*
Y1422785D01*
X484889Y1422957D01*
X487209D01*
X487321Y1422845D01*
Y1422710D01*
Y1421267D01*
X487323Y1421265D01*
X489550Y1419038D01*
X490816D01*
X491078D01*
X491318Y1418798D01*
Y1417457D01*
X491209Y1417348D01*
X490888D01*
G37*
G36*
G01X497541Y1419159D02*
Y1416548D01*
X496805Y1415812D01*
Y1412543D01*
X496697Y1412435D01*
X495621D01*
X495541Y1412515D01*
Y1418373D01*
X495537Y1418377D01*
Y1420454D01*
Y1420948D01*
Y1424769D01*
Y1425696D01*
X494711Y1426522D01*
X489357D01*
X489350Y1426515D01*
X488864D01*
X487657Y1425308D01*
Y1424508D01*
X487257Y1424108D01*
X487119Y1423970D01*
X485203D01*
X484819Y1424353D01*
Y1436009D01*
X485301Y1436491D01*
X501487D01*
X501650Y1436328D01*
Y1424368D01*
Y1423450D01*
X500840Y1422640D01*
X499922D01*
X497541Y1420259D01*
Y1419701D01*
Y1419159D01*
G37*
G36*
G01X497113Y1580678D02*
G03I-720J0D01*
G37*
G36*
G01Y1575686D02*
G03I-720J0D01*
G37*
G36*
G01X490009D02*
G03I-720J0D01*
G37*
G36*
G01Y1580678D02*
G03I-720J0D01*
G37*
G36*
G01X495309Y1599884D02*
G03I-720J0D01*
G37*
G36*
G01X490353D02*
G03I-720J0D01*
G37*
G36*
G01X497113Y1592590D02*
G03I-720J0D01*
G37*
G36*
G01Y1587598D02*
G03I-720J0D01*
G37*
G36*
G01X490009D02*
G03I-720J0D01*
G37*
G36*
G01Y1592590D02*
G03I-720J0D01*
G37*
G36*
G01X490353Y1611796D02*
G03I-720J0D01*
G37*
G36*
G01X495309Y1604876D02*
G03I-720J0D01*
G37*
G36*
G01X490353D02*
G03I-720J0D01*
G37*
G36*
G01X495309Y1611796D02*
G03I-720J0D01*
G37*
G36*
G01X490353Y1616788D02*
G03I-720J0D01*
G37*
G36*
G01X495309D02*
G03I-720J0D01*
G37*
G36*
G01X503820Y109022D02*
X506110D01*
X508040Y107092D01*
X511659D01*
X512401Y106350D01*
Y104841D01*
X511913Y104353D01*
X510303D01*
X509327Y103377D01*
Y97999D01*
X508520Y97192D01*
Y94682D01*
X507430Y93592D01*
X504620D01*
X503678Y92650D01*
X502140D01*
X501928Y92862D01*
Y94198D01*
X502890Y95160D01*
Y104773D01*
X502896Y104798D01*
G03X502942Y105152I-1356J356D01*
G03X502896Y105506I-1402J-2D01*
G01X502890Y105531D01*
Y108092D01*
X503820Y109022D01*
G37*
G36*
G01X515187Y294373D02*
X521329D01*
X523723Y291979D01*
X526881D01*
X526960Y291900D01*
X532689D01*
X533745Y290844D01*
Y286955D01*
X532798Y286008D01*
X529595D01*
X528670Y285083D01*
Y276882D01*
X526490Y274702D01*
X517934D01*
X516872Y275764D01*
Y283767D01*
X514762Y285877D01*
Y293948D01*
X515187Y294373D01*
G37*
G36*
G01X506620Y311562D02*
G03I-720J0D01*
G37*
G36*
G01X515520Y308266D02*
X524761D01*
Y304241D01*
X523813Y303293D01*
X516428D01*
X515350Y304371D01*
Y308096D01*
X515520Y308266D01*
G37*
G36*
G01X511460Y332592D02*
G03I-720J0D01*
G37*
G36*
G01X553219Y1306408D02*
Y1311408D01*
X551719Y1312908D01*
X525719D01*
X523719Y1310908D01*
Y1301908D01*
X519625Y1297814D01*
X502066D01*
X501724Y1297472D01*
Y1292766D01*
Y1291719D01*
X502535Y1290908D01*
X523831D01*
X528219Y1295296D01*
Y1298979D01*
X535148Y1305908D01*
X552719D01*
X553219Y1306408D01*
G37*
G36*
G01X502069Y1580678D02*
G03I-720J0D01*
G37*
G36*
G01Y1575686D02*
G03I-720J0D01*
G37*
G36*
G01X509173D02*
G03I-720J0D01*
G37*
G36*
G01X514129D02*
G03I-720J0D01*
G37*
G36*
G01X509173Y1580678D02*
G03I-720J0D01*
G37*
G36*
G01X514129D02*
G03I-720J0D01*
G37*
G36*
G01X502413Y1599884D02*
G03I-720J0D01*
G37*
G36*
G01X502069Y1592590D02*
G03I-720J0D01*
G37*
G36*
G01Y1587598D02*
G03I-720J0D01*
G37*
G36*
G01X514473Y1599884D02*
G03I-720J0D01*
G37*
G36*
G01X507369D02*
G03I-720J0D01*
G37*
G36*
G01X509173Y1587598D02*
G03I-720J0D01*
G37*
G36*
G01X514129D02*
G03I-720J0D01*
G37*
G36*
G01X509173Y1592590D02*
G03I-720J0D01*
G37*
G36*
G01X514129D02*
G03I-720J0D01*
G37*
G36*
G01X502413Y1611796D02*
G03I-720J0D01*
G37*
G36*
G01Y1604876D02*
G03I-720J0D01*
G37*
G36*
G01Y1616788D02*
G03I-720J0D01*
G37*
G36*
G01X514473D02*
G03I-720J0D01*
G37*
G36*
G01Y1604876D02*
G03I-720J0D01*
G37*
G36*
G01Y1611796D02*
G03I-720J0D01*
G37*
G36*
G01X507369D02*
G03I-720J0D01*
G37*
G36*
G01Y1604876D02*
G03I-720J0D01*
G37*
G36*
G01Y1616788D02*
G03I-720J0D01*
G37*
G36*
G01X529959Y99997D02*
G03I-720J0D01*
G37*
G36*
G01Y92911D02*
G03I-720J0D01*
G37*
G36*
G01X524836Y302883D02*
X536690D01*
X537250Y302323D01*
Y296989D01*
X536562Y293529D01*
X536187Y293154D01*
X525284D01*
X524613Y293825D01*
Y302660D01*
X524836Y302883D01*
G37*
G36*
G01X524380Y323222D02*
G03I-720J0D01*
G37*
G36*
G01X522281Y550819D02*
G03I-720J0D01*
G37*
G36*
G01X527000Y569122D02*
G03I-720J0D01*
G37*
G36*
G01X521430Y592552D02*
G03I-720J0D01*
G37*
G36*
G01X533293Y1575686D02*
G03I-720J0D01*
G37*
G36*
G01Y1580678D02*
G03I-720J0D01*
G37*
G36*
G01X521233D02*
G03I-720J0D01*
G37*
G36*
G01X526189D02*
G03I-720J0D01*
G37*
G36*
G01X521233Y1575686D02*
G03I-720J0D01*
G37*
G36*
G01X526189D02*
G03I-720J0D01*
G37*
G36*
G01X526533Y1599884D02*
G03I-720J0D01*
G37*
G36*
G01X531489D02*
G03I-720J0D01*
G37*
G36*
G01X519429D02*
G03I-720J0D01*
G37*
G36*
G01X533293Y1587598D02*
G03I-720J0D01*
G37*
G36*
G01Y1592590D02*
G03I-720J0D01*
G37*
G36*
G01X526189D02*
G03I-720J0D01*
G37*
G36*
G01X521233D02*
G03I-720J0D01*
G37*
G36*
G01Y1587598D02*
G03I-720J0D01*
G37*
G36*
G01X526189D02*
G03I-720J0D01*
G37*
G36*
G01X526533Y1611796D02*
G03I-720J0D01*
G37*
G36*
G01X531489D02*
G03I-720J0D01*
G37*
G36*
G01X526533Y1604876D02*
G03I-720J0D01*
G37*
G36*
G01X531489D02*
G03I-720J0D01*
G37*
G36*
G01Y1616788D02*
G03I-720J0D01*
G37*
G36*
G01X526533D02*
G03I-720J0D01*
G37*
G36*
G01X519429D02*
G03I-720J0D01*
G37*
G36*
G01Y1604876D02*
G03I-720J0D01*
G37*
G36*
G01Y1611796D02*
G03I-720J0D01*
G37*
G36*
G01X546954Y77443D02*
G03I-720J0D01*
G37*
G36*
G01X543518Y202646D02*
G03I-720J0D01*
G37*
G36*
G01X536350Y306602D02*
G03I-720J0D01*
G37*
G36*
G01X536010Y572932D02*
G03I-720J0D01*
G37*
G36*
G01X544170Y590262D02*
G03I-720J0D01*
G37*
G36*
G01X547944Y1108854D02*
X548344Y1108711D01*
Y1107961D01*
X547944Y1107819D01*
X547744D01*
Y1108854D01*
X547944D01*
G37*
G36*
G01X547544Y1108994D02*
X547144Y1109137D01*
Y1109887D01*
X547544Y1110029D01*
X547744D01*
Y1108994D01*
X547544D01*
G37*
G36*
G01Y1111344D02*
X547144Y1111487D01*
Y1112237D01*
X547544Y1112379D01*
X547744D01*
Y1111344D01*
X547544D01*
G37*
G36*
G01X547944Y1111204D02*
X548344Y1111061D01*
Y1110311D01*
X547944Y1110169D01*
X547744D01*
Y1111204D01*
X547944D01*
G37*
G36*
G01X549144Y1108854D02*
X549544Y1108711D01*
Y1107961D01*
X549144Y1107819D01*
X548944D01*
Y1108854D01*
X549144D01*
G37*
G36*
G01X548744Y1108994D02*
X548344Y1109137D01*
Y1109887D01*
X548744Y1110029D01*
X548944D01*
Y1108994D01*
X548744D01*
G37*
G36*
G01X549144Y1111204D02*
X549544Y1111061D01*
Y1110311D01*
X549144Y1110169D01*
X548944D01*
Y1111204D01*
X549144D01*
G37*
G36*
G01X548744Y1111344D02*
X548344Y1111487D01*
Y1112237D01*
X548744Y1112379D01*
X548944D01*
Y1111344D01*
X548744D01*
G37*
G36*
G01X547544Y1116044D02*
X547144Y1116187D01*
Y1116937D01*
X547544Y1117079D01*
X547744D01*
Y1116044D01*
X547544D01*
G37*
G36*
G01Y1113694D02*
X547144Y1113837D01*
Y1114587D01*
X547544Y1114729D01*
X547744D01*
Y1113694D01*
X547544D01*
G37*
G36*
G01X547944Y1118254D02*
X548344Y1118111D01*
Y1117361D01*
X547944Y1117219D01*
X547744D01*
Y1118254D01*
X547944D01*
G37*
G36*
G01Y1115904D02*
X548344Y1115761D01*
Y1115011D01*
X547944Y1114869D01*
X547744D01*
Y1115904D01*
X547944D01*
G37*
G36*
G01Y1113554D02*
X548344Y1113411D01*
Y1112661D01*
X547944Y1112519D01*
X547744D01*
Y1113554D01*
X547944D01*
G37*
G36*
G01X547544Y1123094D02*
X547144Y1123237D01*
Y1123987D01*
X547544Y1124129D01*
X547744D01*
Y1123094D01*
X547544D01*
G37*
G36*
G01Y1120744D02*
X547144Y1120887D01*
Y1121637D01*
X547544Y1121779D01*
X547744D01*
Y1120744D01*
X547544D01*
G37*
G36*
G01Y1125444D02*
X547144Y1125587D01*
Y1126337D01*
X547544Y1126479D01*
X547744D01*
Y1125444D01*
X547544D01*
G37*
G36*
G01Y1127794D02*
X547144Y1127937D01*
Y1128687D01*
X547544Y1128829D01*
X547744D01*
Y1127794D01*
X547544D01*
G37*
G36*
G01X547944Y1125304D02*
X548344Y1125161D01*
Y1124411D01*
X547944Y1124269D01*
X547744D01*
Y1125304D01*
X547944D01*
G37*
G36*
G01Y1122954D02*
X548344Y1122811D01*
Y1122061D01*
X547944Y1121919D01*
X547744D01*
Y1122954D01*
X547944D01*
G37*
G36*
G01Y1120604D02*
X548344Y1120461D01*
Y1119711D01*
X547944Y1119569D01*
X547744D01*
Y1120604D01*
X547944D01*
G37*
G36*
G01Y1127654D02*
X548344Y1127511D01*
Y1126761D01*
X547944Y1126619D01*
X547744D01*
Y1127654D01*
X547944D01*
G37*
G36*
G01X547544Y1118394D02*
X547144Y1118537D01*
Y1119287D01*
X547544Y1119429D01*
X547744D01*
Y1118394D01*
X547544D01*
G37*
G36*
G01X548744Y1116044D02*
X548344Y1116187D01*
Y1116937D01*
X548744Y1117079D01*
X548944D01*
Y1116044D01*
X548744D01*
G37*
G36*
G01Y1113694D02*
X548344Y1113837D01*
Y1114587D01*
X548744Y1114729D01*
X548944D01*
Y1113694D01*
X548744D01*
G37*
G36*
G01X549144Y1118254D02*
X549544Y1118111D01*
Y1117361D01*
X549144Y1117219D01*
X548944D01*
Y1118254D01*
X549144D01*
G37*
G36*
G01Y1115904D02*
X549544Y1115761D01*
Y1115011D01*
X549144Y1114869D01*
X548944D01*
Y1115904D01*
X549144D01*
G37*
G36*
G01Y1113554D02*
X549544Y1113411D01*
Y1112661D01*
X549144Y1112519D01*
X548944D01*
Y1113554D01*
X549144D01*
G37*
G36*
G01X548744Y1118394D02*
X548344Y1118537D01*
Y1119287D01*
X548744Y1119429D01*
X548944D01*
Y1118394D01*
X548744D01*
G37*
G36*
G01Y1123094D02*
X548344Y1123237D01*
Y1123987D01*
X548744Y1124129D01*
X548944D01*
Y1123094D01*
X548744D01*
G37*
G36*
G01Y1120744D02*
X548344Y1120887D01*
Y1121637D01*
X548744Y1121779D01*
X548944D01*
Y1120744D01*
X548744D01*
G37*
G36*
G01X549144Y1125304D02*
X549544Y1125161D01*
Y1124411D01*
X549144Y1124269D01*
X548944D01*
Y1125304D01*
X549144D01*
G37*
G36*
G01Y1122954D02*
X549544Y1122811D01*
Y1122061D01*
X549144Y1121919D01*
X548944D01*
Y1122954D01*
X549144D01*
G37*
G36*
G01Y1120604D02*
X549544Y1120461D01*
Y1119711D01*
X549144Y1119569D01*
X548944D01*
Y1120604D01*
X549144D01*
G37*
G36*
G01X548744Y1125444D02*
X548344Y1125587D01*
Y1126337D01*
X548744Y1126479D01*
X548944D01*
Y1125444D01*
X548744D01*
G37*
G36*
G01Y1127794D02*
X548344Y1127937D01*
Y1128687D01*
X548744Y1128829D01*
X548944D01*
Y1127794D01*
X548744D01*
G37*
G36*
G01X549144Y1127654D02*
X549544Y1127511D01*
Y1126761D01*
X549144Y1126619D01*
X548944D01*
Y1127654D01*
X549144D01*
G37*
G36*
G01X547544Y1130144D02*
X547144Y1130287D01*
Y1131037D01*
X547544Y1131179D01*
X547744D01*
Y1130144D01*
X547544D01*
G37*
G36*
G01Y1132494D02*
X547144Y1132637D01*
Y1133387D01*
X547544Y1133529D01*
X547744D01*
Y1132494D01*
X547544D01*
G37*
G36*
G01X547944Y1134704D02*
X548344Y1134561D01*
Y1133811D01*
X547944Y1133669D01*
X547744D01*
Y1134704D01*
X547944D01*
G37*
G36*
G01Y1132354D02*
X548344Y1132211D01*
Y1131461D01*
X547944Y1131319D01*
X547744D01*
Y1132354D01*
X547944D01*
G37*
G36*
G01Y1130004D02*
X548344Y1129861D01*
Y1129111D01*
X547944Y1128969D01*
X547744D01*
Y1130004D01*
X547944D01*
G37*
G36*
G01Y1137054D02*
X548344Y1136911D01*
Y1136161D01*
X547944Y1136019D01*
X547744D01*
Y1137054D01*
X547944D01*
G37*
G36*
G01X547544Y1139544D02*
X547144Y1139687D01*
Y1140437D01*
X547544Y1140579D01*
X547744D01*
Y1139544D01*
X547544D01*
G37*
G36*
G01Y1141894D02*
X547144Y1142037D01*
Y1142787D01*
X547544Y1142929D01*
X547744D01*
Y1141894D01*
X547544D01*
G37*
G36*
G01Y1144244D02*
X547144Y1144387D01*
Y1145137D01*
X547544Y1145279D01*
X547744D01*
Y1144244D01*
X547544D01*
G37*
G36*
G01X547944Y1141754D02*
X548344Y1141611D01*
Y1140861D01*
X547944Y1140719D01*
X547744D01*
Y1141754D01*
X547944D01*
G37*
G36*
G01Y1144104D02*
X548344Y1143961D01*
Y1143211D01*
X547944Y1143069D01*
X547744D01*
Y1144104D01*
X547944D01*
G37*
G36*
G01X547544Y1137194D02*
X547144Y1137337D01*
Y1138087D01*
X547544Y1138229D01*
X547744D01*
Y1137194D01*
X547544D01*
G37*
G36*
G01X547944Y1139404D02*
X548344Y1139261D01*
Y1138511D01*
X547944Y1138369D01*
X547744D01*
Y1139404D01*
X547944D01*
G37*
G36*
G01X547544Y1134844D02*
X547144Y1134987D01*
Y1135737D01*
X547544Y1135879D01*
X547744D01*
Y1134844D01*
X547544D01*
G37*
G36*
G01X548744Y1130144D02*
X548344Y1130287D01*
Y1131037D01*
X548744Y1131179D01*
X548944D01*
Y1130144D01*
X548744D01*
G37*
G36*
G01Y1132494D02*
X548344Y1132637D01*
Y1133387D01*
X548744Y1133529D01*
X548944D01*
Y1132494D01*
X548744D01*
G37*
G36*
G01X549144Y1134704D02*
X549544Y1134561D01*
Y1133811D01*
X549144Y1133669D01*
X548944D01*
Y1134704D01*
X549144D01*
G37*
G36*
G01Y1132354D02*
X549544Y1132211D01*
Y1131461D01*
X549144Y1131319D01*
X548944D01*
Y1132354D01*
X549144D01*
G37*
G36*
G01Y1130004D02*
X549544Y1129861D01*
Y1129111D01*
X549144Y1128969D01*
X548944D01*
Y1130004D01*
X549144D01*
G37*
G36*
G01X548744Y1144244D02*
X548344Y1144387D01*
Y1145137D01*
X548744Y1145279D01*
X548944D01*
Y1144244D01*
X548744D01*
G37*
G36*
G01Y1139544D02*
X548344Y1139687D01*
Y1140437D01*
X548744Y1140579D01*
X548944D01*
Y1139544D01*
X548744D01*
G37*
G36*
G01Y1141894D02*
X548344Y1142037D01*
Y1142787D01*
X548744Y1142929D01*
X548944D01*
Y1141894D01*
X548744D01*
G37*
G36*
G01X549144Y1141754D02*
X549544Y1141611D01*
Y1140861D01*
X549144Y1140719D01*
X548944D01*
Y1141754D01*
X549144D01*
G37*
G36*
G01Y1144104D02*
X549544Y1143961D01*
Y1143211D01*
X549144Y1143069D01*
X548944D01*
Y1144104D01*
X549144D01*
G37*
G36*
G01X548744Y1137194D02*
X548344Y1137337D01*
Y1138087D01*
X548744Y1138229D01*
X548944D01*
Y1137194D01*
X548744D01*
G37*
G36*
G01X549144Y1139404D02*
X549544Y1139261D01*
Y1138511D01*
X549144Y1138369D01*
X548944D01*
Y1139404D01*
X549144D01*
G37*
G36*
G01Y1137054D02*
X549544Y1136911D01*
Y1136161D01*
X549144Y1136019D01*
X548944D01*
Y1137054D01*
X549144D01*
G37*
G36*
G01X548744Y1134844D02*
X548344Y1134987D01*
Y1135737D01*
X548744Y1135879D01*
X548944D01*
Y1134844D01*
X548744D01*
G37*
G36*
G01X547944Y1151154D02*
X548344Y1151011D01*
Y1150261D01*
X547944Y1150119D01*
X547744D01*
Y1151154D01*
X547944D01*
G37*
G36*
G01X547544Y1148944D02*
X547144Y1149087D01*
Y1149837D01*
X547544Y1149979D01*
X547744D01*
Y1148944D01*
X547544D01*
G37*
G36*
G01Y1151294D02*
X547144Y1151437D01*
Y1152187D01*
X547544Y1152329D01*
X547744D01*
Y1151294D01*
X547544D01*
G37*
G36*
G01Y1146594D02*
X547144Y1146737D01*
Y1147487D01*
X547544Y1147629D01*
X547744D01*
Y1146594D01*
X547544D01*
G37*
G36*
G01X547944Y1146454D02*
X548344Y1146311D01*
Y1145561D01*
X547944Y1145419D01*
X547744D01*
Y1146454D01*
X547944D01*
G37*
G36*
G01Y1148804D02*
X548344Y1148661D01*
Y1147911D01*
X547944Y1147769D01*
X547744D01*
Y1148804D01*
X547944D01*
G37*
G36*
G01X547544Y1153644D02*
X547144Y1153787D01*
Y1154537D01*
X547544Y1154679D01*
X547744D01*
Y1153644D01*
X547544D01*
G37*
G36*
G01X547944Y1153504D02*
X548344Y1153361D01*
Y1152611D01*
X547944Y1152469D01*
X547744D01*
Y1153504D01*
X547944D01*
G37*
G36*
G01X547544Y1155994D02*
X547144Y1156137D01*
Y1156887D01*
X547544Y1157029D01*
X547744D01*
Y1155994D01*
X547544D01*
G37*
G36*
G01X547944Y1155854D02*
X548344Y1155711D01*
Y1154961D01*
X547944Y1154819D01*
X547744D01*
Y1155854D01*
X547944D01*
G37*
G36*
G01X547544Y1158344D02*
X547144Y1158487D01*
Y1159237D01*
X547544Y1159379D01*
X547744D01*
Y1158344D01*
X547544D01*
G37*
G36*
G01X547944Y1158204D02*
X548344Y1158061D01*
Y1157311D01*
X547944Y1157169D01*
X547744D01*
Y1158204D01*
X547944D01*
G37*
G36*
G01X547544Y1160694D02*
X547144Y1160837D01*
Y1161587D01*
X547544Y1161729D01*
X547744D01*
Y1160694D01*
X547544D01*
G37*
G36*
G01X547944Y1160554D02*
X548344Y1160411D01*
Y1159661D01*
X547944Y1159519D01*
X547744D01*
Y1160554D01*
X547944D01*
G37*
G36*
G01X549144Y1151154D02*
X549544Y1151011D01*
Y1150261D01*
X549144Y1150119D01*
X548944D01*
Y1151154D01*
X549144D01*
G37*
G36*
G01X548744Y1148944D02*
X548344Y1149087D01*
Y1149837D01*
X548744Y1149979D01*
X548944D01*
Y1148944D01*
X548744D01*
G37*
G36*
G01Y1151294D02*
X548344Y1151437D01*
Y1152187D01*
X548744Y1152329D01*
X548944D01*
Y1151294D01*
X548744D01*
G37*
G36*
G01Y1146594D02*
X548344Y1146737D01*
Y1147487D01*
X548744Y1147629D01*
X548944D01*
Y1146594D01*
X548744D01*
G37*
G36*
G01X549144Y1146454D02*
X549544Y1146311D01*
Y1145561D01*
X549144Y1145419D01*
X548944D01*
Y1146454D01*
X549144D01*
G37*
G36*
G01Y1148804D02*
X549544Y1148661D01*
Y1147911D01*
X549144Y1147769D01*
X548944D01*
Y1148804D01*
X549144D01*
G37*
G36*
G01X548744Y1153644D02*
X548344Y1153787D01*
Y1154537D01*
X548744Y1154679D01*
X548944D01*
Y1153644D01*
X548744D01*
G37*
G36*
G01X549144Y1153504D02*
X549544Y1153361D01*
Y1152611D01*
X549144Y1152469D01*
X548944D01*
Y1153504D01*
X549144D01*
G37*
G36*
G01X548744Y1155994D02*
X548344Y1156137D01*
Y1156887D01*
X548744Y1157029D01*
X548944D01*
Y1155994D01*
X548744D01*
G37*
G36*
G01X549144Y1155854D02*
X549544Y1155711D01*
Y1154961D01*
X549144Y1154819D01*
X548944D01*
Y1155854D01*
X549144D01*
G37*
G36*
G01X548744Y1158344D02*
X548344Y1158487D01*
Y1159237D01*
X548744Y1159379D01*
X548944D01*
Y1158344D01*
X548744D01*
G37*
G36*
G01X549144Y1158204D02*
X549544Y1158061D01*
Y1157311D01*
X549144Y1157169D01*
X548944D01*
Y1158204D01*
X549144D01*
G37*
G36*
G01X548744Y1160694D02*
X548344Y1160837D01*
Y1161587D01*
X548744Y1161729D01*
X548944D01*
Y1160694D01*
X548744D01*
G37*
G36*
G01X549144Y1160554D02*
X549544Y1160411D01*
Y1159661D01*
X549144Y1159519D01*
X548944D01*
Y1160554D01*
X549144D01*
G37*
G36*
G01X547544Y1163044D02*
X547144Y1163187D01*
Y1163937D01*
X547544Y1164079D01*
X547744D01*
Y1163044D01*
X547544D01*
G37*
G36*
G01X547944Y1162904D02*
X548344Y1162761D01*
Y1162011D01*
X547944Y1161869D01*
X547744D01*
Y1162904D01*
X547944D01*
G37*
G36*
G01X549144D02*
X549544Y1162761D01*
Y1162011D01*
X549144Y1161869D01*
X548944D01*
Y1162904D01*
X549144D01*
G37*
G36*
G01X533719Y1319627D02*
X534669Y1320577D01*
X559452D01*
X562392Y1323517D01*
X564327Y1325452D01*
Y1328045D01*
X564807Y1328525D01*
X567400D01*
X581747D01*
X582657Y1327615D01*
Y1311855D01*
X581267Y1310465D01*
X578293D01*
X556662D01*
X554219Y1312908D01*
X553219Y1313908D01*
X534719D01*
X533719Y1314908D01*
Y1319627D01*
G37*
G36*
G01X550309Y1580678D02*
G03I-720J0D01*
G37*
G36*
G01X545353D02*
G03I-720J0D01*
G37*
G36*
G01X550309Y1575592D02*
G03I-720J0D01*
G37*
G36*
G01X545353D02*
G03I-720J0D01*
G37*
G36*
G01X538249Y1575686D02*
G03I-720J0D01*
G37*
G36*
G01Y1580678D02*
G03I-720J0D01*
G37*
G36*
G01X550653Y1599790D02*
G03I-720J0D01*
G37*
G36*
G01X538593Y1599884D02*
G03I-720J0D01*
G37*
G36*
G01X543549D02*
G03I-720J0D01*
G37*
G36*
G01X550309Y1592590D02*
G03I-720J0D01*
G37*
G36*
G01X545353D02*
G03I-720J0D01*
G37*
G36*
G01X550309Y1587598D02*
G03I-720J0D01*
G37*
G36*
G01X545353D02*
G03I-720J0D01*
G37*
G36*
G01X538249D02*
G03I-720J0D01*
G37*
G36*
G01Y1592590D02*
G03I-720J0D01*
G37*
G36*
G01X550653Y1611796D02*
G03I-720J0D01*
G37*
G36*
G01Y1604876D02*
G03I-720J0D01*
G37*
G36*
G01Y1616788D02*
G03I-720J0D01*
G37*
G36*
G01X543549D02*
G03I-720J0D01*
G37*
G36*
G01X538593D02*
G03I-720J0D01*
G37*
G36*
G01Y1604876D02*
G03I-720J0D01*
G37*
G36*
G01X543549D02*
G03I-720J0D01*
G37*
G36*
G01X538593Y1611796D02*
G03I-720J0D01*
G37*
G36*
G01X543549D02*
G03I-720J0D01*
G37*
G36*
G01X563500Y32842D02*
G03I-720J0D01*
G37*
G36*
G01X565150Y45132D02*
G03I-720J0D01*
G37*
G36*
G01X554040Y77443D02*
G03I-720J0D01*
G37*
G36*
G01X554377Y193862D02*
G03I-720J0D01*
G37*
G36*
G01X565628Y850474D02*
X566028Y850331D01*
Y849581D01*
X565628Y849439D01*
X565428D01*
Y850474D01*
X565628D01*
G37*
G36*
G01Y848124D02*
X566028Y847981D01*
Y847231D01*
X565628Y847089D01*
X565428D01*
Y848124D01*
X565628D01*
G37*
G36*
G01X565228Y848264D02*
X564828Y848407D01*
Y849157D01*
X565228Y849299D01*
X565428D01*
Y848264D01*
X565228D01*
G37*
G36*
G01Y845914D02*
X564828Y846057D01*
Y846807D01*
X565228Y846949D01*
X565428D01*
Y845914D01*
X565228D01*
G37*
G36*
G01Y850614D02*
X564828Y850757D01*
Y851507D01*
X565228Y851649D01*
X565428D01*
Y850614D01*
X565228D01*
G37*
G36*
G01X563428Y850474D02*
X563828Y850331D01*
Y849581D01*
X563428Y849439D01*
X563228D01*
Y850474D01*
X563428D01*
G37*
G36*
G01X563028Y850614D02*
X562628Y850757D01*
Y851507D01*
X563028Y851649D01*
X563228D01*
Y850614D01*
X563028D01*
G37*
G36*
G01X561028Y850474D02*
X561428Y850331D01*
Y849581D01*
X561028Y849439D01*
X560828D01*
Y850474D01*
X561028D01*
G37*
G36*
G01X560628Y850614D02*
X560228Y850757D01*
Y851507D01*
X560628Y851649D01*
X560828D01*
Y850614D01*
X560628D01*
G37*
G36*
G01X562228Y850474D02*
X562628Y850331D01*
Y849581D01*
X562228Y849439D01*
X562028D01*
Y850474D01*
X562228D01*
G37*
G36*
G01X561828Y850614D02*
X561428Y850757D01*
Y851507D01*
X561828Y851649D01*
X562028D01*
Y850614D01*
X561828D01*
G37*
G36*
G01X559828Y850474D02*
X560228Y850331D01*
Y849581D01*
X559828Y849439D01*
X559628D01*
Y850474D01*
X559828D01*
G37*
G36*
G01X559428Y850614D02*
X559028Y850757D01*
Y851507D01*
X559428Y851649D01*
X559628D01*
Y850614D01*
X559428D01*
G37*
G36*
G01X553428Y851395D02*
X553028Y851537D01*
Y852287D01*
X553428Y852430D01*
X553628D01*
Y851395D01*
X553428D01*
G37*
G36*
G01X553828Y851255D02*
X554228Y851113D01*
Y850363D01*
X553828Y850220D01*
X553628D01*
Y851255D01*
X553828D01*
G37*
G36*
G01X551428Y848905D02*
X551828Y848763D01*
Y848013D01*
X551428Y847870D01*
X551228D01*
Y848905D01*
X551428D01*
G37*
G36*
G01X551028Y849045D02*
X550628Y849187D01*
Y849937D01*
X551028Y850080D01*
X551228D01*
Y849045D01*
X551028D01*
G37*
G36*
G01X551428Y851255D02*
X551828Y851113D01*
Y850363D01*
X551428Y850220D01*
X551228D01*
Y851255D01*
X551428D01*
G37*
G36*
G01X551028Y851395D02*
X550628Y851537D01*
Y852287D01*
X551028Y852430D01*
X551228D01*
Y851395D01*
X551028D01*
G37*
G36*
G01X552628Y848905D02*
X553028Y848763D01*
Y848013D01*
X552628Y847870D01*
X552428D01*
Y848905D01*
X552628D01*
G37*
G36*
G01Y851255D02*
X553028Y851113D01*
Y850363D01*
X552628Y850220D01*
X552428D01*
Y851255D01*
X552628D01*
G37*
G36*
G01X552228Y849045D02*
X551828Y849187D01*
Y849937D01*
X552228Y850080D01*
X552428D01*
Y849045D01*
X552228D01*
G37*
G36*
G01Y851395D02*
X551828Y851537D01*
Y852287D01*
X552228Y852430D01*
X552428D01*
Y851395D01*
X552228D01*
G37*
G36*
G01X549828Y849045D02*
X549428Y849187D01*
Y849937D01*
X549828Y850080D01*
X550028D01*
Y849045D01*
X549828D01*
G37*
G36*
G01Y851395D02*
X549428Y851537D01*
Y852287D01*
X549828Y852430D01*
X550028D01*
Y851395D01*
X549828D01*
G37*
G36*
G01X550228Y851255D02*
X550628Y851113D01*
Y850363D01*
X550228Y850220D01*
X550028D01*
Y851255D01*
X550228D01*
G37*
G36*
G01X565628Y866924D02*
X566028Y866781D01*
Y866031D01*
X565628Y865889D01*
X565428D01*
Y866924D01*
X565628D01*
G37*
G36*
G01Y864574D02*
X566028Y864431D01*
Y863681D01*
X565628Y863539D01*
X565428D01*
Y864574D01*
X565628D01*
G37*
G36*
G01X565228Y864714D02*
X564828Y864857D01*
Y865607D01*
X565228Y865749D01*
X565428D01*
Y864714D01*
X565228D01*
G37*
G36*
G01Y862364D02*
X564828Y862507D01*
Y863257D01*
X565228Y863399D01*
X565428D01*
Y862364D01*
X565228D01*
G37*
G36*
G01Y867064D02*
X564828Y867207D01*
Y867957D01*
X565228Y868099D01*
X565428D01*
Y867064D01*
X565228D01*
G37*
G36*
G01X565628Y852824D02*
X566028Y852681D01*
Y851931D01*
X565628Y851789D01*
X565428D01*
Y852824D01*
X565628D01*
G37*
G36*
G01X565228Y852964D02*
X564828Y853107D01*
Y853857D01*
X565228Y853999D01*
X565428D01*
Y852964D01*
X565228D01*
G37*
G36*
G01X565628Y862224D02*
X566028Y862081D01*
Y861331D01*
X565628Y861189D01*
X565428D01*
Y862224D01*
X565628D01*
G37*
G36*
G01Y859874D02*
X566028Y859731D01*
Y858981D01*
X565628Y858839D01*
X565428D01*
Y859874D01*
X565628D01*
G37*
G36*
G01Y857524D02*
X566028Y857381D01*
Y856631D01*
X565628Y856489D01*
X565428D01*
Y857524D01*
X565628D01*
G37*
G36*
G01Y855174D02*
X566028Y855031D01*
Y854281D01*
X565628Y854139D01*
X565428D01*
Y855174D01*
X565628D01*
G37*
G36*
G01X565228Y860014D02*
X564828Y860157D01*
Y860907D01*
X565228Y861049D01*
X565428D01*
Y860014D01*
X565228D01*
G37*
G36*
G01Y857664D02*
X564828Y857807D01*
Y858557D01*
X565228Y858699D01*
X565428D01*
Y857664D01*
X565228D01*
G37*
G36*
G01Y855314D02*
X564828Y855457D01*
Y856207D01*
X565228Y856349D01*
X565428D01*
Y855314D01*
X565228D01*
G37*
G36*
G01X563028Y852964D02*
X562628Y853107D01*
Y853857D01*
X563028Y853999D01*
X563228D01*
Y852964D01*
X563028D01*
G37*
G36*
G01X563428Y862224D02*
X563828Y862081D01*
Y861331D01*
X563428Y861189D01*
X563228D01*
Y862224D01*
X563428D01*
G37*
G36*
G01Y859874D02*
X563828Y859731D01*
Y858981D01*
X563428Y858839D01*
X563228D01*
Y859874D01*
X563428D01*
G37*
G36*
G01Y857524D02*
X563828Y857381D01*
Y856631D01*
X563428Y856489D01*
X563228D01*
Y857524D01*
X563428D01*
G37*
G36*
G01Y855174D02*
X563828Y855031D01*
Y854281D01*
X563428Y854139D01*
X563228D01*
Y855174D01*
X563428D01*
G37*
G36*
G01X563028Y860014D02*
X562628Y860157D01*
Y860907D01*
X563028Y861049D01*
X563228D01*
Y860014D01*
X563028D01*
G37*
G36*
G01Y857664D02*
X562628Y857807D01*
Y858557D01*
X563028Y858699D01*
X563228D01*
Y857664D01*
X563028D01*
G37*
G36*
G01Y855314D02*
X562628Y855457D01*
Y856207D01*
X563028Y856349D01*
X563228D01*
Y855314D01*
X563028D01*
G37*
G36*
G01X563428Y866924D02*
X563828Y866781D01*
Y866031D01*
X563428Y865889D01*
X563228D01*
Y866924D01*
X563428D01*
G37*
G36*
G01Y864574D02*
X563828Y864431D01*
Y863681D01*
X563428Y863539D01*
X563228D01*
Y864574D01*
X563428D01*
G37*
G36*
G01X563028Y862364D02*
X562628Y862507D01*
Y863257D01*
X563028Y863399D01*
X563228D01*
Y862364D01*
X563028D01*
G37*
G36*
G01Y864714D02*
X562628Y864857D01*
Y865607D01*
X563028Y865749D01*
X563228D01*
Y864714D01*
X563028D01*
G37*
G36*
G01Y867064D02*
X562628Y867207D01*
Y867957D01*
X563028Y868099D01*
X563228D01*
Y867064D01*
X563028D01*
G37*
G36*
G01X563428Y852824D02*
X563828Y852681D01*
Y851931D01*
X563428Y851789D01*
X563228D01*
Y852824D01*
X563428D01*
G37*
G36*
G01X561028D02*
X561428Y852681D01*
Y851931D01*
X561028Y851789D01*
X560828D01*
Y852824D01*
X561028D01*
G37*
G36*
G01X560628Y852964D02*
X560228Y853107D01*
Y853857D01*
X560628Y853999D01*
X560828D01*
Y852964D01*
X560628D01*
G37*
G36*
G01X561028Y862224D02*
X561428Y862081D01*
Y861331D01*
X561028Y861189D01*
X560828D01*
Y862224D01*
X561028D01*
G37*
G36*
G01Y859874D02*
X561428Y859731D01*
Y858981D01*
X561028Y858839D01*
X560828D01*
Y859874D01*
X561028D01*
G37*
G36*
G01Y857524D02*
X561428Y857381D01*
Y856631D01*
X561028Y856489D01*
X560828D01*
Y857524D01*
X561028D01*
G37*
G36*
G01Y855174D02*
X561428Y855031D01*
Y854281D01*
X561028Y854139D01*
X560828D01*
Y855174D01*
X561028D01*
G37*
G36*
G01X560628Y860014D02*
X560228Y860157D01*
Y860907D01*
X560628Y861049D01*
X560828D01*
Y860014D01*
X560628D01*
G37*
G36*
G01Y857664D02*
X560228Y857807D01*
Y858557D01*
X560628Y858699D01*
X560828D01*
Y857664D01*
X560628D01*
G37*
G36*
G01Y855314D02*
X560228Y855457D01*
Y856207D01*
X560628Y856349D01*
X560828D01*
Y855314D01*
X560628D01*
G37*
G36*
G01X561028Y864574D02*
X561428Y864431D01*
Y863681D01*
X561028Y863539D01*
X560828D01*
Y864574D01*
X561028D01*
G37*
G36*
G01Y866924D02*
X561428Y866781D01*
Y866031D01*
X561028Y865889D01*
X560828D01*
Y866924D01*
X561028D01*
G37*
G36*
G01X560628Y864714D02*
X560228Y864857D01*
Y865607D01*
X560628Y865749D01*
X560828D01*
Y864714D01*
X560628D01*
G37*
G36*
G01Y862364D02*
X560228Y862507D01*
Y863257D01*
X560628Y863399D01*
X560828D01*
Y862364D01*
X560628D01*
G37*
G36*
G01Y867064D02*
X560228Y867207D01*
Y867957D01*
X560628Y868099D01*
X560828D01*
Y867064D01*
X560628D01*
G37*
G36*
G01X561828Y864714D02*
X561428Y864857D01*
Y865607D01*
X561828Y865749D01*
X562028D01*
Y864714D01*
X561828D01*
G37*
G36*
G01Y862364D02*
X561428Y862507D01*
Y863257D01*
X561828Y863399D01*
X562028D01*
Y862364D01*
X561828D01*
G37*
G36*
G01X562228Y866924D02*
X562628Y866781D01*
Y866031D01*
X562228Y865889D01*
X562028D01*
Y866924D01*
X562228D01*
G37*
G36*
G01Y864574D02*
X562628Y864431D01*
Y863681D01*
X562228Y863539D01*
X562028D01*
Y864574D01*
X562228D01*
G37*
G36*
G01X561828Y867064D02*
X561428Y867207D01*
Y867957D01*
X561828Y868099D01*
X562028D01*
Y867064D01*
X561828D01*
G37*
G36*
G01Y852964D02*
X561428Y853107D01*
Y853857D01*
X561828Y853999D01*
X562028D01*
Y852964D01*
X561828D01*
G37*
G36*
G01Y860014D02*
X561428Y860157D01*
Y860907D01*
X561828Y861049D01*
X562028D01*
Y860014D01*
X561828D01*
G37*
G36*
G01Y857664D02*
X561428Y857807D01*
Y858557D01*
X561828Y858699D01*
X562028D01*
Y857664D01*
X561828D01*
G37*
G36*
G01Y855314D02*
X561428Y855457D01*
Y856207D01*
X561828Y856349D01*
X562028D01*
Y855314D01*
X561828D01*
G37*
G36*
G01X562228Y852824D02*
X562628Y852681D01*
Y851931D01*
X562228Y851789D01*
X562028D01*
Y852824D01*
X562228D01*
G37*
G36*
G01Y862224D02*
X562628Y862081D01*
Y861331D01*
X562228Y861189D01*
X562028D01*
Y862224D01*
X562228D01*
G37*
G36*
G01Y859874D02*
X562628Y859731D01*
Y858981D01*
X562228Y858839D01*
X562028D01*
Y859874D01*
X562228D01*
G37*
G36*
G01Y857524D02*
X562628Y857381D01*
Y856631D01*
X562228Y856489D01*
X562028D01*
Y857524D01*
X562228D01*
G37*
G36*
G01Y855174D02*
X562628Y855031D01*
Y854281D01*
X562228Y854139D01*
X562028D01*
Y855174D01*
X562228D01*
G37*
G36*
G01X559428Y864714D02*
X559028Y864857D01*
Y865607D01*
X559428Y865749D01*
X559628D01*
Y864714D01*
X559428D01*
G37*
G36*
G01Y862364D02*
X559028Y862507D01*
Y863257D01*
X559428Y863399D01*
X559628D01*
Y862364D01*
X559428D01*
G37*
G36*
G01X559828Y864574D02*
X560228Y864431D01*
Y863681D01*
X559828Y863539D01*
X559628D01*
Y864574D01*
X559828D01*
G37*
G36*
G01Y866924D02*
X560228Y866781D01*
Y866031D01*
X559828Y865889D01*
X559628D01*
Y866924D01*
X559828D01*
G37*
G36*
G01X559428Y867064D02*
X559028Y867207D01*
Y867957D01*
X559428Y868099D01*
X559628D01*
Y867064D01*
X559428D01*
G37*
G36*
G01Y852964D02*
X559028Y853107D01*
Y853857D01*
X559428Y853999D01*
X559628D01*
Y852964D01*
X559428D01*
G37*
G36*
G01X559828Y852824D02*
X560228Y852681D01*
Y851931D01*
X559828Y851789D01*
X559628D01*
Y852824D01*
X559828D01*
G37*
G36*
G01X559428Y860014D02*
X559028Y860157D01*
Y860907D01*
X559428Y861049D01*
X559628D01*
Y860014D01*
X559428D01*
G37*
G36*
G01Y857664D02*
X559028Y857807D01*
Y858557D01*
X559428Y858699D01*
X559628D01*
Y857664D01*
X559428D01*
G37*
G36*
G01Y855314D02*
X559028Y855457D01*
Y856207D01*
X559428Y856349D01*
X559628D01*
Y855314D01*
X559428D01*
G37*
G36*
G01X559828Y862224D02*
X560228Y862081D01*
Y861331D01*
X559828Y861189D01*
X559628D01*
Y862224D01*
X559828D01*
G37*
G36*
G01Y859874D02*
X560228Y859731D01*
Y858981D01*
X559828Y858839D01*
X559628D01*
Y859874D01*
X559828D01*
G37*
G36*
G01Y857524D02*
X560228Y857381D01*
Y856631D01*
X559828Y856489D01*
X559628D01*
Y857524D01*
X559828D01*
G37*
G36*
G01Y855174D02*
X560228Y855031D01*
Y854281D01*
X559828Y854139D01*
X559628D01*
Y855174D01*
X559828D01*
G37*
G36*
G01X553428Y865495D02*
X553028Y865637D01*
Y866387D01*
X553428Y866530D01*
X553628D01*
Y865495D01*
X553428D01*
G37*
G36*
G01Y863145D02*
X553028Y863287D01*
Y864037D01*
X553428Y864180D01*
X553628D01*
Y863145D01*
X553428D01*
G37*
G36*
G01X553828Y867705D02*
X554228Y867563D01*
Y866813D01*
X553828Y866670D01*
X553628D01*
Y867705D01*
X553828D01*
G37*
G36*
G01Y865355D02*
X554228Y865213D01*
Y864463D01*
X553828Y864320D01*
X553628D01*
Y865355D01*
X553828D01*
G37*
G36*
G01Y863005D02*
X554228Y862863D01*
Y862113D01*
X553828Y861970D01*
X553628D01*
Y863005D01*
X553828D01*
G37*
G36*
G01X553428Y867845D02*
X553028Y867987D01*
Y868737D01*
X553428Y868880D01*
X553628D01*
Y867845D01*
X553428D01*
G37*
G36*
G01X553828Y853605D02*
X554228Y853463D01*
Y852713D01*
X553828Y852570D01*
X553628D01*
Y853605D01*
X553828D01*
G37*
G36*
G01X553428Y860795D02*
X553028Y860937D01*
Y861687D01*
X553428Y861830D01*
X553628D01*
Y860795D01*
X553428D01*
G37*
G36*
G01Y858445D02*
X553028Y858587D01*
Y859337D01*
X553428Y859480D01*
X553628D01*
Y858445D01*
X553428D01*
G37*
G36*
G01Y856095D02*
X553028Y856237D01*
Y856987D01*
X553428Y857130D01*
X553628D01*
Y856095D01*
X553428D01*
G37*
G36*
G01Y853745D02*
X553028Y853887D01*
Y854637D01*
X553428Y854780D01*
X553628D01*
Y853745D01*
X553428D01*
G37*
G36*
G01X553828Y860655D02*
X554228Y860513D01*
Y859763D01*
X553828Y859620D01*
X553628D01*
Y860655D01*
X553828D01*
G37*
G36*
G01Y858305D02*
X554228Y858163D01*
Y857413D01*
X553828Y857270D01*
X553628D01*
Y858305D01*
X553828D01*
G37*
G36*
G01Y855955D02*
X554228Y855813D01*
Y855063D01*
X553828Y854920D01*
X553628D01*
Y855955D01*
X553828D01*
G37*
G36*
G01X551428Y853605D02*
X551828Y853463D01*
Y852713D01*
X551428Y852570D01*
X551228D01*
Y853605D01*
X551428D01*
G37*
G36*
G01Y860655D02*
X551828Y860513D01*
Y859763D01*
X551428Y859620D01*
X551228D01*
Y860655D01*
X551428D01*
G37*
G36*
G01Y858305D02*
X551828Y858163D01*
Y857413D01*
X551428Y857270D01*
X551228D01*
Y858305D01*
X551428D01*
G37*
G36*
G01Y855955D02*
X551828Y855813D01*
Y855063D01*
X551428Y854920D01*
X551228D01*
Y855955D01*
X551428D01*
G37*
G36*
G01X551028Y860795D02*
X550628Y860937D01*
Y861687D01*
X551028Y861830D01*
X551228D01*
Y860795D01*
X551028D01*
G37*
G36*
G01Y858445D02*
X550628Y858587D01*
Y859337D01*
X551028Y859480D01*
X551228D01*
Y858445D01*
X551028D01*
G37*
G36*
G01Y856095D02*
X550628Y856237D01*
Y856987D01*
X551028Y857130D01*
X551228D01*
Y856095D01*
X551028D01*
G37*
G36*
G01Y853745D02*
X550628Y853887D01*
Y854637D01*
X551028Y854780D01*
X551228D01*
Y853745D01*
X551028D01*
G37*
G36*
G01X551428Y867705D02*
X551828Y867563D01*
Y866813D01*
X551428Y866670D01*
X551228D01*
Y867705D01*
X551428D01*
G37*
G36*
G01Y865355D02*
X551828Y865213D01*
Y864463D01*
X551428Y864320D01*
X551228D01*
Y865355D01*
X551428D01*
G37*
G36*
G01Y863005D02*
X551828Y862863D01*
Y862113D01*
X551428Y861970D01*
X551228D01*
Y863005D01*
X551428D01*
G37*
G36*
G01X551028Y865495D02*
X550628Y865637D01*
Y866387D01*
X551028Y866530D01*
X551228D01*
Y865495D01*
X551028D01*
G37*
G36*
G01Y863145D02*
X550628Y863287D01*
Y864037D01*
X551028Y864180D01*
X551228D01*
Y863145D01*
X551028D01*
G37*
G36*
G01Y867845D02*
X550628Y867987D01*
Y868737D01*
X551028Y868880D01*
X551228D01*
Y867845D01*
X551028D01*
G37*
G36*
G01X552628Y867705D02*
X553028Y867563D01*
Y866813D01*
X552628Y866670D01*
X552428D01*
Y867705D01*
X552628D01*
G37*
G36*
G01Y865355D02*
X553028Y865213D01*
Y864463D01*
X552628Y864320D01*
X552428D01*
Y865355D01*
X552628D01*
G37*
G36*
G01Y863005D02*
X553028Y862863D01*
Y862113D01*
X552628Y861970D01*
X552428D01*
Y863005D01*
X552628D01*
G37*
G36*
G01Y853605D02*
X553028Y853463D01*
Y852713D01*
X552628Y852570D01*
X552428D01*
Y853605D01*
X552628D01*
G37*
G36*
G01Y860655D02*
X553028Y860513D01*
Y859763D01*
X552628Y859620D01*
X552428D01*
Y860655D01*
X552628D01*
G37*
G36*
G01Y858305D02*
X553028Y858163D01*
Y857413D01*
X552628Y857270D01*
X552428D01*
Y858305D01*
X552628D01*
G37*
G36*
G01Y855955D02*
X553028Y855813D01*
Y855063D01*
X552628Y854920D01*
X552428D01*
Y855955D01*
X552628D01*
G37*
G36*
G01X552228Y865495D02*
X551828Y865637D01*
Y866387D01*
X552228Y866530D01*
X552428D01*
Y865495D01*
X552228D01*
G37*
G36*
G01Y863145D02*
X551828Y863287D01*
Y864037D01*
X552228Y864180D01*
X552428D01*
Y863145D01*
X552228D01*
G37*
G36*
G01Y867845D02*
X551828Y867987D01*
Y868737D01*
X552228Y868880D01*
X552428D01*
Y867845D01*
X552228D01*
G37*
G36*
G01Y860795D02*
X551828Y860937D01*
Y861687D01*
X552228Y861830D01*
X552428D01*
Y860795D01*
X552228D01*
G37*
G36*
G01Y858445D02*
X551828Y858587D01*
Y859337D01*
X552228Y859480D01*
X552428D01*
Y858445D01*
X552228D01*
G37*
G36*
G01Y856095D02*
X551828Y856237D01*
Y856987D01*
X552228Y857130D01*
X552428D01*
Y856095D01*
X552228D01*
G37*
G36*
G01Y853745D02*
X551828Y853887D01*
Y854637D01*
X552228Y854780D01*
X552428D01*
Y853745D01*
X552228D01*
G37*
G36*
G01X550228Y853605D02*
X550628Y853463D01*
Y852713D01*
X550228Y852570D01*
X550028D01*
Y853605D01*
X550228D01*
G37*
G36*
G01Y860655D02*
X550628Y860513D01*
Y859763D01*
X550228Y859620D01*
X550028D01*
Y860655D01*
X550228D01*
G37*
G36*
G01Y858305D02*
X550628Y858163D01*
Y857413D01*
X550228Y857270D01*
X550028D01*
Y858305D01*
X550228D01*
G37*
G36*
G01Y855955D02*
X550628Y855813D01*
Y855063D01*
X550228Y854920D01*
X550028D01*
Y855955D01*
X550228D01*
G37*
G36*
G01X549828Y863145D02*
X549428Y863287D01*
Y864037D01*
X549828Y864180D01*
X550028D01*
Y863145D01*
X549828D01*
G37*
G36*
G01Y865495D02*
X549428Y865637D01*
Y866387D01*
X549828Y866530D01*
X550028D01*
Y865495D01*
X549828D01*
G37*
G36*
G01Y867845D02*
X549428Y867987D01*
Y868737D01*
X549828Y868880D01*
X550028D01*
Y867845D01*
X549828D01*
G37*
G36*
G01X550228Y865355D02*
X550628Y865213D01*
Y864463D01*
X550228Y864320D01*
X550028D01*
Y865355D01*
X550228D01*
G37*
G36*
G01Y863005D02*
X550628Y862863D01*
Y862113D01*
X550228Y861970D01*
X550028D01*
Y863005D01*
X550228D01*
G37*
G36*
G01Y867705D02*
X550628Y867563D01*
Y866813D01*
X550228Y866670D01*
X550028D01*
Y867705D01*
X550228D01*
G37*
G36*
G01X549828Y860795D02*
X549428Y860937D01*
Y861687D01*
X549828Y861830D01*
X550028D01*
Y860795D01*
X549828D01*
G37*
G36*
G01Y858445D02*
X549428Y858587D01*
Y859337D01*
X549828Y859480D01*
X550028D01*
Y858445D01*
X549828D01*
G37*
G36*
G01Y856095D02*
X549428Y856237D01*
Y856987D01*
X549828Y857130D01*
X550028D01*
Y856095D01*
X549828D01*
G37*
G36*
G01Y853745D02*
X549428Y853887D01*
Y854637D01*
X549828Y854780D01*
X550028D01*
Y853745D01*
X549828D01*
G37*
G36*
G01X565228Y883514D02*
X564828Y883657D01*
Y884407D01*
X565228Y884549D01*
X565428D01*
Y883514D01*
X565228D01*
G37*
G36*
G01X565628Y873974D02*
X566028Y873831D01*
Y873081D01*
X565628Y872939D01*
X565428D01*
Y873974D01*
X565628D01*
G37*
G36*
G01Y876324D02*
X566028Y876181D01*
Y875431D01*
X565628Y875289D01*
X565428D01*
Y876324D01*
X565628D01*
G37*
G36*
G01X565228Y871764D02*
X564828Y871907D01*
Y872657D01*
X565228Y872799D01*
X565428D01*
Y871764D01*
X565228D01*
G37*
G36*
G01Y874114D02*
X564828Y874257D01*
Y875007D01*
X565228Y875149D01*
X565428D01*
Y874114D01*
X565228D01*
G37*
G36*
G01Y876464D02*
X564828Y876607D01*
Y877357D01*
X565228Y877499D01*
X565428D01*
Y876464D01*
X565228D01*
G37*
G36*
G01Y869414D02*
X564828Y869557D01*
Y870307D01*
X565228Y870449D01*
X565428D01*
Y869414D01*
X565228D01*
G37*
G36*
G01X565628Y871624D02*
X566028Y871481D01*
Y870731D01*
X565628Y870589D01*
X565428D01*
Y871624D01*
X565628D01*
G37*
G36*
G01Y878674D02*
X566028Y878531D01*
Y877781D01*
X565628Y877639D01*
X565428D01*
Y878674D01*
X565628D01*
G37*
G36*
G01Y869274D02*
X566028Y869131D01*
Y868381D01*
X565628Y868239D01*
X565428D01*
Y869274D01*
X565628D01*
G37*
G36*
G01Y881024D02*
X566028Y880881D01*
Y880131D01*
X565628Y879989D01*
X565428D01*
Y881024D01*
X565628D01*
G37*
G36*
G01Y883374D02*
X566028Y883231D01*
Y882481D01*
X565628Y882339D01*
X565428D01*
Y883374D01*
X565628D01*
G37*
G36*
G01X565228Y878814D02*
X564828Y878957D01*
Y879707D01*
X565228Y879849D01*
X565428D01*
Y878814D01*
X565228D01*
G37*
G36*
G01Y881164D02*
X564828Y881307D01*
Y882057D01*
X565228Y882199D01*
X565428D01*
Y881164D01*
X565228D01*
G37*
G36*
G01X563428Y878674D02*
X563828Y878531D01*
Y877781D01*
X563428Y877639D01*
X563228D01*
Y878674D01*
X563428D01*
G37*
G36*
G01Y881024D02*
X563828Y880881D01*
Y880131D01*
X563428Y879989D01*
X563228D01*
Y881024D01*
X563428D01*
G37*
G36*
G01Y883374D02*
X563828Y883231D01*
Y882481D01*
X563428Y882339D01*
X563228D01*
Y883374D01*
X563428D01*
G37*
G36*
G01X563028Y878814D02*
X562628Y878957D01*
Y879707D01*
X563028Y879849D01*
X563228D01*
Y878814D01*
X563028D01*
G37*
G36*
G01Y881164D02*
X562628Y881307D01*
Y882057D01*
X563028Y882199D01*
X563228D01*
Y881164D01*
X563028D01*
G37*
G36*
G01Y883514D02*
X562628Y883657D01*
Y884407D01*
X563028Y884549D01*
X563228D01*
Y883514D01*
X563028D01*
G37*
G36*
G01Y869414D02*
X562628Y869557D01*
Y870307D01*
X563028Y870449D01*
X563228D01*
Y869414D01*
X563028D01*
G37*
G36*
G01X563428Y871624D02*
X563828Y871481D01*
Y870731D01*
X563428Y870589D01*
X563228D01*
Y871624D01*
X563428D01*
G37*
G36*
G01Y873974D02*
X563828Y873831D01*
Y873081D01*
X563428Y872939D01*
X563228D01*
Y873974D01*
X563428D01*
G37*
G36*
G01Y876324D02*
X563828Y876181D01*
Y875431D01*
X563428Y875289D01*
X563228D01*
Y876324D01*
X563428D01*
G37*
G36*
G01X563028Y871764D02*
X562628Y871907D01*
Y872657D01*
X563028Y872799D01*
X563228D01*
Y871764D01*
X563028D01*
G37*
G36*
G01Y874114D02*
X562628Y874257D01*
Y875007D01*
X563028Y875149D01*
X563228D01*
Y874114D01*
X563028D01*
G37*
G36*
G01Y876464D02*
X562628Y876607D01*
Y877357D01*
X563028Y877499D01*
X563228D01*
Y876464D01*
X563028D01*
G37*
G36*
G01X563428Y869274D02*
X563828Y869131D01*
Y868381D01*
X563428Y868239D01*
X563228D01*
Y869274D01*
X563428D01*
G37*
G36*
G01X560628Y869414D02*
X560228Y869557D01*
Y870307D01*
X560628Y870449D01*
X560828D01*
Y869414D01*
X560628D01*
G37*
G36*
G01X561028Y871624D02*
X561428Y871481D01*
Y870731D01*
X561028Y870589D01*
X560828D01*
Y871624D01*
X561028D01*
G37*
G36*
G01Y873974D02*
X561428Y873831D01*
Y873081D01*
X561028Y872939D01*
X560828D01*
Y873974D01*
X561028D01*
G37*
G36*
G01Y876324D02*
X561428Y876181D01*
Y875431D01*
X561028Y875289D01*
X560828D01*
Y876324D01*
X561028D01*
G37*
G36*
G01Y878674D02*
X561428Y878531D01*
Y877781D01*
X561028Y877639D01*
X560828D01*
Y878674D01*
X561028D01*
G37*
G36*
G01Y881024D02*
X561428Y880881D01*
Y880131D01*
X561028Y879989D01*
X560828D01*
Y881024D01*
X561028D01*
G37*
G36*
G01Y883374D02*
X561428Y883231D01*
Y882481D01*
X561028Y882339D01*
X560828D01*
Y883374D01*
X561028D01*
G37*
G36*
G01X560628Y871764D02*
X560228Y871907D01*
Y872657D01*
X560628Y872799D01*
X560828D01*
Y871764D01*
X560628D01*
G37*
G36*
G01Y874114D02*
X560228Y874257D01*
Y875007D01*
X560628Y875149D01*
X560828D01*
Y874114D01*
X560628D01*
G37*
G36*
G01Y876464D02*
X560228Y876607D01*
Y877357D01*
X560628Y877499D01*
X560828D01*
Y876464D01*
X560628D01*
G37*
G36*
G01Y878814D02*
X560228Y878957D01*
Y879707D01*
X560628Y879849D01*
X560828D01*
Y878814D01*
X560628D01*
G37*
G36*
G01Y881164D02*
X560228Y881307D01*
Y882057D01*
X560628Y882199D01*
X560828D01*
Y881164D01*
X560628D01*
G37*
G36*
G01Y883514D02*
X560228Y883657D01*
Y884407D01*
X560628Y884549D01*
X560828D01*
Y883514D01*
X560628D01*
G37*
G36*
G01X561028Y869274D02*
X561428Y869131D01*
Y868381D01*
X561028Y868239D01*
X560828D01*
Y869274D01*
X561028D01*
G37*
G36*
G01X562228Y878674D02*
X562628Y878531D01*
Y877781D01*
X562228Y877639D01*
X562028D01*
Y878674D01*
X562228D01*
G37*
G36*
G01Y881024D02*
X562628Y880881D01*
Y880131D01*
X562228Y879989D01*
X562028D01*
Y881024D01*
X562228D01*
G37*
G36*
G01Y883374D02*
X562628Y883231D01*
Y882481D01*
X562228Y882339D01*
X562028D01*
Y883374D01*
X562228D01*
G37*
G36*
G01X561828Y869414D02*
X561428Y869557D01*
Y870307D01*
X561828Y870449D01*
X562028D01*
Y869414D01*
X561828D01*
G37*
G36*
G01X562228Y871624D02*
X562628Y871481D01*
Y870731D01*
X562228Y870589D01*
X562028D01*
Y871624D01*
X562228D01*
G37*
G36*
G01X561828Y871764D02*
X561428Y871907D01*
Y872657D01*
X561828Y872799D01*
X562028D01*
Y871764D01*
X561828D01*
G37*
G36*
G01Y874114D02*
X561428Y874257D01*
Y875007D01*
X561828Y875149D01*
X562028D01*
Y874114D01*
X561828D01*
G37*
G36*
G01Y876464D02*
X561428Y876607D01*
Y877357D01*
X561828Y877499D01*
X562028D01*
Y876464D01*
X561828D01*
G37*
G36*
G01Y878814D02*
X561428Y878957D01*
Y879707D01*
X561828Y879849D01*
X562028D01*
Y878814D01*
X561828D01*
G37*
G36*
G01Y881164D02*
X561428Y881307D01*
Y882057D01*
X561828Y882199D01*
X562028D01*
Y881164D01*
X561828D01*
G37*
G36*
G01X562228Y873974D02*
X562628Y873831D01*
Y873081D01*
X562228Y872939D01*
X562028D01*
Y873974D01*
X562228D01*
G37*
G36*
G01Y876324D02*
X562628Y876181D01*
Y875431D01*
X562228Y875289D01*
X562028D01*
Y876324D01*
X562228D01*
G37*
G36*
G01X561828Y883514D02*
X561428Y883657D01*
Y884407D01*
X561828Y884549D01*
X562028D01*
Y883514D01*
X561828D01*
G37*
G36*
G01X562228Y869274D02*
X562628Y869131D01*
Y868381D01*
X562228Y868239D01*
X562028D01*
Y869274D01*
X562228D01*
G37*
G36*
G01X559428Y869414D02*
X559028Y869557D01*
Y870307D01*
X559428Y870449D01*
X559628D01*
Y869414D01*
X559428D01*
G37*
G36*
G01X559828Y871624D02*
X560228Y871481D01*
Y870731D01*
X559828Y870589D01*
X559628D01*
Y871624D01*
X559828D01*
G37*
G36*
G01X559428Y871764D02*
X559028Y871907D01*
Y872657D01*
X559428Y872799D01*
X559628D01*
Y871764D01*
X559428D01*
G37*
G36*
G01Y874114D02*
X559028Y874257D01*
Y875007D01*
X559428Y875149D01*
X559628D01*
Y874114D01*
X559428D01*
G37*
G36*
G01Y876464D02*
X559028Y876607D01*
Y877357D01*
X559428Y877499D01*
X559628D01*
Y876464D01*
X559428D01*
G37*
G36*
G01Y878814D02*
X559028Y878957D01*
Y879707D01*
X559428Y879849D01*
X559628D01*
Y878814D01*
X559428D01*
G37*
G36*
G01Y881164D02*
X559028Y881307D01*
Y882057D01*
X559428Y882199D01*
X559628D01*
Y881164D01*
X559428D01*
G37*
G36*
G01X559828Y873974D02*
X560228Y873831D01*
Y873081D01*
X559828Y872939D01*
X559628D01*
Y873974D01*
X559828D01*
G37*
G36*
G01Y876324D02*
X560228Y876181D01*
Y875431D01*
X559828Y875289D01*
X559628D01*
Y876324D01*
X559828D01*
G37*
G36*
G01Y878674D02*
X560228Y878531D01*
Y877781D01*
X559828Y877639D01*
X559628D01*
Y878674D01*
X559828D01*
G37*
G36*
G01Y881024D02*
X560228Y880881D01*
Y880131D01*
X559828Y879989D01*
X559628D01*
Y881024D01*
X559828D01*
G37*
G36*
G01Y883374D02*
X560228Y883231D01*
Y882481D01*
X559828Y882339D01*
X559628D01*
Y883374D01*
X559828D01*
G37*
G36*
G01X559428Y883514D02*
X559028Y883657D01*
Y884407D01*
X559428Y884549D01*
X559628D01*
Y883514D01*
X559428D01*
G37*
G36*
G01X559828Y869274D02*
X560228Y869131D01*
Y868381D01*
X559828Y868239D01*
X559628D01*
Y869274D01*
X559828D01*
G37*
G36*
G01X553828Y877105D02*
X554228Y876963D01*
Y876213D01*
X553828Y876070D01*
X553628D01*
Y877105D01*
X553828D01*
G37*
G36*
G01Y879455D02*
X554228Y879313D01*
Y878563D01*
X553828Y878420D01*
X553628D01*
Y879455D01*
X553828D01*
G37*
G36*
G01Y881805D02*
X554228Y881663D01*
Y880913D01*
X553828Y880770D01*
X553628D01*
Y881805D01*
X553828D01*
G37*
G36*
G01Y884155D02*
X554228Y884013D01*
Y883263D01*
X553828Y883120D01*
X553628D01*
Y884155D01*
X553828D01*
G37*
G36*
G01Y870055D02*
X554228Y869913D01*
Y869163D01*
X553828Y869020D01*
X553628D01*
Y870055D01*
X553828D01*
G37*
G36*
G01X553428Y870195D02*
X553028Y870337D01*
Y871087D01*
X553428Y871230D01*
X553628D01*
Y870195D01*
X553428D01*
G37*
G36*
G01X553828Y872405D02*
X554228Y872263D01*
Y871513D01*
X553828Y871370D01*
X553628D01*
Y872405D01*
X553828D01*
G37*
G36*
G01X553428Y872545D02*
X553028Y872687D01*
Y873437D01*
X553428Y873580D01*
X553628D01*
Y872545D01*
X553428D01*
G37*
G36*
G01Y874895D02*
X553028Y875037D01*
Y875787D01*
X553428Y875930D01*
X553628D01*
Y874895D01*
X553428D01*
G37*
G36*
G01Y877245D02*
X553028Y877387D01*
Y878137D01*
X553428Y878280D01*
X553628D01*
Y877245D01*
X553428D01*
G37*
G36*
G01Y879595D02*
X553028Y879737D01*
Y880487D01*
X553428Y880630D01*
X553628D01*
Y879595D01*
X553428D01*
G37*
G36*
G01Y881945D02*
X553028Y882087D01*
Y882837D01*
X553428Y882980D01*
X553628D01*
Y881945D01*
X553428D01*
G37*
G36*
G01X553828Y874755D02*
X554228Y874613D01*
Y873863D01*
X553828Y873720D01*
X553628D01*
Y874755D01*
X553828D01*
G37*
G36*
G01X551428Y870055D02*
X551828Y869913D01*
Y869163D01*
X551428Y869020D01*
X551228D01*
Y870055D01*
X551428D01*
G37*
G36*
G01X551028Y870195D02*
X550628Y870337D01*
Y871087D01*
X551028Y871230D01*
X551228D01*
Y870195D01*
X551028D01*
G37*
G36*
G01X551428Y872405D02*
X551828Y872263D01*
Y871513D01*
X551428Y871370D01*
X551228D01*
Y872405D01*
X551428D01*
G37*
G36*
G01Y874755D02*
X551828Y874613D01*
Y873863D01*
X551428Y873720D01*
X551228D01*
Y874755D01*
X551428D01*
G37*
G36*
G01Y877105D02*
X551828Y876963D01*
Y876213D01*
X551428Y876070D01*
X551228D01*
Y877105D01*
X551428D01*
G37*
G36*
G01Y879455D02*
X551828Y879313D01*
Y878563D01*
X551428Y878420D01*
X551228D01*
Y879455D01*
X551428D01*
G37*
G36*
G01Y881805D02*
X551828Y881663D01*
Y880913D01*
X551428Y880770D01*
X551228D01*
Y881805D01*
X551428D01*
G37*
G36*
G01Y884155D02*
X551828Y884013D01*
Y883263D01*
X551428Y883120D01*
X551228D01*
Y884155D01*
X551428D01*
G37*
G36*
G01X551028Y872545D02*
X550628Y872687D01*
Y873437D01*
X551028Y873580D01*
X551228D01*
Y872545D01*
X551028D01*
G37*
G36*
G01Y874895D02*
X550628Y875037D01*
Y875787D01*
X551028Y875930D01*
X551228D01*
Y874895D01*
X551028D01*
G37*
G36*
G01Y877245D02*
X550628Y877387D01*
Y878137D01*
X551028Y878280D01*
X551228D01*
Y877245D01*
X551028D01*
G37*
G36*
G01Y879595D02*
X550628Y879737D01*
Y880487D01*
X551028Y880630D01*
X551228D01*
Y879595D01*
X551028D01*
G37*
G36*
G01Y881945D02*
X550628Y882087D01*
Y882837D01*
X551028Y882980D01*
X551228D01*
Y881945D01*
X551028D01*
G37*
G36*
G01X552628Y879455D02*
X553028Y879313D01*
Y878563D01*
X552628Y878420D01*
X552428D01*
Y879455D01*
X552628D01*
G37*
G36*
G01Y881805D02*
X553028Y881663D01*
Y880913D01*
X552628Y880770D01*
X552428D01*
Y881805D01*
X552628D01*
G37*
G36*
G01Y884155D02*
X553028Y884013D01*
Y883263D01*
X552628Y883120D01*
X552428D01*
Y884155D01*
X552628D01*
G37*
G36*
G01X552228Y870195D02*
X551828Y870337D01*
Y871087D01*
X552228Y871230D01*
X552428D01*
Y870195D01*
X552228D01*
G37*
G36*
G01Y872545D02*
X551828Y872687D01*
Y873437D01*
X552228Y873580D01*
X552428D01*
Y872545D01*
X552228D01*
G37*
G36*
G01Y874895D02*
X551828Y875037D01*
Y875787D01*
X552228Y875930D01*
X552428D01*
Y874895D01*
X552228D01*
G37*
G36*
G01Y877245D02*
X551828Y877387D01*
Y878137D01*
X552228Y878280D01*
X552428D01*
Y877245D01*
X552228D01*
G37*
G36*
G01Y879595D02*
X551828Y879737D01*
Y880487D01*
X552228Y880630D01*
X552428D01*
Y879595D01*
X552228D01*
G37*
G36*
G01Y881945D02*
X551828Y882087D01*
Y882837D01*
X552228Y882980D01*
X552428D01*
Y881945D01*
X552228D01*
G37*
G36*
G01X552628Y870055D02*
X553028Y869913D01*
Y869163D01*
X552628Y869020D01*
X552428D01*
Y870055D01*
X552628D01*
G37*
G36*
G01Y872405D02*
X553028Y872263D01*
Y871513D01*
X552628Y871370D01*
X552428D01*
Y872405D01*
X552628D01*
G37*
G36*
G01Y874755D02*
X553028Y874613D01*
Y873863D01*
X552628Y873720D01*
X552428D01*
Y874755D01*
X552628D01*
G37*
G36*
G01Y877105D02*
X553028Y876963D01*
Y876213D01*
X552628Y876070D01*
X552428D01*
Y877105D01*
X552628D01*
G37*
G36*
G01X549828Y870195D02*
X549428Y870337D01*
Y871087D01*
X549828Y871230D01*
X550028D01*
Y870195D01*
X549828D01*
G37*
G36*
G01Y872545D02*
X549428Y872687D01*
Y873437D01*
X549828Y873580D01*
X550028D01*
Y872545D01*
X549828D01*
G37*
G36*
G01Y874895D02*
X549428Y875037D01*
Y875787D01*
X549828Y875930D01*
X550028D01*
Y874895D01*
X549828D01*
G37*
G36*
G01Y877245D02*
X549428Y877387D01*
Y878137D01*
X549828Y878280D01*
X550028D01*
Y877245D01*
X549828D01*
G37*
G36*
G01Y879595D02*
X549428Y879737D01*
Y880487D01*
X549828Y880630D01*
X550028D01*
Y879595D01*
X549828D01*
G37*
G36*
G01Y881945D02*
X549428Y882087D01*
Y882837D01*
X549828Y882980D01*
X550028D01*
Y881945D01*
X549828D01*
G37*
G36*
G01X550228Y870055D02*
X550628Y869913D01*
Y869163D01*
X550228Y869020D01*
X550028D01*
Y870055D01*
X550228D01*
G37*
G36*
G01Y872405D02*
X550628Y872263D01*
Y871513D01*
X550228Y871370D01*
X550028D01*
Y872405D01*
X550228D01*
G37*
G36*
G01Y874755D02*
X550628Y874613D01*
Y873863D01*
X550228Y873720D01*
X550028D01*
Y874755D01*
X550228D01*
G37*
G36*
G01Y877105D02*
X550628Y876963D01*
Y876213D01*
X550228Y876070D01*
X550028D01*
Y877105D01*
X550228D01*
G37*
G36*
G01Y879455D02*
X550628Y879313D01*
Y878563D01*
X550228Y878420D01*
X550028D01*
Y879455D01*
X550228D01*
G37*
G36*
G01Y881805D02*
X550628Y881663D01*
Y880913D01*
X550228Y880770D01*
X550028D01*
Y881805D01*
X550228D01*
G37*
G36*
G01Y884155D02*
X550628Y884013D01*
Y883263D01*
X550228Y883120D01*
X550028D01*
Y884155D01*
X550228D01*
G37*
G36*
G01X566436Y899923D02*
X566052Y899741D01*
X565522Y900271D01*
X565704Y900655D01*
X565846Y900796D01*
X566577Y900065D01*
X566436Y899923D01*
G37*
G36*
G01X565120Y898409D02*
X565504Y898591D01*
X566034Y898061D01*
X565852Y897677D01*
X565710Y897536D01*
X564978Y898268D01*
X565120Y898409D01*
G37*
G36*
G01X564738Y898225D02*
X564354Y898043D01*
X563824Y898573D01*
X564006Y898957D01*
X564148Y899098D01*
X564879Y898367D01*
X564738Y898225D01*
G37*
G36*
G01X563458Y900071D02*
X563842Y900253D01*
X564372Y899722D01*
X564190Y899339D01*
X564049Y899197D01*
X563317Y899929D01*
X563458Y900071D01*
G37*
G36*
G01X563076Y899887D02*
X562693Y899705D01*
X562162Y900235D01*
X562345Y900619D01*
X562486Y900760D01*
X563218Y900028D01*
X563076Y899887D01*
G37*
G36*
G01X565587Y899074D02*
X565203Y898892D01*
X564673Y899422D01*
X564855Y899806D01*
X564997Y899947D01*
X565728Y899216D01*
X565587Y899074D01*
G37*
G36*
G01X564307Y900920D02*
X564691Y901102D01*
X565221Y900571D01*
X565039Y900188D01*
X564898Y900046D01*
X564166Y900778D01*
X564307Y900920D01*
G37*
G36*
G01X565628Y885724D02*
X566028Y885581D01*
Y884831D01*
X565628Y884689D01*
X565428D01*
Y885724D01*
X565628D01*
G37*
G36*
G01Y890424D02*
X566028Y890281D01*
Y889531D01*
X565628Y889389D01*
X565428D01*
Y890424D01*
X565628D01*
G37*
G36*
G01X565228Y888214D02*
X564828Y888357D01*
Y889107D01*
X565228Y889249D01*
X565428D01*
Y888214D01*
X565228D01*
G37*
G36*
G01Y890564D02*
X564828Y890707D01*
Y891457D01*
X565228Y891599D01*
X565428D01*
Y890564D01*
X565228D01*
G37*
G36*
G01Y885864D02*
X564828Y886007D01*
Y886757D01*
X565228Y886899D01*
X565428D01*
Y885864D01*
X565228D01*
G37*
G36*
G01X565628Y888074D02*
X566028Y887931D01*
Y887181D01*
X565628Y887039D01*
X565428D01*
Y888074D01*
X565628D01*
G37*
G36*
G01X560947Y900883D02*
X561331Y901065D01*
X561861Y900535D01*
X561679Y900151D01*
X561538Y900010D01*
X560806Y900742D01*
X560947Y900883D01*
G37*
G36*
G01X565628Y895124D02*
X566028Y894981D01*
Y894231D01*
X565628Y894089D01*
X565428D01*
Y895124D01*
X565628D01*
G37*
G36*
G01X564271Y897560D02*
X564655Y897742D01*
X565185Y897212D01*
X565003Y896828D01*
X564861Y896687D01*
X564129Y897419D01*
X564271Y897560D01*
G37*
G36*
G01X562609Y899222D02*
X562993Y899404D01*
X563523Y898873D01*
X563341Y898490D01*
X563200Y898348D01*
X562468Y899080D01*
X562609Y899222D01*
G37*
G36*
G01X565628Y892774D02*
X566028Y892631D01*
Y891881D01*
X565628Y891739D01*
X565428D01*
Y892774D01*
X565628D01*
G37*
G36*
G01X565228Y892914D02*
X564828Y893057D01*
Y893807D01*
X565228Y893949D01*
X565428D01*
Y892914D01*
X565228D01*
G37*
G36*
G01X563428Y885724D02*
X563828Y885581D01*
Y884831D01*
X563428Y884689D01*
X563228D01*
Y885724D01*
X563428D01*
G37*
G36*
G01X563028Y885864D02*
X562628Y886007D01*
Y886757D01*
X563028Y886899D01*
X563228D01*
Y885864D01*
X563028D01*
G37*
G36*
G01X561028Y885724D02*
X561428Y885581D01*
Y884831D01*
X561028Y884689D01*
X560828D01*
Y885724D01*
X561028D01*
G37*
G36*
G01X560628Y885864D02*
X560228Y886007D01*
Y886757D01*
X560628Y886899D01*
X560828D01*
Y885864D01*
X560628D01*
G37*
G36*
G01X562228Y885724D02*
X562628Y885581D01*
Y884831D01*
X562228Y884689D01*
X562028D01*
Y885724D01*
X562228D01*
G37*
G36*
G01X561828Y885864D02*
X561428Y886007D01*
Y886757D01*
X561828Y886899D01*
X562028D01*
Y885864D01*
X561828D01*
G37*
G36*
G01X559828Y885724D02*
X560228Y885581D01*
Y884831D01*
X559828Y884689D01*
X559628D01*
Y885724D01*
X559828D01*
G37*
G36*
G01X559428Y885864D02*
X559028Y886007D01*
Y886757D01*
X559428Y886899D01*
X559628D01*
Y885864D01*
X559428D01*
G37*
G36*
G01X553428Y884295D02*
X553028Y884437D01*
Y885187D01*
X553428Y885330D01*
X553628D01*
Y884295D01*
X553428D01*
G37*
G36*
G01X551028D02*
X550628Y884437D01*
Y885187D01*
X551028Y885330D01*
X551228D01*
Y884295D01*
X551028D01*
G37*
G36*
G01X552228D02*
X551828Y884437D01*
Y885187D01*
X552228Y885330D01*
X552428D01*
Y884295D01*
X552228D01*
G37*
G36*
G01X564916Y915029D02*
X564533Y914847D01*
X564003Y915377D01*
X564185Y915761D01*
X564326Y915902D01*
X565058Y915170D01*
X564916Y915029D01*
G37*
G36*
G01X565298Y915213D02*
X565682Y915395D01*
X566212Y914864D01*
X566030Y914481D01*
X565889Y914339D01*
X565157Y915071D01*
X565298Y915213D01*
G37*
G36*
G01X563255Y916690D02*
X562871Y916508D01*
X562341Y917039D01*
X562523Y917422D01*
X562664Y917564D01*
X563396Y916832D01*
X563255Y916690D01*
G37*
G36*
G01X563637Y916874D02*
X564020Y917056D01*
X564551Y916526D01*
X564368Y916142D01*
X564227Y916001D01*
X563495Y916733D01*
X563637Y916874D01*
G37*
G36*
G01X566542Y910007D02*
X566158Y909825D01*
X565628Y910356D01*
X565810Y910739D01*
X565951Y910881D01*
X566683Y910149D01*
X566542Y910007D01*
G37*
G36*
G01X561557Y914992D02*
X561173Y914810D01*
X560643Y915341D01*
X560825Y915724D01*
X560966Y915866D01*
X561698Y915134D01*
X561557Y914992D01*
G37*
G36*
G01X560277Y916838D02*
X560660Y917020D01*
X561191Y916490D01*
X561009Y916106D01*
X560867Y915965D01*
X560135Y916697D01*
X560277Y916838D01*
G37*
G36*
G01X563218Y913331D02*
X562835Y913149D01*
X562305Y913679D01*
X562487Y914063D01*
X562628Y914204D01*
X563360Y913472D01*
X563218Y913331D01*
G37*
G36*
G01X563600Y913515D02*
X563984Y913697D01*
X564514Y913166D01*
X564332Y912783D01*
X564191Y912641D01*
X563459Y913373D01*
X563600Y913515D01*
G37*
G36*
G01X561939Y915176D02*
X562322Y915358D01*
X562853Y914828D01*
X562670Y914444D01*
X562529Y914303D01*
X561797Y915035D01*
X561939Y915176D01*
G37*
G36*
G01X559895Y916654D02*
X559511Y916472D01*
X558981Y917002D01*
X559163Y917386D01*
X559305Y917527D01*
X560036Y916796D01*
X559895Y916654D01*
G37*
G36*
G01X564880Y911669D02*
X564497Y911487D01*
X563966Y912017D01*
X564148Y912401D01*
X564290Y912542D01*
X565022Y911810D01*
X564880Y911669D01*
G37*
G36*
G01X565262Y911853D02*
X565646Y912035D01*
X566176Y911505D01*
X565994Y911121D01*
X565852Y910980D01*
X565121Y911711D01*
X565262Y911853D01*
G37*
G36*
G01X564067Y914180D02*
X563684Y913998D01*
X563154Y914528D01*
X563336Y914912D01*
X563477Y915053D01*
X564209Y914321D01*
X564067Y914180D01*
G37*
G36*
G01X565729Y912518D02*
X565346Y912336D01*
X564815Y912866D01*
X564997Y913250D01*
X565139Y913391D01*
X565871Y912659D01*
X565729Y912518D01*
G37*
G36*
G01X564449Y914364D02*
X564833Y914546D01*
X565363Y914015D01*
X565181Y913632D01*
X565040Y913490D01*
X564308Y914222D01*
X564449Y914364D01*
G37*
G36*
G01X562788Y916025D02*
X563171Y916207D01*
X563702Y915677D01*
X563519Y915293D01*
X563378Y915152D01*
X562646Y915884D01*
X562788Y916025D01*
G37*
G36*
G01X562406Y915841D02*
X562022Y915659D01*
X561492Y916190D01*
X561674Y916573D01*
X561815Y916715D01*
X562547Y915983D01*
X562406Y915841D01*
G37*
G36*
G01X559046Y915805D02*
X558662Y915623D01*
X558132Y916153D01*
X558314Y916537D01*
X558456Y916678D01*
X559187Y915947D01*
X559046Y915805D01*
G37*
G36*
G01X557766Y917651D02*
X558150Y917833D01*
X558680Y917302D01*
X558498Y916919D01*
X558357Y916777D01*
X557625Y917509D01*
X557766Y917651D01*
G37*
G36*
G01X564413Y911004D02*
X564797Y911186D01*
X565327Y910656D01*
X565145Y910272D01*
X565003Y910131D01*
X564272Y910862D01*
X564413Y911004D01*
G37*
G36*
G01X561090Y914327D02*
X561473Y914509D01*
X562004Y913979D01*
X561821Y913595D01*
X561680Y913454D01*
X560948Y914186D01*
X561090Y914327D01*
G37*
G36*
G01X562369Y912482D02*
X561986Y912300D01*
X561456Y912830D01*
X561638Y913214D01*
X561779Y913355D01*
X562511Y912623D01*
X562369Y912482D01*
G37*
G36*
G01X560708Y914143D02*
X560324Y913961D01*
X559794Y914492D01*
X559976Y914875D01*
X560117Y915017D01*
X560849Y914285D01*
X560708Y914143D01*
G37*
G36*
G01X559428Y915989D02*
X559811Y916171D01*
X560342Y915641D01*
X560160Y915257D01*
X560018Y915116D01*
X559286Y915848D01*
X559428Y915989D01*
G37*
G36*
G01X564031Y910820D02*
X563648Y910638D01*
X563117Y911168D01*
X563299Y911552D01*
X563441Y911693D01*
X564173Y910961D01*
X564031Y910820D01*
G37*
G36*
G01X562751Y912666D02*
X563135Y912848D01*
X563665Y912317D01*
X563483Y911934D01*
X563342Y911792D01*
X562610Y912524D01*
X562751Y912666D01*
G37*
G36*
G01X565693Y909158D02*
X565309Y908976D01*
X564779Y909507D01*
X564961Y909890D01*
X565102Y910032D01*
X565834Y909300D01*
X565693Y909158D01*
G37*
G36*
G01X558509Y908415D02*
X558893Y908598D01*
X559423Y908067D01*
X559241Y907684D01*
X559100Y907542D01*
X558368Y908274D01*
X558509Y908415D01*
G37*
G36*
G01X556848Y910077D02*
X557231Y910259D01*
X557762Y909729D01*
X557580Y909345D01*
X557438Y909204D01*
X556706Y909936D01*
X556848Y910077D01*
G37*
G36*
G01X559789Y906570D02*
X559406Y906388D01*
X558875Y906918D01*
X559057Y907302D01*
X559199Y907443D01*
X559931Y906711D01*
X559789Y906570D01*
G37*
G36*
G01X558128Y908232D02*
X557744Y908050D01*
X557214Y908580D01*
X557396Y908963D01*
X557537Y909105D01*
X558269Y908373D01*
X558128Y908232D01*
G37*
G36*
G01X556466Y909893D02*
X556082Y909711D01*
X555552Y910242D01*
X555734Y910625D01*
X555875Y910767D01*
X556607Y910035D01*
X556466Y909893D01*
G37*
G36*
G01X565156Y901769D02*
X565540Y901951D01*
X566070Y901420D01*
X565888Y901037D01*
X565747Y900895D01*
X565015Y901627D01*
X565156Y901769D01*
G37*
G36*
G01X564774Y901585D02*
X564391Y901403D01*
X563860Y901933D01*
X564043Y902317D01*
X564184Y902458D01*
X564916Y901726D01*
X564774Y901585D01*
G37*
G36*
G01X560171Y906754D02*
X560555Y906936D01*
X561085Y906406D01*
X560903Y906022D01*
X560762Y905880D01*
X560030Y906612D01*
X560171Y906754D01*
G37*
G36*
G01X561451Y904908D02*
X561067Y904726D01*
X560537Y905256D01*
X560719Y905640D01*
X560861Y905781D01*
X561592Y905050D01*
X561451Y904908D01*
G37*
G36*
G01X561833Y905092D02*
X562216Y905274D01*
X562747Y904744D01*
X562565Y904360D01*
X562423Y904219D01*
X561691Y904951D01*
X561833Y905092D01*
G37*
G36*
G01X563494Y903430D02*
X563878Y903612D01*
X564408Y903082D01*
X564226Y902698D01*
X564085Y902557D01*
X563353Y903289D01*
X563494Y903430D01*
G37*
G36*
G01X563113Y903247D02*
X562729Y903064D01*
X562199Y903595D01*
X562381Y903978D01*
X562522Y904120D01*
X563254Y903388D01*
X563113Y903247D01*
G37*
G36*
G01X556811Y906717D02*
X557195Y906900D01*
X557725Y906369D01*
X557543Y905986D01*
X557402Y905844D01*
X556670Y906576D01*
X556811Y906717D01*
G37*
G36*
G01X556430Y906534D02*
X556046Y906352D01*
X555516Y906882D01*
X555698Y907265D01*
X555839Y907407D01*
X556571Y906675D01*
X556430Y906534D01*
G37*
G36*
G01X555150Y908379D02*
X555533Y908561D01*
X556064Y908031D01*
X555882Y907647D01*
X555740Y907506D01*
X555008Y908238D01*
X555150Y908379D01*
G37*
G36*
G01X558091Y904872D02*
X557708Y904690D01*
X557177Y905220D01*
X557359Y905604D01*
X557501Y905745D01*
X558233Y905013D01*
X558091Y904872D01*
G37*
G36*
G01X559753Y903210D02*
X559369Y903028D01*
X558839Y903558D01*
X559021Y903942D01*
X559163Y904083D01*
X559894Y903352D01*
X559753Y903210D01*
G37*
G36*
G01X558473Y905056D02*
X558857Y905238D01*
X559387Y904708D01*
X559205Y904324D01*
X559064Y904182D01*
X558332Y904914D01*
X558473Y905056D01*
G37*
G36*
G01X561415Y901549D02*
X561031Y901366D01*
X560501Y901897D01*
X560683Y902280D01*
X560824Y902422D01*
X561556Y901690D01*
X561415Y901549D01*
G37*
G36*
G01X561796Y901732D02*
X562180Y901914D01*
X562710Y901384D01*
X562528Y901000D01*
X562387Y900859D01*
X561655Y901591D01*
X561796Y901732D01*
G37*
G36*
G01X560135Y903394D02*
X560518Y903576D01*
X561049Y903046D01*
X560867Y902662D01*
X560725Y902521D01*
X559993Y903253D01*
X560135Y903394D01*
G37*
G36*
G01X557660Y907566D02*
X558044Y907749D01*
X558574Y907218D01*
X558392Y906835D01*
X558251Y906693D01*
X557519Y907425D01*
X557660Y907566D01*
G37*
G36*
G01X557279Y907383D02*
X556895Y907201D01*
X556365Y907731D01*
X556547Y908114D01*
X556688Y908256D01*
X557420Y907524D01*
X557279Y907383D01*
G37*
G36*
G01X555999Y909228D02*
X556382Y909410D01*
X556913Y908880D01*
X556731Y908496D01*
X556589Y908355D01*
X555857Y909087D01*
X555999Y909228D01*
G37*
G36*
G01X558940Y905721D02*
X558557Y905539D01*
X558026Y906069D01*
X558208Y906453D01*
X558350Y906594D01*
X559082Y905862D01*
X558940Y905721D01*
G37*
G36*
G01X563925Y900736D02*
X563542Y900554D01*
X563011Y901084D01*
X563194Y901468D01*
X563335Y901609D01*
X564067Y900877D01*
X563925Y900736D01*
G37*
G36*
G01X560602Y904059D02*
X560218Y903877D01*
X559688Y904407D01*
X559870Y904791D01*
X560012Y904932D01*
X560743Y904201D01*
X560602Y904059D01*
G37*
G36*
G01X560984Y904243D02*
X561367Y904425D01*
X561898Y903895D01*
X561716Y903511D01*
X561574Y903370D01*
X560842Y904102D01*
X560984Y904243D01*
G37*
G36*
G01X559322Y905905D02*
X559706Y906087D01*
X560236Y905557D01*
X560054Y905173D01*
X559913Y905031D01*
X559181Y905763D01*
X559322Y905905D01*
G37*
G36*
G01X562264Y902398D02*
X561880Y902215D01*
X561350Y902746D01*
X561532Y903129D01*
X561673Y903271D01*
X562405Y902539D01*
X562264Y902398D01*
G37*
G36*
G01X562645Y902581D02*
X563029Y902763D01*
X563559Y902233D01*
X563377Y901849D01*
X563236Y901708D01*
X562504Y902440D01*
X562645Y902581D01*
G37*
G36*
G01X554301Y907530D02*
X554684Y907712D01*
X555215Y907182D01*
X555033Y906798D01*
X554891Y906657D01*
X554159Y907389D01*
X554301Y907530D01*
G37*
G36*
G01X557624Y904207D02*
X558008Y904389D01*
X558538Y903859D01*
X558356Y903475D01*
X558215Y903333D01*
X557483Y904065D01*
X557624Y904207D01*
G37*
G36*
G01X555581Y905685D02*
X555197Y905503D01*
X554667Y906033D01*
X554849Y906416D01*
X554990Y906558D01*
X555722Y905826D01*
X555581Y905685D01*
G37*
G36*
G01X557242Y904023D02*
X556859Y903841D01*
X556328Y904371D01*
X556510Y904755D01*
X556652Y904896D01*
X557384Y904164D01*
X557242Y904023D01*
G37*
G36*
G01X555962Y905868D02*
X556346Y906051D01*
X556876Y905520D01*
X556694Y905137D01*
X556553Y904995D01*
X555821Y905727D01*
X555962Y905868D01*
G37*
G36*
G01X559286Y902545D02*
X559669Y902727D01*
X560200Y902197D01*
X560018Y901813D01*
X559876Y901672D01*
X559144Y902404D01*
X559286Y902545D01*
G37*
G36*
G01X565431Y931984D02*
X565814Y932166D01*
X566345Y931636D01*
X566163Y931252D01*
X566021Y931111D01*
X565289Y931843D01*
X565431Y931984D01*
G37*
G36*
G01X565049Y931800D02*
X564665Y931618D01*
X564135Y932148D01*
X564317Y932532D01*
X564458Y932673D01*
X565190Y931942D01*
X565049Y931800D01*
G37*
G36*
G01X563769Y933646D02*
X564153Y933828D01*
X564683Y933298D01*
X564501Y932914D01*
X564360Y932773D01*
X563628Y933504D01*
X563769Y933646D01*
G37*
G36*
G01X561197Y927728D02*
X561580Y927910D01*
X562111Y927380D01*
X561929Y926996D01*
X561787Y926855D01*
X561055Y927587D01*
X561197Y927728D01*
G37*
G36*
G01X560815Y927544D02*
X560431Y927362D01*
X559901Y927892D01*
X560083Y928276D01*
X560225Y928417D01*
X560956Y927686D01*
X560815Y927544D01*
G37*
G36*
G01X564520Y924405D02*
X564904Y924587D01*
X565434Y924056D01*
X565252Y923673D01*
X565111Y923531D01*
X564379Y924263D01*
X564520Y924405D01*
G37*
G36*
G01X565800Y922559D02*
X565416Y922377D01*
X564886Y922907D01*
X565068Y923291D01*
X565210Y923432D01*
X565941Y922701D01*
X565800Y922559D01*
G37*
G36*
G01X564138Y924221D02*
X563755Y924039D01*
X563224Y924569D01*
X563406Y924953D01*
X563548Y925094D01*
X564280Y924362D01*
X564138Y924221D01*
G37*
G36*
G01X562858Y926066D02*
X563242Y926248D01*
X563772Y925718D01*
X563590Y925334D01*
X563449Y925193D01*
X562717Y925925D01*
X562858Y926066D01*
G37*
G36*
G01X562477Y925883D02*
X562093Y925700D01*
X561563Y926231D01*
X561745Y926614D01*
X561886Y926756D01*
X562618Y926024D01*
X562477Y925883D01*
G37*
G36*
G01X559117Y925846D02*
X558733Y925664D01*
X558203Y926194D01*
X558385Y926578D01*
X558527Y926719D01*
X559258Y925988D01*
X559117Y925846D01*
G37*
G36*
G01X560779Y924185D02*
X560395Y924002D01*
X559865Y924533D01*
X560047Y924916D01*
X560188Y925058D01*
X560920Y924326D01*
X560779Y924185D01*
G37*
G36*
G01X561160Y924368D02*
X561544Y924550D01*
X562074Y924020D01*
X561892Y923636D01*
X561751Y923495D01*
X561019Y924227D01*
X561160Y924368D01*
G37*
G36*
G01X559499Y926030D02*
X559882Y926212D01*
X560413Y925682D01*
X560231Y925298D01*
X560089Y925157D01*
X559357Y925889D01*
X559499Y926030D01*
G37*
G36*
G01X562440Y922523D02*
X562057Y922341D01*
X561526Y922871D01*
X561708Y923255D01*
X561850Y923396D01*
X562582Y922664D01*
X562440Y922523D01*
G37*
G36*
G01X562822Y922707D02*
X563206Y922889D01*
X563736Y922358D01*
X563554Y921975D01*
X563413Y921833D01*
X562681Y922565D01*
X562822Y922707D01*
G37*
G36*
G01X565764Y919199D02*
X565380Y919017D01*
X564850Y919548D01*
X565032Y919931D01*
X565173Y920073D01*
X565905Y919341D01*
X565764Y919199D01*
G37*
G36*
G01X564102Y920861D02*
X563718Y920679D01*
X563188Y921209D01*
X563370Y921593D01*
X563512Y921734D01*
X564243Y921003D01*
X564102Y920861D01*
G37*
G36*
G01X564484Y921045D02*
X564867Y921227D01*
X565398Y920697D01*
X565216Y920313D01*
X565074Y920172D01*
X564342Y920904D01*
X564484Y921045D01*
G37*
G36*
G01X558686Y928541D02*
X559070Y928723D01*
X559600Y928193D01*
X559418Y927809D01*
X559277Y927667D01*
X558545Y928399D01*
X558686Y928541D01*
G37*
G36*
G01X562009Y925217D02*
X562393Y925399D01*
X562923Y924869D01*
X562741Y924485D01*
X562600Y924344D01*
X561868Y925076D01*
X562009Y925217D01*
G37*
G36*
G01X565333Y921894D02*
X565716Y922076D01*
X566247Y921546D01*
X566065Y921162D01*
X565923Y921021D01*
X565191Y921753D01*
X565333Y921894D01*
G37*
G36*
G01X561628Y925034D02*
X561244Y924851D01*
X560714Y925382D01*
X560896Y925765D01*
X561037Y925907D01*
X561769Y925175D01*
X561628Y925034D01*
G37*
G36*
G01X559966Y926695D02*
X559582Y926513D01*
X559052Y927043D01*
X559234Y927427D01*
X559376Y927568D01*
X560107Y926837D01*
X559966Y926695D01*
G37*
G36*
G01X560348Y926879D02*
X560731Y927061D01*
X561262Y926531D01*
X561080Y926147D01*
X560938Y926006D01*
X560206Y926738D01*
X560348Y926879D01*
G37*
G36*
G01X564951Y921710D02*
X564567Y921528D01*
X564037Y922058D01*
X564219Y922442D01*
X564361Y922583D01*
X565092Y921852D01*
X564951Y921710D01*
G37*
G36*
G01X563289Y923372D02*
X562906Y923190D01*
X562375Y923720D01*
X562557Y924104D01*
X562699Y924245D01*
X563431Y923513D01*
X563289Y923372D01*
G37*
G36*
G01X563671Y923556D02*
X564055Y923738D01*
X564585Y923207D01*
X564403Y922824D01*
X564262Y922682D01*
X563530Y923414D01*
X563671Y923556D01*
G37*
G36*
G01X558268Y924997D02*
X557884Y924815D01*
X557354Y925345D01*
X557536Y925729D01*
X557678Y925870D01*
X558409Y925139D01*
X558268Y924997D01*
G37*
G36*
G01X558650Y925181D02*
X559033Y925363D01*
X559564Y924833D01*
X559382Y924449D01*
X559240Y924308D01*
X558508Y925040D01*
X558650Y925181D01*
G37*
G36*
G01X565297Y918534D02*
X565680Y918716D01*
X566211Y918186D01*
X566028Y917802D01*
X565887Y917661D01*
X565155Y918393D01*
X565297Y918534D01*
G37*
G36*
G01X563253Y920012D02*
X562869Y919830D01*
X562339Y920360D01*
X562521Y920744D01*
X562663Y920885D01*
X563394Y920154D01*
X563253Y920012D01*
G37*
G36*
G01X563635Y920196D02*
X564018Y920378D01*
X564549Y919848D01*
X564367Y919464D01*
X564225Y919323D01*
X563493Y920055D01*
X563635Y920196D01*
G37*
G36*
G01X561973Y921858D02*
X562357Y922040D01*
X562887Y921509D01*
X562705Y921126D01*
X562564Y920984D01*
X561832Y921716D01*
X561973Y921858D01*
G37*
G36*
G01X564915Y918350D02*
X564531Y918168D01*
X564001Y918699D01*
X564183Y919082D01*
X564324Y919224D01*
X565056Y918492D01*
X564915Y918350D01*
G37*
G36*
G01X561591Y921674D02*
X561208Y921492D01*
X560677Y922022D01*
X560859Y922406D01*
X561001Y922547D01*
X561733Y921815D01*
X561591Y921674D01*
G37*
G36*
G01X559930Y923336D02*
X559546Y923153D01*
X559016Y923684D01*
X559198Y924067D01*
X559339Y924209D01*
X560071Y923477D01*
X559930Y923336D01*
G37*
G36*
G01X560311Y923519D02*
X560695Y923701D01*
X561225Y923171D01*
X561043Y922787D01*
X560902Y922646D01*
X560170Y923378D01*
X560311Y923519D01*
G37*
G36*
G01X556608Y923337D02*
X556224Y923155D01*
X555694Y923685D01*
X555876Y924069D01*
X556018Y924210D01*
X556749Y923479D01*
X556608Y923337D01*
G37*
G36*
G01X558270Y921676D02*
X557886Y921493D01*
X557356Y922024D01*
X557538Y922407D01*
X557679Y922549D01*
X558411Y921817D01*
X558270Y921676D01*
G37*
G36*
G01X556990Y923521D02*
X557373Y923703D01*
X557904Y923173D01*
X557722Y922789D01*
X557580Y922648D01*
X556848Y923380D01*
X556990Y923521D01*
G37*
G36*
G01X558651Y921859D02*
X559035Y922041D01*
X559565Y921511D01*
X559383Y921127D01*
X559242Y920986D01*
X558510Y921718D01*
X558651Y921859D01*
G37*
G36*
G01X561975Y918536D02*
X562358Y918718D01*
X562889Y918188D01*
X562707Y917804D01*
X562565Y917663D01*
X561833Y918395D01*
X561975Y918536D01*
G37*
G36*
G01X560313Y920198D02*
X560697Y920380D01*
X561227Y919849D01*
X561045Y919466D01*
X560904Y919324D01*
X560172Y920056D01*
X560313Y920198D01*
G37*
G36*
G01X559931Y920014D02*
X559548Y919832D01*
X559017Y920362D01*
X559199Y920746D01*
X559341Y920887D01*
X560073Y920155D01*
X559931Y920014D01*
G37*
G36*
G01X561593Y918352D02*
X561209Y918170D01*
X560679Y918700D01*
X560861Y919084D01*
X561003Y919225D01*
X561734Y918494D01*
X561593Y918352D01*
G37*
G36*
G01X558615Y918500D02*
X558999Y918682D01*
X559529Y918151D01*
X559347Y917768D01*
X559206Y917626D01*
X558474Y918358D01*
X558615Y918500D01*
G37*
G36*
G01X556953Y920161D02*
X557337Y920343D01*
X557867Y919813D01*
X557685Y919429D01*
X557544Y919288D01*
X556812Y920020D01*
X556953Y920161D01*
G37*
G36*
G01X558233Y918316D02*
X557850Y918134D01*
X557319Y918664D01*
X557501Y919048D01*
X557643Y919189D01*
X558375Y918457D01*
X558233Y918316D01*
G37*
G36*
G01X556572Y919978D02*
X556188Y919795D01*
X555658Y920326D01*
X555840Y920709D01*
X555981Y920851D01*
X556713Y920119D01*
X556572Y919978D01*
G37*
G36*
G01X555292Y921823D02*
X555675Y922005D01*
X556206Y921475D01*
X556024Y921091D01*
X555882Y920950D01*
X555150Y921682D01*
X555292Y921823D01*
G37*
G36*
G01X559082Y919165D02*
X558699Y918983D01*
X558168Y919513D01*
X558350Y919897D01*
X558492Y920038D01*
X559224Y919306D01*
X559082Y919165D01*
G37*
G36*
G01X557802Y921010D02*
X558186Y921192D01*
X558716Y920662D01*
X558534Y920278D01*
X558393Y920137D01*
X557661Y920869D01*
X557802Y921010D01*
G37*
G36*
G01X557421Y920827D02*
X557037Y920644D01*
X556507Y921175D01*
X556689Y921558D01*
X556830Y921700D01*
X557562Y920968D01*
X557421Y920827D01*
G37*
G36*
G01X556141Y922672D02*
X556524Y922854D01*
X557055Y922324D01*
X556873Y921940D01*
X556731Y921799D01*
X555999Y922531D01*
X556141Y922672D01*
G37*
G36*
G01X561126Y917687D02*
X561509Y917869D01*
X562040Y917339D01*
X561858Y916955D01*
X561716Y916814D01*
X560984Y917546D01*
X561126Y917687D01*
G37*
G36*
G01X560744Y917503D02*
X560360Y917321D01*
X559830Y917851D01*
X560012Y918235D01*
X560154Y918376D01*
X560885Y917645D01*
X560744Y917503D01*
G37*
G36*
G01X559464Y919349D02*
X559848Y919531D01*
X560378Y919000D01*
X560196Y918617D01*
X560055Y918475D01*
X559323Y919207D01*
X559464Y919349D01*
G37*
G36*
G01X557384Y917467D02*
X557001Y917285D01*
X556470Y917815D01*
X556652Y918199D01*
X556794Y918340D01*
X557526Y917608D01*
X557384Y917467D01*
G37*
G36*
G01X555723Y919129D02*
X555339Y918946D01*
X554809Y919477D01*
X554991Y919860D01*
X555132Y920002D01*
X555864Y919270D01*
X555723Y919129D01*
G37*
G36*
G01X556104Y919312D02*
X556488Y919494D01*
X557018Y918964D01*
X556836Y918580D01*
X556695Y918439D01*
X555963Y919171D01*
X556104Y919312D01*
G37*
G36*
G01X565898Y932650D02*
X565515Y932467D01*
X564984Y932998D01*
X565166Y933381D01*
X565308Y933523D01*
X566040Y932791D01*
X565898Y932650D01*
G37*
G36*
G01X561793Y945910D02*
X561936Y946310D01*
X562686D01*
X562828Y945910D01*
Y945710D01*
X561793D01*
Y945910D01*
G37*
G36*
G01X564003Y945510D02*
X563860Y945110D01*
X563110D01*
X562968Y945510D01*
Y945710D01*
X564003D01*
Y945510D01*
G37*
G36*
G01X565538Y945385D02*
X565922Y945567D01*
X566452Y945037D01*
X566270Y944654D01*
X566129Y944512D01*
X565397Y945244D01*
X565538Y945385D01*
G37*
G36*
G01X561653Y945510D02*
X561510Y945110D01*
X560760D01*
X560618Y945510D01*
Y945710D01*
X561653D01*
Y945510D01*
G37*
G36*
G01X559443Y943510D02*
X559586Y943910D01*
X560336D01*
X560478Y943510D01*
Y943310D01*
X559443D01*
Y943510D01*
G37*
G36*
G01X561653Y943110D02*
X561510Y942710D01*
X560760D01*
X560618Y943110D01*
Y943310D01*
X561653D01*
Y943110D01*
G37*
G36*
G01X565120Y941842D02*
X564737Y941660D01*
X564206Y942190D01*
X564388Y942574D01*
X564530Y942715D01*
X565262Y941983D01*
X565120Y941842D01*
G37*
G36*
G01X561793Y943510D02*
X561936Y943910D01*
X562686D01*
X562828Y943510D01*
Y943310D01*
X561793D01*
Y943510D01*
G37*
G36*
G01X565502Y942026D02*
X565886Y942208D01*
X566416Y941677D01*
X566234Y941294D01*
X566093Y941152D01*
X565361Y941884D01*
X565502Y942026D01*
G37*
G36*
G01X561793Y944710D02*
X561936Y945110D01*
X562686D01*
X562828Y944710D01*
Y944510D01*
X561793D01*
Y944710D01*
G37*
G36*
G01X559443D02*
X559586Y945110D01*
X560336D01*
X560478Y944710D01*
Y944510D01*
X559443D01*
Y944710D01*
G37*
G36*
G01X561653Y944310D02*
X561510Y943910D01*
X560760D01*
X560618Y944310D01*
Y944510D01*
X561653D01*
Y944310D01*
G37*
G36*
G01X565969Y942691D02*
X565586Y942509D01*
X565055Y943039D01*
X565237Y943423D01*
X565379Y943564D01*
X566111Y942832D01*
X565969Y942691D01*
G37*
G36*
G01X559303Y941910D02*
X559160Y941510D01*
X558410D01*
X558268Y941910D01*
Y942110D01*
X559303D01*
Y941910D01*
G37*
G36*
G01X559443Y942310D02*
X559586Y942710D01*
X560336D01*
X560478Y942310D01*
Y942110D01*
X559443D01*
Y942310D01*
G37*
G36*
G01X561793D02*
X561936Y942710D01*
X562686D01*
X562828Y942310D01*
Y942110D01*
X561793D01*
Y942310D01*
G37*
G36*
G01X565933Y939331D02*
X565549Y939149D01*
X565019Y939679D01*
X565201Y940063D01*
X565343Y940204D01*
X566074Y939473D01*
X565933Y939331D01*
G37*
G36*
G01X564653Y941177D02*
X565037Y941359D01*
X565567Y940828D01*
X565385Y940445D01*
X565244Y940303D01*
X564512Y941035D01*
X564653Y941177D01*
G37*
G36*
G01X561653Y941910D02*
X561510Y941510D01*
X560760D01*
X560618Y941910D01*
Y942110D01*
X561653D01*
Y941910D01*
G37*
G36*
G01X557281Y938909D02*
X557424Y939309D01*
X558174D01*
X558316Y938909D01*
Y938709D01*
X557281D01*
Y938909D01*
G37*
G36*
G01X559491Y938509D02*
X559348Y938109D01*
X558598D01*
X558456Y938509D01*
Y938709D01*
X559491D01*
Y938509D01*
G37*
G36*
G01X557141D02*
X556998Y938109D01*
X556248D01*
X556106Y938509D01*
Y938709D01*
X557141D01*
Y938509D01*
G37*
G36*
G01X565470Y935347D02*
X565854Y935529D01*
X566384Y934999D01*
X566202Y934615D01*
X566061Y934473D01*
X565329Y935205D01*
X565470Y935347D01*
G37*
G36*
G01X559631Y938909D02*
X559774Y939309D01*
X560524D01*
X560666Y938909D01*
Y938709D01*
X559631D01*
Y938909D01*
G37*
G36*
G01X563427Y936825D02*
X563043Y936643D01*
X562513Y937173D01*
X562695Y937556D01*
X562836Y937698D01*
X563568Y936966D01*
X563427Y936825D01*
G37*
G36*
G01X563808Y937008D02*
X564192Y937191D01*
X564722Y936660D01*
X564540Y936277D01*
X564399Y936135D01*
X563667Y936867D01*
X563808Y937008D01*
G37*
G36*
G01X565088Y935163D02*
X564705Y934981D01*
X564174Y935511D01*
X564356Y935895D01*
X564498Y936036D01*
X565230Y935304D01*
X565088Y935163D01*
G37*
G36*
G01X559491Y936109D02*
X559348Y935709D01*
X558598D01*
X558456Y936109D01*
Y936309D01*
X559491D01*
Y936109D01*
G37*
G36*
G01X557141D02*
X556998Y935709D01*
X556248D01*
X556106Y936109D01*
Y936309D01*
X557141D01*
Y936109D01*
G37*
G36*
G01X557281Y936509D02*
X557424Y936909D01*
X558174D01*
X558316Y936509D01*
Y936309D01*
X557281D01*
Y936509D01*
G37*
G36*
G01X563387Y933462D02*
X563004Y933280D01*
X562473Y933810D01*
X562655Y934194D01*
X562797Y934335D01*
X563529Y933603D01*
X563387Y933462D01*
G37*
G36*
G01X562107Y935307D02*
X562491Y935490D01*
X563021Y934959D01*
X562839Y934576D01*
X562698Y934434D01*
X561966Y935166D01*
X562107Y935307D01*
G37*
G36*
G01X557281Y940109D02*
X557424Y940509D01*
X558174D01*
X558316Y940109D01*
Y939909D01*
X557281D01*
Y940109D01*
G37*
G36*
G01X559491Y939709D02*
X559348Y939309D01*
X558598D01*
X558456Y939709D01*
Y939909D01*
X559491D01*
Y939709D01*
G37*
G36*
G01X559631Y940109D02*
X559774Y940509D01*
X560524D01*
X560666Y940109D01*
Y939909D01*
X559631D01*
Y940109D01*
G37*
G36*
G01X562996Y939520D02*
X563380Y939702D01*
X563910Y939171D01*
X563728Y938788D01*
X563587Y938646D01*
X562855Y939378D01*
X562996Y939520D01*
G37*
G36*
G01X564658Y937858D02*
X565041Y938040D01*
X565572Y937510D01*
X565390Y937126D01*
X565248Y936985D01*
X564516Y937717D01*
X564658Y937858D01*
G37*
G36*
G01X565938Y936012D02*
X565554Y935830D01*
X565024Y936361D01*
X565206Y936744D01*
X565347Y936886D01*
X566079Y936154D01*
X565938Y936012D01*
G37*
G36*
G01X564276Y937674D02*
X563892Y937492D01*
X563362Y938022D01*
X563544Y938406D01*
X563686Y938547D01*
X564417Y937816D01*
X564276Y937674D01*
G37*
G36*
G01X564618Y934495D02*
X565002Y934677D01*
X565532Y934147D01*
X565350Y933763D01*
X565209Y933622D01*
X564477Y934354D01*
X564618Y934495D01*
G37*
G36*
G01X564237Y934311D02*
X563853Y934129D01*
X563323Y934659D01*
X563505Y935043D01*
X563646Y935184D01*
X564378Y934453D01*
X564237Y934311D01*
G37*
G36*
G01X562575Y935973D02*
X562191Y935791D01*
X561661Y936321D01*
X561843Y936705D01*
X561984Y936846D01*
X562716Y936114D01*
X562575Y935973D01*
G37*
G36*
G01X559631Y937709D02*
X559774Y938109D01*
X560524D01*
X560666Y937709D01*
Y937509D01*
X559631D01*
Y937709D01*
G37*
G36*
G01X562957Y936157D02*
X563340Y936339D01*
X563870Y935808D01*
X563688Y935425D01*
X563547Y935283D01*
X562815Y936015D01*
X562957Y936157D01*
G37*
G36*
G01X555502Y960727D02*
X555885Y960909D01*
X556416Y960379D01*
X556233Y959995D01*
X556092Y959854D01*
X555360Y960586D01*
X555502Y960727D01*
G37*
G36*
G01X555120Y960543D02*
X554736Y960361D01*
X554206Y960892D01*
X554388Y961275D01*
X554529Y961417D01*
X555261Y960685D01*
X555120Y960543D01*
G37*
G36*
G01X556782Y958882D02*
X556398Y958700D01*
X555868Y959230D01*
X556050Y959614D01*
X556191Y959755D01*
X556923Y959023D01*
X556782Y958882D01*
G37*
G36*
G01X558443Y957220D02*
X558060Y957038D01*
X557529Y957568D01*
X557711Y957952D01*
X557853Y958093D01*
X558585Y957361D01*
X558443Y957220D01*
G37*
G36*
G01X557163Y959065D02*
X557547Y959248D01*
X558077Y958717D01*
X557895Y958334D01*
X557754Y958192D01*
X557022Y958924D01*
X557163Y959065D01*
G37*
G36*
G01X558825Y957404D02*
X559209Y957586D01*
X559739Y957056D01*
X559557Y956672D01*
X559415Y956531D01*
X558684Y957262D01*
X558825Y957404D01*
G37*
G36*
G01X560105Y955558D02*
X559721Y955376D01*
X559191Y955906D01*
X559373Y956290D01*
X559514Y956432D01*
X560246Y955700D01*
X560105Y955558D01*
G37*
G36*
G01X563081Y955514D02*
X563224Y955914D01*
X563974D01*
X564116Y955514D01*
Y955314D01*
X563081D01*
Y955514D01*
G37*
G36*
G01X562941Y955114D02*
X562798Y954714D01*
X562048D01*
X561906Y955114D01*
Y955314D01*
X562941D01*
Y955114D01*
G37*
G36*
G01X565291D02*
X565148Y954714D01*
X564398D01*
X564256Y955114D01*
Y955314D01*
X565291D01*
Y955114D01*
G37*
G36*
G01X565431Y955514D02*
X565574Y955914D01*
X566324D01*
X566466Y955514D01*
Y955314D01*
X565431D01*
Y955514D01*
G37*
G36*
G01X553804Y959029D02*
X554187Y959211D01*
X554718Y958681D01*
X554535Y958297D01*
X554394Y958156D01*
X553662Y958888D01*
X553804Y959029D01*
G37*
G36*
G01X557127Y955706D02*
X557511Y955888D01*
X558041Y955358D01*
X557859Y954974D01*
X557717Y954833D01*
X556986Y955564D01*
X557127Y955706D01*
G37*
G36*
G01X555465Y957367D02*
X555849Y957550D01*
X556379Y957019D01*
X556197Y956636D01*
X556056Y956494D01*
X555324Y957226D01*
X555465Y957367D01*
G37*
G36*
G01X556745Y955522D02*
X556362Y955340D01*
X555831Y955870D01*
X556013Y956254D01*
X556155Y956395D01*
X556887Y955663D01*
X556745Y955522D01*
G37*
G36*
G01X555084Y957184D02*
X554700Y957002D01*
X554170Y957532D01*
X554352Y957916D01*
X554493Y958057D01*
X555225Y957325D01*
X555084Y957184D01*
G37*
G36*
G01X558407Y953860D02*
X558023Y953678D01*
X557493Y954208D01*
X557675Y954592D01*
X557816Y954734D01*
X558548Y954002D01*
X558407Y953860D01*
G37*
G36*
G01X562941Y952714D02*
X562798Y952314D01*
X562048D01*
X561906Y952714D01*
Y952914D01*
X562941D01*
Y952714D01*
G37*
G36*
G01X565431Y953114D02*
X565574Y953514D01*
X566324D01*
X566466Y953114D01*
Y952914D01*
X565431D01*
Y953114D01*
G37*
G36*
G01X560731D02*
X560874Y953514D01*
X561624D01*
X561766Y953114D01*
Y952914D01*
X560731D01*
Y953114D01*
G37*
G36*
G01X563081D02*
X563224Y953514D01*
X563974D01*
X564116Y953114D01*
Y952914D01*
X563081D01*
Y953114D01*
G37*
G36*
G01X565291Y952714D02*
X565148Y952314D01*
X564398D01*
X564256Y952714D01*
Y952914D01*
X565291D01*
Y952714D01*
G37*
G36*
G01X556314Y958216D02*
X556698Y958399D01*
X557228Y957868D01*
X557046Y957485D01*
X556905Y957343D01*
X556173Y958075D01*
X556314Y958216D01*
G37*
G36*
G01X554653Y959878D02*
X555036Y960060D01*
X555567Y959530D01*
X555384Y959146D01*
X555243Y959005D01*
X554511Y959737D01*
X554653Y959878D01*
G37*
G36*
G01X557594Y956371D02*
X557211Y956189D01*
X556680Y956719D01*
X556862Y957103D01*
X557004Y957244D01*
X557736Y956512D01*
X557594Y956371D01*
G37*
G36*
G01X559256Y954709D02*
X558872Y954527D01*
X558342Y955057D01*
X558524Y955441D01*
X558665Y955583D01*
X559397Y954851D01*
X559256Y954709D01*
G37*
G36*
G01X555933Y958033D02*
X555549Y957851D01*
X555019Y958381D01*
X555201Y958765D01*
X555342Y958906D01*
X556074Y958174D01*
X555933Y958033D01*
G37*
G36*
G01X557976Y956555D02*
X558360Y956737D01*
X558890Y956207D01*
X558708Y955823D01*
X558566Y955682D01*
X557835Y956413D01*
X557976Y956555D01*
G37*
G36*
G01X560731Y954314D02*
X560874Y954714D01*
X561624D01*
X561766Y954314D01*
Y954114D01*
X560731D01*
Y954314D01*
G37*
G36*
G01X563081D02*
X563224Y954714D01*
X563974D01*
X564116Y954314D01*
Y954114D01*
X563081D01*
Y954314D01*
G37*
G36*
G01X565291Y953914D02*
X565148Y953514D01*
X564398D01*
X564256Y953914D01*
Y954114D01*
X565291D01*
Y953914D01*
G37*
G36*
G01X562941D02*
X562798Y953514D01*
X562048D01*
X561906Y953914D01*
Y954114D01*
X562941D01*
Y953914D01*
G37*
G36*
G01X565431Y954314D02*
X565574Y954714D01*
X566324D01*
X566466Y954314D01*
Y954114D01*
X565431D01*
Y954314D01*
G37*
G36*
G01X554235Y956335D02*
X553851Y956153D01*
X553321Y956683D01*
X553503Y957067D01*
X553644Y957208D01*
X554376Y956476D01*
X554235Y956335D01*
G37*
G36*
G01X555896Y954673D02*
X555513Y954491D01*
X554982Y955021D01*
X555164Y955405D01*
X555306Y955546D01*
X556038Y954814D01*
X555896Y954673D01*
G37*
G36*
G01X554616Y956518D02*
X555000Y956701D01*
X555530Y956170D01*
X555348Y955787D01*
X555207Y955645D01*
X554475Y956377D01*
X554616Y956518D01*
G37*
G36*
G01X557558Y953011D02*
X557174Y952829D01*
X556644Y953359D01*
X556826Y953743D01*
X556967Y953885D01*
X557699Y953153D01*
X557558Y953011D01*
G37*
G36*
G01X556278Y954857D02*
X556662Y955039D01*
X557192Y954509D01*
X557010Y954125D01*
X556868Y953984D01*
X556137Y954715D01*
X556278Y954857D01*
G37*
G36*
G01X557940Y953195D02*
X558323Y953377D01*
X558854Y952847D01*
X558672Y952463D01*
X558530Y952322D01*
X557798Y953054D01*
X557940Y953195D01*
G37*
G36*
G01X562941Y951514D02*
X562798Y951114D01*
X562048D01*
X561906Y951514D01*
Y951714D01*
X562941D01*
Y951514D01*
G37*
G36*
G01X565291D02*
X565148Y951114D01*
X564398D01*
X564256Y951514D01*
Y951714D01*
X565291D01*
Y951514D01*
G37*
G36*
G01X560731Y951914D02*
X560874Y952314D01*
X561624D01*
X561766Y951914D01*
Y951714D01*
X560731D01*
Y951914D01*
G37*
G36*
G01X563081D02*
X563224Y952314D01*
X563974D01*
X564116Y951914D01*
Y951714D01*
X563081D01*
Y951914D01*
G37*
G36*
G01X565431D02*
X565574Y952314D01*
X566324D01*
X566466Y951914D01*
Y951714D01*
X565431D01*
Y951914D01*
G37*
G36*
G01X561262Y980188D02*
X561120Y979788D01*
X560370D01*
X560228Y980188D01*
Y980388D01*
X561262D01*
Y980188D01*
G37*
G36*
G01X561402Y980588D02*
X561545Y980988D01*
X562295D01*
X562438Y980588D01*
Y980388D01*
X561402D01*
Y980588D01*
G37*
G36*
G01X563752D02*
X563895Y980988D01*
X564645D01*
X564788Y980588D01*
Y980388D01*
X563752D01*
Y980588D01*
G37*
G36*
G01X563612Y980188D02*
X563470Y979788D01*
X562720D01*
X562578Y980188D01*
Y980388D01*
X563612D01*
Y980188D01*
G37*
G36*
G01X565962D02*
X565820Y979788D01*
X565070D01*
X564928Y980188D01*
Y980388D01*
X565962D01*
Y980188D01*
G37*
G36*
G01X561262Y978988D02*
X561120Y978588D01*
X560370D01*
X560228Y978988D01*
Y979188D01*
X561262D01*
Y978988D01*
G37*
G36*
G01X561402Y979388D02*
X561545Y979788D01*
X562295D01*
X562438Y979388D01*
Y979188D01*
X561402D01*
Y979388D01*
G37*
G36*
G01X563752D02*
X563895Y979788D01*
X564645D01*
X564788Y979388D01*
Y979188D01*
X563752D01*
Y979388D01*
G37*
G36*
G01X563612Y978988D02*
X563470Y978588D01*
X562720D01*
X562578Y978988D01*
Y979188D01*
X563612D01*
Y978988D01*
G37*
G36*
G01X565962D02*
X565820Y978588D01*
X565070D01*
X564928Y978988D01*
Y979188D01*
X565962D01*
Y978988D01*
G37*
G36*
G01X559052Y978188D02*
X559195Y978588D01*
X559945D01*
X560088Y978188D01*
Y977988D01*
X559052D01*
Y978188D01*
G37*
G36*
G01X561262Y977788D02*
X561120Y977388D01*
X560370D01*
X560228Y977788D01*
Y977988D01*
X561262D01*
Y977788D01*
G37*
G36*
G01X561402Y978188D02*
X561545Y978588D01*
X562295D01*
X562438Y978188D01*
Y977988D01*
X561402D01*
Y978188D01*
G37*
G36*
G01X563752D02*
X563895Y978588D01*
X564645D01*
X564788Y978188D01*
Y977988D01*
X563752D01*
Y978188D01*
G37*
G36*
G01X563612Y977788D02*
X563470Y977388D01*
X562720D01*
X562578Y977788D01*
Y977988D01*
X563612D01*
Y977788D01*
G37*
G36*
G01X565962D02*
X565820Y977388D01*
X565070D01*
X564928Y977788D01*
Y977988D01*
X565962D01*
Y977788D01*
G37*
G36*
G01X561262Y976588D02*
X561120Y976188D01*
X560370D01*
X560228Y976588D01*
Y976788D01*
X561262D01*
Y976588D01*
G37*
G36*
G01X563612D02*
X563470Y976188D01*
X562720D01*
X562578Y976588D01*
Y976788D01*
X563612D01*
Y976588D01*
G37*
G36*
G01X565962D02*
X565820Y976188D01*
X565070D01*
X564928Y976588D01*
Y976788D01*
X565962D01*
Y976588D01*
G37*
G36*
G01X559052Y976988D02*
X559195Y977388D01*
X559945D01*
X560088Y976988D01*
Y976788D01*
X559052D01*
Y976988D01*
G37*
G36*
G01X561402D02*
X561545Y977388D01*
X562295D01*
X562438Y976988D01*
Y976788D01*
X561402D01*
Y976988D01*
G37*
G36*
G01X563752D02*
X563895Y977388D01*
X564645D01*
X564788Y976988D01*
Y976788D01*
X563752D01*
Y976988D01*
G37*
G36*
G01X558912Y975388D02*
X558770Y974988D01*
X558020D01*
X557878Y975388D01*
Y975588D01*
X558912D01*
Y975388D01*
G37*
G36*
G01X559052Y975788D02*
X559195Y976188D01*
X559945D01*
X560088Y975788D01*
Y975588D01*
X559052D01*
Y975788D01*
G37*
G36*
G01X561262Y975388D02*
X561120Y974988D01*
X560370D01*
X560228Y975388D01*
Y975588D01*
X561262D01*
Y975388D01*
G37*
G36*
G01X561402Y975788D02*
X561545Y976188D01*
X562295D01*
X562438Y975788D01*
Y975588D01*
X561402D01*
Y975788D01*
G37*
G36*
G01X563752D02*
X563895Y976188D01*
X564645D01*
X564788Y975788D01*
Y975588D01*
X563752D01*
Y975788D01*
G37*
G36*
G01X565962Y975388D02*
X565820Y974988D01*
X565070D01*
X564928Y975388D01*
Y975588D01*
X565962D01*
Y975388D01*
G37*
G36*
G01X563612D02*
X563470Y974988D01*
X562720D01*
X562578Y975388D01*
Y975588D01*
X563612D01*
Y975388D01*
G37*
G36*
G01X558912Y974188D02*
X558770Y973788D01*
X558020D01*
X557878Y974188D01*
Y974388D01*
X558912D01*
Y974188D01*
G37*
G36*
G01X559052Y974588D02*
X559195Y974988D01*
X559945D01*
X560088Y974588D01*
Y974388D01*
X559052D01*
Y974588D01*
G37*
G36*
G01X561262Y974188D02*
X561120Y973788D01*
X560370D01*
X560228Y974188D01*
Y974388D01*
X561262D01*
Y974188D01*
G37*
G36*
G01X563752Y974588D02*
X563895Y974988D01*
X564645D01*
X564788Y974588D01*
Y974388D01*
X563752D01*
Y974588D01*
G37*
G36*
G01X561402D02*
X561545Y974988D01*
X562295D01*
X562438Y974588D01*
Y974388D01*
X561402D01*
Y974588D01*
G37*
G36*
G01X565962Y974188D02*
X565820Y973788D01*
X565070D01*
X564928Y974188D01*
Y974388D01*
X565962D01*
Y974188D01*
G37*
G36*
G01X563612D02*
X563470Y973788D01*
X562720D01*
X562578Y974188D01*
Y974388D01*
X563612D01*
Y974188D01*
G37*
G36*
G01X556702Y973388D02*
X556845Y973788D01*
X557595D01*
X557738Y973388D01*
Y973188D01*
X556702D01*
Y973388D01*
G37*
G36*
G01X558912Y972988D02*
X558770Y972588D01*
X558020D01*
X557878Y972988D01*
Y973188D01*
X558912D01*
Y972988D01*
G37*
G36*
G01X559052Y973388D02*
X559195Y973788D01*
X559945D01*
X560088Y973388D01*
Y973188D01*
X559052D01*
Y973388D01*
G37*
G36*
G01X561262Y972988D02*
X561120Y972588D01*
X560370D01*
X560228Y972988D01*
Y973188D01*
X561262D01*
Y972988D01*
G37*
G36*
G01X563752Y973388D02*
X563895Y973788D01*
X564645D01*
X564788Y973388D01*
Y973188D01*
X563752D01*
Y973388D01*
G37*
G36*
G01X561402D02*
X561545Y973788D01*
X562295D01*
X562438Y973388D01*
Y973188D01*
X561402D01*
Y973388D01*
G37*
G36*
G01X565962Y972988D02*
X565820Y972588D01*
X565070D01*
X564928Y972988D01*
Y973188D01*
X565962D01*
Y972988D01*
G37*
G36*
G01X563612D02*
X563470Y972588D01*
X562720D01*
X562578Y972988D01*
Y973188D01*
X563612D01*
Y972988D01*
G37*
G36*
G01X558912Y970588D02*
X558770Y970188D01*
X558020D01*
X557878Y970588D01*
Y970788D01*
X558912D01*
Y970588D01*
G37*
G36*
G01X556702Y970988D02*
X556845Y971388D01*
X557595D01*
X557738Y970988D01*
Y970788D01*
X556702D01*
Y970988D01*
G37*
G36*
G01X556562Y970588D02*
X556420Y970188D01*
X555670D01*
X555528Y970588D01*
Y970788D01*
X556562D01*
Y970588D01*
G37*
G36*
G01X559052Y970988D02*
X559195Y971388D01*
X559945D01*
X560088Y970988D01*
Y970788D01*
X559052D01*
Y970988D01*
G37*
G36*
G01X561262Y970588D02*
X561120Y970188D01*
X560370D01*
X560228Y970588D01*
Y970788D01*
X561262D01*
Y970588D01*
G37*
G36*
G01X563752Y970988D02*
X563895Y971388D01*
X564645D01*
X564788Y970988D01*
Y970788D01*
X563752D01*
Y970988D01*
G37*
G36*
G01X561402D02*
X561545Y971388D01*
X562295D01*
X562438Y970988D01*
Y970788D01*
X561402D01*
Y970988D01*
G37*
G36*
G01X565962Y970588D02*
X565820Y970188D01*
X565070D01*
X564928Y970588D01*
Y970788D01*
X565962D01*
Y970588D01*
G37*
G36*
G01X563612D02*
X563470Y970188D01*
X562720D01*
X562578Y970588D01*
Y970788D01*
X563612D01*
Y970588D01*
G37*
G36*
G01X558912Y968188D02*
X558770Y967788D01*
X558020D01*
X557878Y968188D01*
Y968388D01*
X558912D01*
Y968188D01*
G37*
G36*
G01X556562D02*
X556420Y967788D01*
X555670D01*
X555528Y968188D01*
Y968388D01*
X556562D01*
Y968188D01*
G37*
G36*
G01X554212D02*
X554070Y967788D01*
X553320D01*
X553178Y968188D01*
Y968388D01*
X554212D01*
Y968188D01*
G37*
G36*
G01X556702Y968588D02*
X556845Y968988D01*
X557595D01*
X557738Y968588D01*
Y968388D01*
X556702D01*
Y968588D01*
G37*
G36*
G01X554352D02*
X554495Y968988D01*
X555245D01*
X555388Y968588D01*
Y968388D01*
X554352D01*
Y968588D01*
G37*
G36*
G01X561262Y968188D02*
X561120Y967788D01*
X560370D01*
X560228Y968188D01*
Y968388D01*
X561262D01*
Y968188D01*
G37*
G36*
G01X561402Y968588D02*
X561545Y968988D01*
X562295D01*
X562438Y968588D01*
Y968388D01*
X561402D01*
Y968588D01*
G37*
G36*
G01X559052D02*
X559195Y968988D01*
X559945D01*
X560088Y968588D01*
Y968388D01*
X559052D01*
Y968588D01*
G37*
G36*
G01X558912Y969388D02*
X558770Y968988D01*
X558020D01*
X557878Y969388D01*
Y969588D01*
X558912D01*
Y969388D01*
G37*
G36*
G01X556702Y969788D02*
X556845Y970188D01*
X557595D01*
X557738Y969788D01*
Y969588D01*
X556702D01*
Y969788D01*
G37*
G36*
G01X554352D02*
X554495Y970188D01*
X555245D01*
X555388Y969788D01*
Y969588D01*
X554352D01*
Y969788D01*
G37*
G36*
G01X556562Y969388D02*
X556420Y968988D01*
X555670D01*
X555528Y969388D01*
Y969588D01*
X556562D01*
Y969388D01*
G37*
G36*
G01X559052Y969788D02*
X559195Y970188D01*
X559945D01*
X560088Y969788D01*
Y969588D01*
X559052D01*
Y969788D01*
G37*
G36*
G01X561262Y969388D02*
X561120Y968988D01*
X560370D01*
X560228Y969388D01*
Y969588D01*
X561262D01*
Y969388D01*
G37*
G36*
G01X563752Y969788D02*
X563895Y970188D01*
X564645D01*
X564788Y969788D01*
Y969588D01*
X563752D01*
Y969788D01*
G37*
G36*
G01X561402D02*
X561545Y970188D01*
X562295D01*
X562438Y969788D01*
Y969588D01*
X561402D01*
Y969788D01*
G37*
G36*
G01X563612Y969388D02*
X563470Y968988D01*
X562720D01*
X562578Y969388D01*
Y969588D01*
X563612D01*
Y969388D01*
G37*
G36*
G01X558912Y966988D02*
X558770Y966588D01*
X558020D01*
X557878Y966988D01*
Y967188D01*
X558912D01*
Y966988D01*
G37*
G36*
G01X556562D02*
X556420Y966588D01*
X555670D01*
X555528Y966988D01*
Y967188D01*
X556562D01*
Y966988D01*
G37*
G36*
G01X556702Y967388D02*
X556845Y967788D01*
X557595D01*
X557738Y967388D01*
Y967188D01*
X556702D01*
Y967388D01*
G37*
G36*
G01X554352D02*
X554495Y967788D01*
X555245D01*
X555388Y967388D01*
Y967188D01*
X554352D01*
Y967388D01*
G37*
G36*
G01X554212Y966988D02*
X554070Y966588D01*
X553320D01*
X553178Y966988D01*
Y967188D01*
X554212D01*
Y966988D01*
G37*
G36*
G01X559052Y967388D02*
X559195Y967788D01*
X559945D01*
X560088Y967388D01*
Y967188D01*
X559052D01*
Y967388D01*
G37*
G36*
G01X561262Y966988D02*
X561120Y966588D01*
X560370D01*
X560228Y966988D01*
Y967188D01*
X561262D01*
Y966988D01*
G37*
G36*
G01X558912Y971788D02*
X558770Y971388D01*
X558020D01*
X557878Y971788D01*
Y971988D01*
X558912D01*
Y971788D01*
G37*
G36*
G01X556702Y972188D02*
X556845Y972588D01*
X557595D01*
X557738Y972188D01*
Y971988D01*
X556702D01*
Y972188D01*
G37*
G36*
G01X559052D02*
X559195Y972588D01*
X559945D01*
X560088Y972188D01*
Y971988D01*
X559052D01*
Y972188D01*
G37*
G36*
G01X561262Y971788D02*
X561120Y971388D01*
X560370D01*
X560228Y971788D01*
Y971988D01*
X561262D01*
Y971788D01*
G37*
G36*
G01X563752Y972188D02*
X563895Y972588D01*
X564645D01*
X564788Y972188D01*
Y971988D01*
X563752D01*
Y972188D01*
G37*
G36*
G01X561402D02*
X561545Y972588D01*
X562295D01*
X562438Y972188D01*
Y971988D01*
X561402D01*
Y972188D01*
G37*
G36*
G01X565962Y971788D02*
X565820Y971388D01*
X565070D01*
X564928Y971788D01*
Y971988D01*
X565962D01*
Y971788D01*
G37*
G36*
G01X563612D02*
X563470Y971388D01*
X562720D01*
X562578Y971788D01*
Y971988D01*
X563612D01*
Y971788D01*
G37*
G36*
G01X557967Y1008774D02*
X558149Y1008390D01*
X557618Y1007860D01*
X557235Y1008042D01*
X557093Y1008183D01*
X557825Y1008915D01*
X557967Y1008774D01*
G37*
G36*
G01X559628Y1010435D02*
X559810Y1010051D01*
X559279Y1009521D01*
X558896Y1009703D01*
X558754Y1009844D01*
X559486Y1010576D01*
X559628Y1010435D01*
G37*
G36*
G01X557782Y1009155D02*
X557600Y1009539D01*
X558130Y1010069D01*
X558514Y1009887D01*
X558655Y1009745D01*
X557924Y1009014D01*
X557782Y1009155D01*
G37*
G36*
G01X561289Y1012097D02*
X561471Y1011713D01*
X560941Y1011183D01*
X560558Y1011365D01*
X560416Y1011506D01*
X561148Y1012238D01*
X561289Y1012097D01*
G37*
G36*
G01X559444Y1010817D02*
X559262Y1011200D01*
X559792Y1011731D01*
X560176Y1011549D01*
X560317Y1011407D01*
X559585Y1010675D01*
X559444Y1010817D01*
G37*
G36*
G01X561106Y1012478D02*
X560923Y1012862D01*
X561454Y1013392D01*
X561837Y1013210D01*
X561979Y1013069D01*
X561247Y1012337D01*
X561106Y1012478D01*
G37*
G36*
G01X562951Y1013758D02*
X563133Y1013375D01*
X562603Y1012844D01*
X562219Y1013026D01*
X562078Y1013168D01*
X562810Y1013900D01*
X562951Y1013758D01*
G37*
G36*
G01X562767Y1014140D02*
X562585Y1014524D01*
X563116Y1015054D01*
X563499Y1014872D01*
X563641Y1014731D01*
X562909Y1013999D01*
X562767Y1014140D01*
G37*
G36*
G01X558816Y1007925D02*
X558998Y1007541D01*
X558467Y1007011D01*
X558084Y1007193D01*
X557942Y1007334D01*
X558674Y1008066D01*
X558816Y1007925D01*
G37*
G36*
G01X558631Y1008306D02*
X558449Y1008690D01*
X558979Y1009220D01*
X559363Y1009038D01*
X559504Y1008896D01*
X558773Y1008165D01*
X558631Y1008306D01*
G37*
G36*
G01X563800Y1012909D02*
X563982Y1012526D01*
X563452Y1011995D01*
X563068Y1012177D01*
X562927Y1012319D01*
X563659Y1013051D01*
X563800Y1012909D01*
G37*
G36*
G01X560477Y1009586D02*
X560659Y1009202D01*
X560128Y1008672D01*
X559745Y1008854D01*
X559603Y1008995D01*
X560335Y1009727D01*
X560477Y1009586D01*
G37*
G36*
G01X560293Y1009968D02*
X560111Y1010351D01*
X560641Y1010882D01*
X561025Y1010700D01*
X561166Y1010558D01*
X560434Y1009826D01*
X560293Y1009968D01*
G37*
G36*
G01X562138Y1011248D02*
X562320Y1010864D01*
X561790Y1010334D01*
X561407Y1010516D01*
X561265Y1010657D01*
X561997Y1011389D01*
X562138Y1011248D01*
G37*
G36*
G01X561955Y1011629D02*
X561772Y1012013D01*
X562303Y1012543D01*
X562686Y1012361D01*
X562828Y1012220D01*
X562096Y1011488D01*
X561955Y1011629D01*
G37*
G36*
G01X565462Y1014571D02*
X565644Y1014187D01*
X565114Y1013657D01*
X564730Y1013839D01*
X564589Y1013981D01*
X565320Y1014712D01*
X565462Y1014571D01*
G37*
G36*
G01X563616Y1013291D02*
X563434Y1013675D01*
X563965Y1014205D01*
X564348Y1014023D01*
X564490Y1013882D01*
X563758Y1013150D01*
X563616Y1013291D01*
G37*
G36*
G01X557819Y1005796D02*
X557637Y1006180D01*
X558167Y1006710D01*
X558551Y1006528D01*
X558692Y1006386D01*
X557961Y1005655D01*
X557819Y1005796D01*
G37*
G36*
G01X559665Y1007076D02*
X559847Y1006692D01*
X559316Y1006162D01*
X558933Y1006344D01*
X558791Y1006485D01*
X559523Y1007217D01*
X559665Y1007076D01*
G37*
G36*
G01X559480Y1007457D02*
X559298Y1007841D01*
X559828Y1008371D01*
X560212Y1008189D01*
X560353Y1008047D01*
X559622Y1007316D01*
X559480Y1007457D01*
G37*
G36*
G01X561326Y1008737D02*
X561508Y1008353D01*
X560977Y1007823D01*
X560594Y1008005D01*
X560452Y1008146D01*
X561184Y1008878D01*
X561326Y1008737D01*
G37*
G36*
G01X564649Y1012060D02*
X564831Y1011677D01*
X564301Y1011146D01*
X563917Y1011328D01*
X563776Y1011470D01*
X564508Y1012202D01*
X564649Y1012060D01*
G37*
G36*
G01X564465Y1012442D02*
X564283Y1012826D01*
X564814Y1013356D01*
X565197Y1013174D01*
X565339Y1013033D01*
X564607Y1012301D01*
X564465Y1012442D01*
G37*
G36*
G01X561142Y1009119D02*
X560960Y1009502D01*
X561490Y1010033D01*
X561874Y1009851D01*
X562015Y1009709D01*
X561283Y1008977D01*
X561142Y1009119D01*
G37*
G36*
G01X562804Y1010780D02*
X562621Y1011164D01*
X563152Y1011694D01*
X563535Y1011512D01*
X563677Y1011371D01*
X562945Y1010639D01*
X562804Y1010780D01*
G37*
G36*
G01X562987Y1010399D02*
X563169Y1010015D01*
X562639Y1009485D01*
X562256Y1009667D01*
X562114Y1009808D01*
X562846Y1010540D01*
X562987Y1010399D01*
G37*
G36*
G01X558668Y1004947D02*
X558486Y1005331D01*
X559016Y1005861D01*
X559400Y1005679D01*
X559541Y1005537D01*
X558810Y1004806D01*
X558668Y1004947D01*
G37*
G36*
G01X560329Y1006608D02*
X560147Y1006992D01*
X560677Y1007522D01*
X561061Y1007340D01*
X561202Y1007198D01*
X560471Y1006467D01*
X560329Y1006608D01*
G37*
G36*
G01X560514Y1006227D02*
X560696Y1005843D01*
X560165Y1005313D01*
X559782Y1005495D01*
X559640Y1005636D01*
X560372Y1006368D01*
X560514Y1006227D01*
G37*
G36*
G01X562175Y1007888D02*
X562357Y1007504D01*
X561826Y1006974D01*
X561443Y1007156D01*
X561301Y1007297D01*
X562033Y1008029D01*
X562175Y1007888D01*
G37*
G36*
G01X565314Y1011593D02*
X565132Y1011977D01*
X565663Y1012507D01*
X566046Y1012325D01*
X566188Y1012184D01*
X565456Y1011452D01*
X565314Y1011593D01*
G37*
G36*
G01X563653Y1009931D02*
X563470Y1010315D01*
X564001Y1010845D01*
X564384Y1010663D01*
X564526Y1010522D01*
X563794Y1009790D01*
X563653Y1009931D01*
G37*
G36*
G01X565498Y1011211D02*
X565680Y1010828D01*
X565150Y1010297D01*
X564766Y1010479D01*
X564625Y1010621D01*
X565357Y1011353D01*
X565498Y1011211D01*
G37*
G36*
G01X563836Y1009550D02*
X564018Y1009166D01*
X563488Y1008636D01*
X563105Y1008818D01*
X562963Y1008959D01*
X563695Y1009691D01*
X563836Y1009550D01*
G37*
G36*
G01X561991Y1008270D02*
X561809Y1008653D01*
X562339Y1009184D01*
X562723Y1009002D01*
X562864Y1008860D01*
X562132Y1008128D01*
X561991Y1008270D01*
G37*
G36*
G01X559701Y1003716D02*
X559883Y1003332D01*
X559352Y1002802D01*
X558969Y1002984D01*
X558827Y1003125D01*
X559559Y1003857D01*
X559701Y1003716D01*
G37*
G36*
G01X561178Y1005759D02*
X560996Y1006143D01*
X561526Y1006673D01*
X561910Y1006491D01*
X562051Y1006349D01*
X561320Y1005618D01*
X561178Y1005759D01*
G37*
G36*
G01X559517Y1004098D02*
X559335Y1004481D01*
X559865Y1005012D01*
X560249Y1004830D01*
X560390Y1004688D01*
X559658Y1003956D01*
X559517Y1004098D01*
G37*
G36*
G01X561362Y1005378D02*
X561544Y1004994D01*
X561014Y1004464D01*
X560631Y1004646D01*
X560489Y1004787D01*
X561221Y1005519D01*
X561362Y1005378D01*
G37*
G36*
G01X562840Y1007421D02*
X562658Y1007804D01*
X563188Y1008335D01*
X563572Y1008153D01*
X563713Y1008011D01*
X562981Y1007279D01*
X562840Y1007421D01*
G37*
G36*
G01X563024Y1007039D02*
X563206Y1006655D01*
X562675Y1006125D01*
X562292Y1006307D01*
X562150Y1006448D01*
X562882Y1007180D01*
X563024Y1007039D01*
G37*
G36*
G01X566347Y1010362D02*
X566529Y1009979D01*
X565999Y1009448D01*
X565615Y1009630D01*
X565474Y1009772D01*
X566206Y1010504D01*
X566347Y1010362D01*
G37*
G36*
G01X564685Y1008701D02*
X564867Y1008317D01*
X564337Y1007787D01*
X563954Y1007969D01*
X563812Y1008110D01*
X564544Y1008842D01*
X564685Y1008701D01*
G37*
G36*
G01X564502Y1009082D02*
X564319Y1009466D01*
X564850Y1009996D01*
X565233Y1009814D01*
X565375Y1009673D01*
X564643Y1008941D01*
X564502Y1009082D01*
G37*
G36*
G01X565534Y1007852D02*
X565716Y1007468D01*
X565186Y1006938D01*
X564803Y1007120D01*
X564661Y1007261D01*
X565393Y1007993D01*
X565534Y1007852D01*
G37*
G36*
G01X563873Y1006190D02*
X564055Y1005806D01*
X563524Y1005276D01*
X563141Y1005458D01*
X562999Y1005599D01*
X563731Y1006331D01*
X563873Y1006190D01*
G37*
G36*
G01X563689Y1006572D02*
X563507Y1006955D01*
X564037Y1007486D01*
X564421Y1007304D01*
X564562Y1007162D01*
X563830Y1006430D01*
X563689Y1006572D01*
G37*
G36*
G01X560366Y1003249D02*
X560184Y1003633D01*
X560714Y1004163D01*
X561098Y1003981D01*
X561239Y1003839D01*
X560508Y1003108D01*
X560366Y1003249D01*
G37*
G36*
G01X562211Y1004528D02*
X562393Y1004145D01*
X561863Y1003614D01*
X561479Y1003796D01*
X561338Y1003938D01*
X562070Y1004670D01*
X562211Y1004528D01*
G37*
G36*
G01X560550Y1002867D02*
X560732Y1002484D01*
X560202Y1001953D01*
X559818Y1002135D01*
X559677Y1002277D01*
X560409Y1003009D01*
X560550Y1002867D01*
G37*
G36*
G01X562027Y1004910D02*
X561845Y1005294D01*
X562375Y1005824D01*
X562759Y1005642D01*
X562900Y1005500D01*
X562169Y1004769D01*
X562027Y1004910D01*
G37*
G36*
G01X565351Y1008233D02*
X565168Y1008617D01*
X565699Y1009147D01*
X566082Y1008965D01*
X566224Y1008824D01*
X565492Y1008092D01*
X565351Y1008233D01*
G37*
G36*
G01X562876Y1004061D02*
X562694Y1004445D01*
X563224Y1004975D01*
X563608Y1004793D01*
X563749Y1004651D01*
X563018Y1003920D01*
X562876Y1004061D01*
G37*
G36*
G01X563060Y1003679D02*
X563242Y1003296D01*
X562712Y1002765D01*
X562328Y1002947D01*
X562187Y1003089D01*
X562919Y1003821D01*
X563060Y1003679D01*
G37*
G36*
G01X561214Y1002399D02*
X561032Y1002783D01*
X561563Y1003313D01*
X561946Y1003131D01*
X562088Y1002990D01*
X561356Y1002258D01*
X561214Y1002399D01*
G37*
G36*
G01X564722Y1005341D02*
X564904Y1004957D01*
X564373Y1004427D01*
X563990Y1004609D01*
X563848Y1004750D01*
X564580Y1005482D01*
X564722Y1005341D01*
G37*
G36*
G01X564538Y1005723D02*
X564356Y1006106D01*
X564886Y1006637D01*
X565270Y1006455D01*
X565411Y1006313D01*
X564679Y1005581D01*
X564538Y1005723D01*
G37*
G36*
G01X566383Y1007003D02*
X566565Y1006619D01*
X566035Y1006089D01*
X565652Y1006271D01*
X565510Y1006412D01*
X566242Y1007144D01*
X566383Y1007003D01*
G37*
G36*
G01X561398Y1002017D02*
X561580Y1001634D01*
X561050Y1001104D01*
X560666Y1001286D01*
X560525Y1001427D01*
X561257Y1002159D01*
X561398Y1002017D01*
G37*
G36*
G01X556047Y1014213D02*
X555865Y1014597D01*
X556396Y1015127D01*
X556779Y1014945D01*
X556921Y1014804D01*
X556189Y1014072D01*
X556047Y1014213D01*
G37*
G36*
G01X557746Y1012515D02*
X557564Y1012898D01*
X558094Y1013429D01*
X558478Y1013247D01*
X558619Y1013105D01*
X557887Y1012373D01*
X557746Y1012515D01*
G37*
G36*
G01X557930Y1012133D02*
X558112Y1011749D01*
X557581Y1011219D01*
X557198Y1011401D01*
X557056Y1011542D01*
X557788Y1012274D01*
X557930Y1012133D01*
G37*
G36*
G01X559591Y1013795D02*
X559773Y1013411D01*
X559243Y1012881D01*
X558860Y1013063D01*
X558718Y1013204D01*
X559450Y1013936D01*
X559591Y1013795D01*
G37*
G36*
G01X559408Y1014176D02*
X559225Y1014560D01*
X559756Y1015090D01*
X560139Y1014908D01*
X560281Y1014767D01*
X559549Y1014035D01*
X559408Y1014176D01*
G37*
G36*
G01X557081Y1012982D02*
X557263Y1012598D01*
X556732Y1012068D01*
X556349Y1012250D01*
X556207Y1012391D01*
X556939Y1013123D01*
X557081Y1012982D01*
G37*
G36*
G01X556897Y1013364D02*
X556715Y1013747D01*
X557245Y1014278D01*
X557629Y1014096D01*
X557770Y1013954D01*
X557038Y1013222D01*
X556897Y1013364D01*
G37*
G36*
G01X558742Y1014644D02*
X558924Y1014260D01*
X558394Y1013730D01*
X558011Y1013912D01*
X557869Y1014053D01*
X558601Y1014785D01*
X558742Y1014644D01*
G37*
G36*
G01X556933Y1010004D02*
X556751Y1010388D01*
X557281Y1010918D01*
X557665Y1010736D01*
X557806Y1010594D01*
X557075Y1009863D01*
X556933Y1010004D01*
G37*
G36*
G01X558595Y1011666D02*
X558413Y1012049D01*
X558943Y1012580D01*
X559327Y1012398D01*
X559468Y1012256D01*
X558736Y1011524D01*
X558595Y1011666D01*
G37*
G36*
G01X558779Y1011284D02*
X558961Y1010900D01*
X558430Y1010370D01*
X558047Y1010552D01*
X557905Y1010693D01*
X558637Y1011425D01*
X558779Y1011284D01*
G37*
G36*
G01X560440Y1012946D02*
X560622Y1012562D01*
X560092Y1012032D01*
X559709Y1012214D01*
X559567Y1012355D01*
X560299Y1013087D01*
X560440Y1012946D01*
G37*
G36*
G01X562102Y1014607D02*
X562284Y1014224D01*
X561754Y1013693D01*
X561370Y1013875D01*
X561229Y1014017D01*
X561961Y1014749D01*
X562102Y1014607D01*
G37*
G36*
G01X560257Y1013327D02*
X560074Y1013711D01*
X560605Y1014241D01*
X560988Y1014059D01*
X561130Y1013918D01*
X560398Y1013186D01*
X560257Y1013327D01*
G37*
G36*
G01X562247Y1001168D02*
X562429Y1000785D01*
X561899Y1000255D01*
X561515Y1000437D01*
X561374Y1000578D01*
X562106Y1001310D01*
X562247Y1001168D01*
G37*
G36*
G01X560402Y999889D02*
X560220Y1000272D01*
X560750Y1000803D01*
X561134Y1000620D01*
X561275Y1000479D01*
X560543Y999747D01*
X560402Y999889D01*
G37*
G36*
G01X562063Y1001550D02*
X561881Y1001934D01*
X562412Y1002464D01*
X562795Y1002282D01*
X562937Y1002141D01*
X562205Y1001409D01*
X562063Y1001550D01*
G37*
G36*
G01X565571Y1004492D02*
X565753Y1004108D01*
X565222Y1003578D01*
X564839Y1003760D01*
X564697Y1003901D01*
X565429Y1004633D01*
X565571Y1004492D01*
G37*
G36*
G01X565387Y1004874D02*
X565205Y1005257D01*
X565735Y1005788D01*
X566119Y1005606D01*
X566260Y1005464D01*
X565528Y1004732D01*
X565387Y1004874D01*
G37*
G36*
G01X563725Y1003212D02*
X563543Y1003596D01*
X564073Y1004126D01*
X564457Y1003944D01*
X564598Y1003802D01*
X563867Y1003071D01*
X563725Y1003212D01*
G37*
G36*
G01X563909Y1002830D02*
X564091Y1002447D01*
X563561Y1001916D01*
X563177Y1002098D01*
X563036Y1002240D01*
X563768Y1002972D01*
X563909Y1002830D01*
G37*
G36*
G01X564613Y1015420D02*
X564795Y1015036D01*
X564265Y1014506D01*
X563881Y1014688D01*
X563740Y1014830D01*
X564471Y1015561D01*
X564613Y1015420D01*
G37*
G36*
G01X557149Y1026605D02*
X556967Y1026989D01*
X557497Y1027519D01*
X557881Y1027337D01*
X558022Y1027195D01*
X557291Y1026464D01*
X557149Y1026605D01*
G37*
G36*
G01X558995Y1027885D02*
X559177Y1027501D01*
X558646Y1026971D01*
X558263Y1027153D01*
X558121Y1027294D01*
X558853Y1028026D01*
X558995Y1027885D01*
G37*
G36*
G01X557333Y1026223D02*
X557515Y1025839D01*
X556985Y1025309D01*
X556601Y1025491D01*
X556460Y1025633D01*
X557192Y1026365D01*
X557333Y1026223D01*
G37*
G36*
G01X558811Y1028267D02*
X558629Y1028650D01*
X559159Y1029181D01*
X559543Y1028998D01*
X559684Y1028857D01*
X558952Y1028125D01*
X558811Y1028267D01*
G37*
G36*
G01X562318Y1031208D02*
X562500Y1030825D01*
X561970Y1030294D01*
X561586Y1030476D01*
X561445Y1030618D01*
X562177Y1031350D01*
X562318Y1031208D01*
G37*
G36*
G01X560472Y1029928D02*
X560290Y1030312D01*
X560821Y1030842D01*
X561204Y1030660D01*
X561346Y1030519D01*
X560614Y1029787D01*
X560472Y1029928D01*
G37*
G36*
G01X560656Y1029546D02*
X560838Y1029163D01*
X560308Y1028633D01*
X559924Y1028815D01*
X559783Y1028956D01*
X560515Y1029688D01*
X560656Y1029546D01*
G37*
G36*
G01X559031Y1024525D02*
X559213Y1024141D01*
X558683Y1023611D01*
X558299Y1023793D01*
X558158Y1023935D01*
X558890Y1024667D01*
X559031Y1024525D01*
G37*
G36*
G01X558847Y1024907D02*
X558665Y1025291D01*
X559195Y1025821D01*
X559579Y1025639D01*
X559720Y1025497D01*
X558989Y1024766D01*
X558847Y1024907D01*
G37*
G36*
G01X563832Y1029892D02*
X563650Y1030276D01*
X564180Y1030806D01*
X564564Y1030624D01*
X564705Y1030482D01*
X563974Y1029751D01*
X563832Y1029892D01*
G37*
G36*
G01X565678Y1031172D02*
X565860Y1030788D01*
X565329Y1030258D01*
X564946Y1030440D01*
X564804Y1030581D01*
X565536Y1031313D01*
X565678Y1031172D01*
G37*
G36*
G01X564016Y1029510D02*
X564198Y1029127D01*
X563668Y1028596D01*
X563284Y1028778D01*
X563143Y1028920D01*
X563875Y1029652D01*
X564016Y1029510D01*
G37*
G36*
G01X560509Y1026569D02*
X560327Y1026952D01*
X560857Y1027483D01*
X561241Y1027300D01*
X561382Y1027159D01*
X560650Y1026427D01*
X560509Y1026569D01*
G37*
G36*
G01X562354Y1027848D02*
X562536Y1027465D01*
X562006Y1026935D01*
X561622Y1027117D01*
X561481Y1027258D01*
X562213Y1027990D01*
X562354Y1027848D01*
G37*
G36*
G01X562170Y1028230D02*
X561988Y1028614D01*
X562519Y1029144D01*
X562902Y1028962D01*
X563044Y1028821D01*
X562312Y1028089D01*
X562170Y1028230D01*
G37*
G36*
G01X560693Y1026187D02*
X560875Y1025803D01*
X560344Y1025273D01*
X559961Y1025455D01*
X559819Y1025596D01*
X560551Y1026328D01*
X560693Y1026187D01*
G37*
G36*
G01X557998Y1025756D02*
X557816Y1026140D01*
X558346Y1026670D01*
X558730Y1026488D01*
X558871Y1026346D01*
X558140Y1025615D01*
X557998Y1025756D01*
G37*
G36*
G01X558182Y1025374D02*
X558364Y1024990D01*
X557834Y1024460D01*
X557450Y1024642D01*
X557309Y1024784D01*
X558041Y1025516D01*
X558182Y1025374D01*
G37*
G36*
G01X562983Y1030741D02*
X562801Y1031125D01*
X563331Y1031655D01*
X563715Y1031473D01*
X563856Y1031331D01*
X563125Y1030600D01*
X562983Y1030741D01*
G37*
G36*
G01X561321Y1029079D02*
X561139Y1029463D01*
X561670Y1029993D01*
X562053Y1029811D01*
X562195Y1029670D01*
X561463Y1028938D01*
X561321Y1029079D01*
G37*
G36*
G01X563167Y1030359D02*
X563349Y1029976D01*
X562819Y1029445D01*
X562435Y1029627D01*
X562294Y1029769D01*
X563026Y1030501D01*
X563167Y1030359D01*
G37*
G36*
G01X559660Y1027418D02*
X559478Y1027801D01*
X560008Y1028332D01*
X560392Y1028149D01*
X560533Y1028008D01*
X559801Y1027276D01*
X559660Y1027418D01*
G37*
G36*
G01X561505Y1028697D02*
X561687Y1028314D01*
X561157Y1027784D01*
X560773Y1027966D01*
X560632Y1028107D01*
X561364Y1028839D01*
X561505Y1028697D01*
G37*
G36*
G01X559844Y1027036D02*
X560026Y1026652D01*
X559495Y1026122D01*
X559112Y1026304D01*
X558970Y1026445D01*
X559702Y1027177D01*
X559844Y1027036D01*
G37*
G36*
G01X561542Y1025338D02*
X561724Y1024954D01*
X561193Y1024424D01*
X560810Y1024606D01*
X560668Y1024747D01*
X561400Y1025479D01*
X561542Y1025338D01*
G37*
G36*
G01X559880Y1023676D02*
X560062Y1023292D01*
X559532Y1022762D01*
X559148Y1022944D01*
X559007Y1023086D01*
X559739Y1023818D01*
X559880Y1023676D01*
G37*
G36*
G01X559696Y1024058D02*
X559514Y1024442D01*
X560044Y1024972D01*
X560428Y1024790D01*
X560569Y1024648D01*
X559838Y1023917D01*
X559696Y1024058D01*
G37*
G36*
G01X564681Y1029043D02*
X564499Y1029427D01*
X565029Y1029957D01*
X565413Y1029775D01*
X565554Y1029633D01*
X564823Y1028902D01*
X564681Y1029043D01*
G37*
G36*
G01X561358Y1025720D02*
X561176Y1026103D01*
X561706Y1026634D01*
X562090Y1026451D01*
X562231Y1026310D01*
X561499Y1025578D01*
X561358Y1025720D01*
G37*
G36*
G01X564865Y1028661D02*
X565047Y1028278D01*
X564517Y1027747D01*
X564133Y1027929D01*
X563992Y1028071D01*
X564724Y1028803D01*
X564865Y1028661D01*
G37*
G36*
G01X563203Y1026999D02*
X563385Y1026616D01*
X562855Y1026086D01*
X562471Y1026268D01*
X562330Y1026409D01*
X563062Y1027141D01*
X563203Y1026999D01*
G37*
G36*
G01X563019Y1027381D02*
X562837Y1027765D01*
X563368Y1028295D01*
X563751Y1028113D01*
X563893Y1027972D01*
X563161Y1027240D01*
X563019Y1027381D01*
G37*
G36*
G01X557709Y1015875D02*
X557527Y1016259D01*
X558057Y1016789D01*
X558441Y1016607D01*
X558582Y1016465D01*
X557850Y1015733D01*
X557709Y1015875D01*
G37*
G36*
G01X557893Y1015493D02*
X558075Y1015109D01*
X557545Y1014579D01*
X557161Y1014761D01*
X557020Y1014903D01*
X557751Y1015634D01*
X557893Y1015493D01*
G37*
G36*
G01X559555Y1017155D02*
X559737Y1016771D01*
X559206Y1016241D01*
X558823Y1016423D01*
X558681Y1016564D01*
X559413Y1017296D01*
X559555Y1017155D01*
G37*
G36*
G01X561216Y1018816D02*
X561398Y1018433D01*
X560868Y1017903D01*
X560484Y1018085D01*
X560343Y1018226D01*
X561075Y1018958D01*
X561216Y1018816D01*
G37*
G36*
G01X559371Y1017537D02*
X559189Y1017920D01*
X559719Y1018451D01*
X560103Y1018268D01*
X560244Y1018127D01*
X559512Y1017395D01*
X559371Y1017537D01*
G37*
G36*
G01X561032Y1019198D02*
X560850Y1019582D01*
X561381Y1020112D01*
X561764Y1019930D01*
X561906Y1019789D01*
X561174Y1019057D01*
X561032Y1019198D01*
G37*
G36*
G01X562878Y1020478D02*
X563060Y1020095D01*
X562530Y1019564D01*
X562146Y1019746D01*
X562005Y1019888D01*
X562737Y1020620D01*
X562878Y1020478D01*
G37*
G36*
G01X562694Y1020860D02*
X562512Y1021244D01*
X563042Y1021774D01*
X563426Y1021592D01*
X563567Y1021450D01*
X562836Y1020719D01*
X562694Y1020860D01*
G37*
G36*
G01X561069Y1015838D02*
X560887Y1016222D01*
X561418Y1016752D01*
X561801Y1016570D01*
X561943Y1016429D01*
X561211Y1015697D01*
X561069Y1015838D01*
G37*
G36*
G01X561253Y1015456D02*
X561435Y1015073D01*
X560905Y1014542D01*
X560521Y1014724D01*
X560380Y1014866D01*
X561112Y1015598D01*
X561253Y1015456D01*
G37*
G36*
G01X564577Y1018780D02*
X564759Y1018396D01*
X564228Y1017866D01*
X563845Y1018048D01*
X563703Y1018189D01*
X564435Y1018921D01*
X564577Y1018780D01*
G37*
G36*
G01X562915Y1017118D02*
X563097Y1016734D01*
X562567Y1016204D01*
X562183Y1016386D01*
X562042Y1016528D01*
X562773Y1017259D01*
X562915Y1017118D01*
G37*
G36*
G01X562731Y1017500D02*
X562549Y1017883D01*
X563079Y1018414D01*
X563463Y1018232D01*
X563604Y1018090D01*
X562872Y1017358D01*
X562731Y1017500D01*
G37*
G36*
G01X558559Y1015025D02*
X558376Y1015409D01*
X558907Y1015939D01*
X559290Y1015757D01*
X559432Y1015616D01*
X558700Y1014884D01*
X558559Y1015025D01*
G37*
G36*
G01X560220Y1016687D02*
X560038Y1017071D01*
X560569Y1017601D01*
X560952Y1017419D01*
X561094Y1017278D01*
X560362Y1016546D01*
X560220Y1016687D01*
G37*
G36*
G01X560404Y1016305D02*
X560586Y1015922D01*
X560056Y1015391D01*
X559672Y1015573D01*
X559531Y1015715D01*
X560263Y1016447D01*
X560404Y1016305D01*
G37*
G36*
G01X562066Y1017967D02*
X562248Y1017583D01*
X561718Y1017053D01*
X561334Y1017235D01*
X561193Y1017377D01*
X561924Y1018108D01*
X562066Y1017967D01*
G37*
G36*
G01X561882Y1018349D02*
X561700Y1018732D01*
X562230Y1019263D01*
X562614Y1019081D01*
X562755Y1018939D01*
X562023Y1018207D01*
X561882Y1018349D01*
G37*
G36*
G01X563728Y1019629D02*
X563910Y1019245D01*
X563379Y1018715D01*
X562996Y1018897D01*
X562854Y1019038D01*
X563586Y1019770D01*
X563728Y1019629D01*
G37*
G36*
G01X561918Y1014989D02*
X561736Y1015373D01*
X562267Y1015903D01*
X562650Y1015721D01*
X562792Y1015580D01*
X562060Y1014848D01*
X561918Y1014989D01*
G37*
G36*
G01X563580Y1016651D02*
X563398Y1017034D01*
X563928Y1017565D01*
X564312Y1017383D01*
X564453Y1017241D01*
X563721Y1016509D01*
X563580Y1016651D01*
G37*
G36*
G01X563764Y1016269D02*
X563946Y1015885D01*
X563416Y1015355D01*
X563032Y1015537D01*
X562891Y1015679D01*
X563622Y1016410D01*
X563764Y1016269D01*
G37*
G36*
G01X558769Y1041246D02*
X558951Y1040863D01*
X558421Y1040332D01*
X558037Y1040514D01*
X557896Y1040656D01*
X558628Y1041388D01*
X558769Y1041246D01*
G37*
G36*
G01X556924Y1039966D02*
X556741Y1040350D01*
X557272Y1040880D01*
X557655Y1040698D01*
X557797Y1040557D01*
X557065Y1039825D01*
X556924Y1039966D01*
G37*
G36*
G01X557107Y1039585D02*
X557289Y1039201D01*
X556759Y1038671D01*
X556376Y1038853D01*
X556234Y1038994D01*
X556966Y1039726D01*
X557107Y1039585D01*
G37*
G36*
G01X555446Y1037923D02*
X555628Y1037539D01*
X555097Y1037009D01*
X554714Y1037191D01*
X554572Y1037332D01*
X555304Y1038064D01*
X555446Y1037923D01*
G37*
G36*
G01X553784Y1036261D02*
X553966Y1035878D01*
X553436Y1035347D01*
X553052Y1035529D01*
X552911Y1035671D01*
X553643Y1036403D01*
X553784Y1036261D01*
G37*
G36*
G01X558585Y1041628D02*
X558403Y1042012D01*
X558933Y1042542D01*
X559317Y1042360D01*
X559459Y1042219D01*
X558727Y1041487D01*
X558585Y1041628D01*
G37*
G36*
G01X560247Y1043290D02*
X560065Y1043673D01*
X560595Y1044204D01*
X560979Y1044022D01*
X561120Y1043880D01*
X560388Y1043148D01*
X560247Y1043290D01*
G37*
G36*
G01X562092Y1044570D02*
X562275Y1044186D01*
X561744Y1043656D01*
X561361Y1043838D01*
X561219Y1043979D01*
X561951Y1044711D01*
X562092Y1044570D01*
G37*
G36*
G01X563754Y1046231D02*
X563936Y1045848D01*
X563406Y1045317D01*
X563022Y1045499D01*
X562881Y1045641D01*
X563613Y1046373D01*
X563754Y1046231D01*
G37*
G36*
G01X561909Y1044951D02*
X561727Y1045335D01*
X562257Y1045865D01*
X562641Y1045683D01*
X562782Y1045542D01*
X562050Y1044810D01*
X561909Y1044951D01*
G37*
G36*
G01X563570Y1046613D02*
X563388Y1046997D01*
X563919Y1047527D01*
X564302Y1047345D01*
X564444Y1047204D01*
X563712Y1046472D01*
X563570Y1046613D01*
G37*
G36*
G01X560431Y1042908D02*
X560613Y1042524D01*
X560083Y1041994D01*
X559699Y1042176D01*
X559558Y1042318D01*
X560289Y1043049D01*
X560431Y1042908D01*
G37*
G36*
G01X555482Y1034563D02*
X555664Y1034180D01*
X555134Y1033649D01*
X554750Y1033831D01*
X554609Y1033973D01*
X555341Y1034705D01*
X555482Y1034563D01*
G37*
G36*
G01X558805Y1037887D02*
X558987Y1037503D01*
X558457Y1036973D01*
X558074Y1037155D01*
X557932Y1037296D01*
X558664Y1038028D01*
X558805Y1037887D01*
G37*
G36*
G01X558622Y1038268D02*
X558439Y1038652D01*
X558970Y1039182D01*
X559353Y1039000D01*
X559495Y1038859D01*
X558763Y1038127D01*
X558622Y1038268D01*
G37*
G36*
G01X557144Y1036225D02*
X557326Y1035841D01*
X556795Y1035311D01*
X556412Y1035493D01*
X556270Y1035634D01*
X557002Y1036366D01*
X557144Y1036225D01*
G37*
G36*
G01X556960Y1036607D02*
X556778Y1036990D01*
X557308Y1037521D01*
X557692Y1037339D01*
X557833Y1037197D01*
X557101Y1036465D01*
X556960Y1036607D01*
G37*
G36*
G01X555298Y1034945D02*
X555116Y1035329D01*
X555646Y1035859D01*
X556030Y1035677D01*
X556171Y1035535D01*
X555440Y1034804D01*
X555298Y1034945D01*
G37*
G36*
G01X565452Y1044533D02*
X565634Y1044150D01*
X565104Y1043619D01*
X564720Y1043801D01*
X564579Y1043943D01*
X565311Y1044675D01*
X565452Y1044533D01*
G37*
G36*
G01X563607Y1043253D02*
X563425Y1043637D01*
X563955Y1044167D01*
X564339Y1043985D01*
X564480Y1043844D01*
X563748Y1043112D01*
X563607Y1043253D01*
G37*
G36*
G01X563790Y1042872D02*
X563973Y1042488D01*
X563442Y1041958D01*
X563059Y1042140D01*
X562917Y1042281D01*
X563649Y1043013D01*
X563790Y1042872D01*
G37*
G36*
G01X560283Y1039930D02*
X560101Y1040314D01*
X560631Y1040844D01*
X561015Y1040662D01*
X561157Y1040521D01*
X560425Y1039789D01*
X560283Y1039930D01*
G37*
G36*
G01X560467Y1039548D02*
X560649Y1039165D01*
X560119Y1038634D01*
X559735Y1038816D01*
X559594Y1038958D01*
X560326Y1039690D01*
X560467Y1039548D01*
G37*
G36*
G01X562129Y1041210D02*
X562311Y1040826D01*
X561781Y1040296D01*
X561397Y1040478D01*
X561256Y1040620D01*
X561987Y1041351D01*
X562129Y1041210D01*
G37*
G36*
G01X561945Y1041592D02*
X561763Y1041975D01*
X562293Y1042506D01*
X562677Y1042324D01*
X562818Y1042182D01*
X562086Y1041450D01*
X561945Y1041592D01*
G37*
G36*
G01X565268Y1044915D02*
X565086Y1045299D01*
X565617Y1045829D01*
X566000Y1045647D01*
X566142Y1045506D01*
X565410Y1044774D01*
X565268Y1044915D01*
G37*
G36*
G01X554633Y1035412D02*
X554815Y1035029D01*
X554285Y1034498D01*
X553901Y1034680D01*
X553760Y1034822D01*
X554492Y1035554D01*
X554633Y1035412D01*
G37*
G36*
G01X559618Y1040397D02*
X559800Y1040014D01*
X559270Y1039483D01*
X558886Y1039665D01*
X558745Y1039807D01*
X559477Y1040539D01*
X559618Y1040397D01*
G37*
G36*
G01X557773Y1039117D02*
X557590Y1039501D01*
X558121Y1040031D01*
X558504Y1039849D01*
X558646Y1039708D01*
X557914Y1038976D01*
X557773Y1039117D01*
G37*
G36*
G01X557956Y1038736D02*
X558138Y1038352D01*
X557608Y1037822D01*
X557225Y1038004D01*
X557083Y1038145D01*
X557815Y1038877D01*
X557956Y1038736D01*
G37*
G36*
G01X556111Y1037456D02*
X555929Y1037839D01*
X556459Y1038370D01*
X556843Y1038188D01*
X556984Y1038046D01*
X556252Y1037314D01*
X556111Y1037456D01*
G37*
G36*
G01X556295Y1037074D02*
X556477Y1036690D01*
X555946Y1036160D01*
X555563Y1036342D01*
X555421Y1036483D01*
X556153Y1037215D01*
X556295Y1037074D01*
G37*
G36*
G01X554449Y1035794D02*
X554267Y1036178D01*
X554797Y1036708D01*
X555181Y1036526D01*
X555322Y1036384D01*
X554591Y1035653D01*
X554449Y1035794D01*
G37*
G36*
G01X562941Y1043721D02*
X563124Y1043337D01*
X562593Y1042807D01*
X562210Y1042989D01*
X562068Y1043130D01*
X562800Y1043862D01*
X562941Y1043721D01*
G37*
G36*
G01X564603Y1045382D02*
X564785Y1044999D01*
X564255Y1044468D01*
X563871Y1044650D01*
X563730Y1044792D01*
X564462Y1045524D01*
X564603Y1045382D01*
G37*
G36*
G01X562758Y1044102D02*
X562576Y1044486D01*
X563106Y1045016D01*
X563490Y1044834D01*
X563631Y1044693D01*
X562899Y1043961D01*
X562758Y1044102D01*
G37*
G36*
G01X564419Y1045764D02*
X564237Y1046148D01*
X564768Y1046678D01*
X565151Y1046496D01*
X565293Y1046355D01*
X564561Y1045623D01*
X564419Y1045764D01*
G37*
G36*
G01X561096Y1042441D02*
X560914Y1042824D01*
X561444Y1043355D01*
X561828Y1043173D01*
X561969Y1043031D01*
X561237Y1042299D01*
X561096Y1042441D01*
G37*
G36*
G01X561280Y1042059D02*
X561462Y1041675D01*
X560932Y1041145D01*
X560548Y1041327D01*
X560407Y1041469D01*
X561138Y1042200D01*
X561280Y1042059D01*
G37*
G36*
G01X559434Y1040779D02*
X559252Y1041163D01*
X559782Y1041693D01*
X560166Y1041511D01*
X560308Y1041370D01*
X559576Y1040638D01*
X559434Y1040779D01*
G37*
G36*
G01X566265Y1047044D02*
X566447Y1046660D01*
X565917Y1046130D01*
X565533Y1046312D01*
X565392Y1046454D01*
X566123Y1047185D01*
X566265Y1047044D01*
G37*
G36*
G01X557993Y1035376D02*
X558175Y1034992D01*
X557644Y1034462D01*
X557261Y1034644D01*
X557119Y1034785D01*
X557851Y1035517D01*
X557993Y1035376D01*
G37*
G36*
G01X556147Y1034096D02*
X555965Y1034480D01*
X556495Y1035010D01*
X556879Y1034828D01*
X557020Y1034686D01*
X556289Y1033955D01*
X556147Y1034096D01*
G37*
G36*
G01X556331Y1033714D02*
X556513Y1033331D01*
X555983Y1032800D01*
X555599Y1032982D01*
X555458Y1033124D01*
X556190Y1033856D01*
X556331Y1033714D01*
G37*
G36*
G01X559654Y1037038D02*
X559836Y1036654D01*
X559306Y1036124D01*
X558923Y1036306D01*
X558781Y1036447D01*
X559513Y1037179D01*
X559654Y1037038D01*
G37*
G36*
G01X557809Y1035758D02*
X557627Y1036141D01*
X558157Y1036672D01*
X558541Y1036490D01*
X558682Y1036348D01*
X557950Y1035616D01*
X557809Y1035758D01*
G37*
G36*
G01X564456Y1042404D02*
X564274Y1042788D01*
X564804Y1043318D01*
X565188Y1043136D01*
X565329Y1042995D01*
X564597Y1042263D01*
X564456Y1042404D01*
G37*
G36*
G01X561316Y1038699D02*
X561498Y1038316D01*
X560968Y1037785D01*
X560584Y1037967D01*
X560443Y1038109D01*
X561175Y1038841D01*
X561316Y1038699D01*
G37*
G36*
G01X559471Y1037419D02*
X559288Y1037803D01*
X559819Y1038333D01*
X560202Y1038151D01*
X560344Y1038010D01*
X559612Y1037278D01*
X559471Y1037419D01*
G37*
G36*
G01X561132Y1039081D02*
X560950Y1039465D01*
X561480Y1039995D01*
X561864Y1039813D01*
X562006Y1039672D01*
X561274Y1038940D01*
X561132Y1039081D01*
G37*
G36*
G01X562978Y1040361D02*
X563160Y1039977D01*
X562630Y1039447D01*
X562246Y1039629D01*
X562105Y1039771D01*
X562836Y1040502D01*
X562978Y1040361D01*
G37*
G36*
G01X562794Y1040743D02*
X562612Y1041126D01*
X563142Y1041657D01*
X563526Y1041475D01*
X563667Y1041333D01*
X562935Y1040601D01*
X562794Y1040743D01*
G37*
G36*
G01X566301Y1043684D02*
X566483Y1043301D01*
X565953Y1042770D01*
X565569Y1042952D01*
X565428Y1043094D01*
X566160Y1043826D01*
X566301Y1043684D01*
G37*
G36*
G01X564639Y1042023D02*
X564822Y1041639D01*
X564291Y1041109D01*
X563908Y1041291D01*
X563766Y1041432D01*
X564498Y1042164D01*
X564639Y1042023D01*
G37*
G36*
G01X565641Y1034532D02*
X565824Y1034148D01*
X565293Y1033618D01*
X564910Y1033800D01*
X564768Y1033941D01*
X565500Y1034673D01*
X565641Y1034532D01*
G37*
G36*
G01X563796Y1033252D02*
X563614Y1033635D01*
X564144Y1034166D01*
X564528Y1033984D01*
X564669Y1033842D01*
X563937Y1033110D01*
X563796Y1033252D01*
G37*
G36*
G01X562134Y1031590D02*
X561952Y1031974D01*
X562482Y1032504D01*
X562866Y1032322D01*
X563007Y1032180D01*
X562276Y1031449D01*
X562134Y1031590D01*
G37*
G36*
G01X563980Y1032870D02*
X564162Y1032486D01*
X563631Y1031956D01*
X563248Y1032138D01*
X563106Y1032279D01*
X563838Y1033011D01*
X563980Y1032870D01*
G37*
G36*
G01X565458Y1034913D02*
X565276Y1035297D01*
X565806Y1035827D01*
X566189Y1035645D01*
X566331Y1035504D01*
X565599Y1034772D01*
X565458Y1034913D01*
G37*
G36*
G01X565494Y1031554D02*
X565312Y1031937D01*
X565842Y1032468D01*
X566226Y1032286D01*
X566367Y1032144D01*
X565635Y1031412D01*
X565494Y1031554D01*
G37*
G36*
G01X564645Y1032403D02*
X564463Y1032786D01*
X564993Y1033317D01*
X565377Y1033135D01*
X565518Y1032993D01*
X564786Y1032261D01*
X564645Y1032403D01*
G37*
G36*
G01X566490Y1033683D02*
X566673Y1033299D01*
X566142Y1032769D01*
X565759Y1032951D01*
X565617Y1033092D01*
X566349Y1033824D01*
X566490Y1033683D01*
G37*
G36*
G01X564829Y1032021D02*
X565011Y1031637D01*
X564480Y1031107D01*
X564097Y1031289D01*
X563955Y1031430D01*
X564687Y1032162D01*
X564829Y1032021D01*
G37*
G36*
G01X554544Y1045669D02*
X554362Y1046053D01*
X554892Y1046583D01*
X555276Y1046401D01*
X555418Y1046260D01*
X554686Y1045528D01*
X554544Y1045669D01*
G37*
G36*
G01X554728Y1045287D02*
X554910Y1044904D01*
X554380Y1044373D01*
X553996Y1044555D01*
X553855Y1044697D01*
X554587Y1045429D01*
X554728Y1045287D01*
G37*
G36*
G01X556390Y1046949D02*
X556572Y1046565D01*
X556042Y1046035D01*
X555658Y1046217D01*
X555517Y1046359D01*
X556248Y1047090D01*
X556390Y1046949D01*
G37*
G36*
G01X556243Y1043971D02*
X556061Y1044354D01*
X556591Y1044885D01*
X556975Y1044702D01*
X557116Y1044561D01*
X556384Y1043829D01*
X556243Y1043971D01*
G37*
G36*
G01X558088Y1045250D02*
X558270Y1044867D01*
X557740Y1044337D01*
X557356Y1044519D01*
X557215Y1044660D01*
X557947Y1045392D01*
X558088Y1045250D01*
G37*
G36*
G01X559750Y1046912D02*
X559932Y1046529D01*
X559402Y1045998D01*
X559018Y1046180D01*
X558877Y1046322D01*
X559609Y1047054D01*
X559750Y1046912D01*
G37*
G36*
G01X557904Y1045632D02*
X557722Y1046016D01*
X558253Y1046546D01*
X558636Y1046364D01*
X558778Y1046223D01*
X558046Y1045491D01*
X557904Y1045632D01*
G37*
G36*
G01X556427Y1043589D02*
X556609Y1043205D01*
X556078Y1042675D01*
X555695Y1042857D01*
X555553Y1042998D01*
X556285Y1043730D01*
X556427Y1043589D01*
G37*
G36*
G01X555577Y1044438D02*
X555759Y1044055D01*
X555229Y1043524D01*
X554845Y1043706D01*
X554704Y1043848D01*
X555436Y1044580D01*
X555577Y1044438D01*
G37*
G36*
G01X557239Y1046100D02*
X557421Y1045716D01*
X556891Y1045186D01*
X556507Y1045368D01*
X556366Y1045510D01*
X557097Y1046241D01*
X557239Y1046100D01*
G37*
G36*
G01X558900Y1047762D02*
X559083Y1047378D01*
X558552Y1046848D01*
X558169Y1047030D01*
X558027Y1047171D01*
X558759Y1047903D01*
X558900Y1047762D01*
G37*
G36*
G01X557055Y1046482D02*
X556873Y1046865D01*
X557403Y1047396D01*
X557787Y1047214D01*
X557928Y1047072D01*
X557196Y1046340D01*
X557055Y1046482D01*
G37*
G36*
G01X555393Y1044820D02*
X555211Y1045204D01*
X555741Y1045734D01*
X556125Y1045552D01*
X556267Y1045411D01*
X555535Y1044679D01*
X555393Y1044820D01*
G37*
G36*
G01X557276Y1042739D02*
X557458Y1042356D01*
X556928Y1041825D01*
X556544Y1042007D01*
X556403Y1042149D01*
X557135Y1042881D01*
X557276Y1042739D01*
G37*
G36*
G01X558938Y1044401D02*
X559120Y1044017D01*
X558590Y1043487D01*
X558206Y1043669D01*
X558065Y1043811D01*
X558796Y1044542D01*
X558938Y1044401D01*
G37*
G36*
G01X557092Y1043121D02*
X556910Y1043505D01*
X557440Y1044035D01*
X557824Y1043853D01*
X557966Y1043712D01*
X557234Y1042980D01*
X557092Y1043121D01*
G37*
G36*
G01X558754Y1044783D02*
X558572Y1045166D01*
X559102Y1045697D01*
X559486Y1045515D01*
X559627Y1045373D01*
X558895Y1044641D01*
X558754Y1044783D01*
G37*
G36*
G01X562261Y1047724D02*
X562443Y1047341D01*
X561913Y1046810D01*
X561529Y1046992D01*
X561388Y1047134D01*
X562120Y1047866D01*
X562261Y1047724D01*
G37*
G36*
G01X560599Y1046063D02*
X560782Y1045679D01*
X560251Y1045149D01*
X559868Y1045331D01*
X559726Y1045472D01*
X560458Y1046204D01*
X560599Y1046063D01*
G37*
G36*
G01X560416Y1046444D02*
X560234Y1046828D01*
X560764Y1047358D01*
X561148Y1047176D01*
X561289Y1047035D01*
X560557Y1046303D01*
X560416Y1046444D01*
G37*
G36*
G01X565416Y1047893D02*
X565598Y1047509D01*
X565068Y1046979D01*
X564684Y1047161D01*
X564543Y1047303D01*
X565274Y1048034D01*
X565416Y1047893D01*
G37*
G36*
G01X565232Y1048275D02*
X565050Y1048658D01*
X565580Y1049189D01*
X565964Y1049007D01*
X566105Y1048865D01*
X565373Y1048133D01*
X565232Y1048275D01*
G37*
G36*
G01X552378Y1056667D02*
X552560Y1056283D01*
X552029Y1055753D01*
X551646Y1055935D01*
X551504Y1056076D01*
X552236Y1056808D01*
X552378Y1056667D01*
G37*
G36*
G01X554039Y1058329D02*
X554221Y1057945D01*
X553691Y1057415D01*
X553308Y1057597D01*
X553166Y1057738D01*
X553898Y1058470D01*
X554039Y1058329D01*
G37*
G36*
G01X559025Y1063314D02*
X559207Y1062930D01*
X558676Y1062400D01*
X558293Y1062582D01*
X558151Y1062723D01*
X558883Y1063455D01*
X559025Y1063314D01*
G37*
G36*
G01X557179Y1062034D02*
X556997Y1062417D01*
X557527Y1062948D01*
X557911Y1062766D01*
X558052Y1062624D01*
X557320Y1061892D01*
X557179Y1062034D01*
G37*
G36*
G01X555701Y1059990D02*
X555883Y1059607D01*
X555353Y1059076D01*
X554969Y1059258D01*
X554828Y1059400D01*
X555560Y1060132D01*
X555701Y1059990D01*
G37*
G36*
G01X557363Y1061652D02*
X557545Y1061268D01*
X557015Y1060738D01*
X556631Y1060920D01*
X556490Y1061062D01*
X557221Y1061793D01*
X557363Y1061652D01*
G37*
G36*
G01X557399Y1058292D02*
X557581Y1057908D01*
X557051Y1057378D01*
X556667Y1057560D01*
X556526Y1057702D01*
X557257Y1058433D01*
X557399Y1058292D01*
G37*
G36*
G01X555737Y1056630D02*
X555919Y1056247D01*
X555389Y1055716D01*
X555005Y1055898D01*
X554864Y1056040D01*
X555596Y1056772D01*
X555737Y1056630D01*
G37*
G36*
G01X554075Y1054969D02*
X554258Y1054585D01*
X553727Y1054055D01*
X553344Y1054237D01*
X553202Y1054378D01*
X553934Y1055110D01*
X554075Y1054969D01*
G37*
G36*
G01X555553Y1057012D02*
X555371Y1057396D01*
X555902Y1057926D01*
X556285Y1057744D01*
X556427Y1057603D01*
X555695Y1056871D01*
X555553Y1057012D01*
G37*
G36*
G01X553892Y1055350D02*
X553710Y1055734D01*
X554240Y1056264D01*
X554623Y1056082D01*
X554765Y1055941D01*
X554033Y1055209D01*
X553892Y1055350D01*
G37*
G36*
G01X552230Y1053689D02*
X552048Y1054072D01*
X552578Y1054603D01*
X552962Y1054421D01*
X553103Y1054279D01*
X552371Y1053547D01*
X552230Y1053689D01*
G37*
G36*
G01X559061Y1059954D02*
X559243Y1059570D01*
X558712Y1059040D01*
X558329Y1059222D01*
X558187Y1059363D01*
X558919Y1060095D01*
X559061Y1059954D01*
G37*
G36*
G01X558877Y1060336D02*
X558695Y1060719D01*
X559225Y1061249D01*
X559609Y1061067D01*
X559750Y1060926D01*
X559018Y1060194D01*
X558877Y1060336D01*
G37*
G36*
G01X557215Y1058674D02*
X557033Y1059057D01*
X557563Y1059588D01*
X557947Y1059406D01*
X558088Y1059264D01*
X557356Y1058532D01*
X557215Y1058674D01*
G37*
G36*
G01X560538Y1061997D02*
X560356Y1062381D01*
X560887Y1062911D01*
X561270Y1062729D01*
X561412Y1062588D01*
X560680Y1061856D01*
X560538Y1061997D01*
G37*
G36*
G01X560722Y1061615D02*
X560904Y1061232D01*
X560374Y1060701D01*
X559990Y1060884D01*
X559849Y1061025D01*
X560581Y1061757D01*
X560722Y1061615D01*
G37*
G36*
G01X562384Y1063277D02*
X562566Y1062893D01*
X562036Y1062363D01*
X561652Y1062545D01*
X561511Y1062687D01*
X562243Y1063419D01*
X562384Y1063277D01*
G37*
G36*
G01X554888Y1057479D02*
X555070Y1057096D01*
X554540Y1056565D01*
X554156Y1056748D01*
X554015Y1056889D01*
X554747Y1057621D01*
X554888Y1057479D01*
G37*
G36*
G01X553227Y1055818D02*
X553409Y1055434D01*
X552878Y1054904D01*
X552495Y1055086D01*
X552353Y1055227D01*
X553085Y1055959D01*
X553227Y1055818D01*
G37*
G36*
G01X553043Y1056200D02*
X552861Y1056583D01*
X553391Y1057114D01*
X553775Y1056931D01*
X553916Y1056790D01*
X553184Y1056058D01*
X553043Y1056200D01*
G37*
G36*
G01X558212Y1060803D02*
X558394Y1060419D01*
X557863Y1059889D01*
X557480Y1060071D01*
X557338Y1060212D01*
X558070Y1060944D01*
X558212Y1060803D01*
G37*
G36*
G01X556366Y1059523D02*
X556184Y1059907D01*
X556714Y1060437D01*
X557098Y1060255D01*
X557239Y1060113D01*
X556508Y1059382D01*
X556366Y1059523D01*
G37*
G36*
G01X558028Y1061185D02*
X557846Y1061568D01*
X558376Y1062099D01*
X558760Y1061917D01*
X558901Y1061775D01*
X558169Y1061043D01*
X558028Y1061185D01*
G37*
G36*
G01X556550Y1059141D02*
X556732Y1058758D01*
X556202Y1058227D01*
X555818Y1058409D01*
X555677Y1058551D01*
X556409Y1059283D01*
X556550Y1059141D01*
G37*
G36*
G01X554704Y1057861D02*
X554522Y1058245D01*
X555053Y1058775D01*
X555436Y1058593D01*
X555578Y1058452D01*
X554846Y1057720D01*
X554704Y1057861D01*
G37*
G36*
G01X559690Y1062846D02*
X559507Y1063230D01*
X560038Y1063760D01*
X560421Y1063578D01*
X560563Y1063437D01*
X559831Y1062705D01*
X559690Y1062846D01*
G37*
G36*
G01X559873Y1062465D02*
X560055Y1062081D01*
X559525Y1061551D01*
X559142Y1061733D01*
X559000Y1061874D01*
X559732Y1062606D01*
X559873Y1062465D01*
G37*
G36*
G01X558248Y1057443D02*
X558430Y1057059D01*
X557899Y1056529D01*
X557516Y1056711D01*
X557374Y1056852D01*
X558106Y1057584D01*
X558248Y1057443D01*
G37*
G36*
G01X558064Y1057825D02*
X557882Y1058208D01*
X558412Y1058739D01*
X558796Y1058557D01*
X558937Y1058415D01*
X558205Y1057683D01*
X558064Y1057825D01*
G37*
G36*
G01X556586Y1055781D02*
X556768Y1055398D01*
X556238Y1054867D01*
X555854Y1055049D01*
X555713Y1055191D01*
X556445Y1055923D01*
X556586Y1055781D01*
G37*
G36*
G01X554924Y1054119D02*
X555106Y1053736D01*
X554576Y1053206D01*
X554192Y1053388D01*
X554051Y1053529D01*
X554783Y1054261D01*
X554924Y1054119D01*
G37*
G36*
G01X556402Y1056163D02*
X556220Y1056547D01*
X556750Y1057077D01*
X557134Y1056895D01*
X557275Y1056753D01*
X556544Y1056022D01*
X556402Y1056163D01*
G37*
G36*
G01X554740Y1054501D02*
X554558Y1054885D01*
X555089Y1055415D01*
X555472Y1055233D01*
X555614Y1055092D01*
X554882Y1054360D01*
X554740Y1054501D01*
G37*
G36*
G01X559726Y1059486D02*
X559543Y1059870D01*
X560074Y1060400D01*
X560457Y1060218D01*
X560599Y1060077D01*
X559867Y1059345D01*
X559726Y1059486D01*
G37*
G36*
G01X561571Y1060766D02*
X561753Y1060383D01*
X561223Y1059852D01*
X560839Y1060034D01*
X560698Y1060176D01*
X561430Y1060908D01*
X561571Y1060766D01*
G37*
G36*
G01X561387Y1061148D02*
X561205Y1061532D01*
X561735Y1062062D01*
X562119Y1061880D01*
X562261Y1061739D01*
X561529Y1061007D01*
X561387Y1061148D01*
G37*
G36*
G01X563049Y1062810D02*
X562867Y1063193D01*
X563397Y1063724D01*
X563781Y1063542D01*
X563922Y1063400D01*
X563190Y1062668D01*
X563049Y1062810D01*
G37*
G36*
G01X563233Y1062428D02*
X563415Y1062044D01*
X562885Y1061514D01*
X562501Y1061696D01*
X562360Y1061838D01*
X563091Y1062569D01*
X563233Y1062428D01*
G37*
G36*
G01X559909Y1059105D02*
X560091Y1058721D01*
X559561Y1058191D01*
X559178Y1058373D01*
X559036Y1058514D01*
X559768Y1059246D01*
X559909Y1059105D01*
G37*
G36*
G01X564894Y1064090D02*
X565077Y1063706D01*
X564546Y1063176D01*
X564163Y1063358D01*
X564021Y1063499D01*
X564753Y1064231D01*
X564894Y1064090D01*
G37*
G36*
G01X556206Y1047331D02*
X556024Y1047714D01*
X556554Y1048245D01*
X556938Y1048063D01*
X557079Y1047921D01*
X556347Y1047189D01*
X556206Y1047331D01*
G37*
G36*
G01X557868Y1048992D02*
X557686Y1049376D01*
X558216Y1049906D01*
X558600Y1049724D01*
X558741Y1049583D01*
X558009Y1048851D01*
X557868Y1048992D01*
G37*
G36*
G01X558051Y1048611D02*
X558234Y1048227D01*
X557703Y1047697D01*
X557320Y1047879D01*
X557178Y1048020D01*
X557910Y1048752D01*
X558051Y1048611D01*
G37*
G36*
G01X559713Y1050272D02*
X559895Y1049889D01*
X559365Y1049358D01*
X558981Y1049540D01*
X558840Y1049682D01*
X559572Y1050414D01*
X559713Y1050272D01*
G37*
G36*
G01X559529Y1050654D02*
X559347Y1051038D01*
X559878Y1051568D01*
X560261Y1051386D01*
X560403Y1051245D01*
X559671Y1050513D01*
X559529Y1050654D01*
G37*
G36*
G01X561375Y1051934D02*
X561557Y1051550D01*
X561027Y1051020D01*
X560643Y1051202D01*
X560502Y1051344D01*
X561233Y1052075D01*
X561375Y1051934D01*
G37*
G36*
G01X562853Y1053978D02*
X562671Y1054361D01*
X563201Y1054892D01*
X563585Y1054709D01*
X563726Y1054568D01*
X562994Y1053836D01*
X562853Y1053978D01*
G37*
G36*
G01X564514Y1055639D02*
X564332Y1056023D01*
X564863Y1056553D01*
X565246Y1056371D01*
X565388Y1056230D01*
X564656Y1055498D01*
X564514Y1055639D01*
G37*
G36*
G01X561191Y1052316D02*
X561009Y1052699D01*
X561539Y1053230D01*
X561923Y1053048D01*
X562064Y1052906D01*
X561332Y1052174D01*
X561191Y1052316D01*
G37*
G36*
G01X563037Y1053596D02*
X563219Y1053212D01*
X562688Y1052682D01*
X562305Y1052864D01*
X562163Y1053005D01*
X562895Y1053737D01*
X563037Y1053596D01*
G37*
G36*
G01X564698Y1055257D02*
X564880Y1054874D01*
X564350Y1054344D01*
X563966Y1054526D01*
X563825Y1054667D01*
X564557Y1055399D01*
X564698Y1055257D01*
G37*
G36*
G01X566360Y1056919D02*
X566542Y1056536D01*
X566012Y1056005D01*
X565628Y1056187D01*
X565487Y1056329D01*
X566219Y1057061D01*
X566360Y1056919D01*
G37*
G36*
G01X564735Y1051897D02*
X564917Y1051514D01*
X564387Y1050983D01*
X564003Y1051165D01*
X563862Y1051307D01*
X564594Y1052039D01*
X564735Y1051897D01*
G37*
G36*
G01X561228Y1048956D02*
X561046Y1049339D01*
X561576Y1049870D01*
X561960Y1049688D01*
X562101Y1049546D01*
X561369Y1048814D01*
X561228Y1048956D01*
G37*
G36*
G01X562890Y1050617D02*
X562707Y1051001D01*
X563238Y1051531D01*
X563621Y1051349D01*
X563763Y1051208D01*
X563031Y1050476D01*
X562890Y1050617D01*
G37*
G36*
G01X563073Y1050236D02*
X563255Y1049852D01*
X562725Y1049322D01*
X562342Y1049504D01*
X562200Y1049645D01*
X562932Y1050377D01*
X563073Y1050236D01*
G37*
G36*
G01X566397Y1053559D02*
X566579Y1053175D01*
X566049Y1052645D01*
X565665Y1052827D01*
X565524Y1052969D01*
X566255Y1053700D01*
X566397Y1053559D01*
G37*
G36*
G01X564551Y1052279D02*
X564369Y1052663D01*
X564899Y1053193D01*
X565283Y1053011D01*
X565425Y1052870D01*
X564693Y1052138D01*
X564551Y1052279D01*
G37*
G36*
G01X561412Y1048574D02*
X561594Y1048190D01*
X561063Y1047660D01*
X560680Y1047842D01*
X560538Y1047983D01*
X561270Y1048715D01*
X561412Y1048574D01*
G37*
G36*
G01X559566Y1047294D02*
X559384Y1047678D01*
X559914Y1048208D01*
X560298Y1048026D01*
X560439Y1047884D01*
X559708Y1047153D01*
X559566Y1047294D01*
G37*
G36*
G01X558717Y1048143D02*
X558535Y1048527D01*
X559065Y1049057D01*
X559449Y1048875D01*
X559590Y1048734D01*
X558858Y1048002D01*
X558717Y1048143D01*
G37*
G36*
G01X562224Y1051085D02*
X562406Y1050701D01*
X561876Y1050171D01*
X561492Y1050353D01*
X561351Y1050495D01*
X562082Y1051226D01*
X562224Y1051085D01*
G37*
G36*
G01X562040Y1051467D02*
X561858Y1051850D01*
X562388Y1052381D01*
X562772Y1052199D01*
X562913Y1052057D01*
X562181Y1051325D01*
X562040Y1051467D01*
G37*
G36*
G01X560378Y1049805D02*
X560196Y1050189D01*
X560727Y1050719D01*
X561110Y1050537D01*
X561252Y1050396D01*
X560520Y1049664D01*
X560378Y1049805D01*
G37*
G36*
G01X565547Y1054408D02*
X565729Y1054025D01*
X565199Y1053495D01*
X564815Y1053677D01*
X564674Y1053818D01*
X565406Y1054550D01*
X565547Y1054408D01*
G37*
G36*
G01X563886Y1052747D02*
X564068Y1052363D01*
X563537Y1051833D01*
X563154Y1052015D01*
X563012Y1052156D01*
X563744Y1052888D01*
X563886Y1052747D01*
G37*
G36*
G01X565363Y1054790D02*
X565181Y1055174D01*
X565712Y1055704D01*
X566095Y1055522D01*
X566237Y1055381D01*
X565505Y1054649D01*
X565363Y1054790D01*
G37*
G36*
G01X563702Y1053129D02*
X563520Y1053512D01*
X564050Y1054043D01*
X564434Y1053860D01*
X564575Y1053719D01*
X563843Y1052987D01*
X563702Y1053129D01*
G37*
G36*
G01X560562Y1049423D02*
X560744Y1049040D01*
X560214Y1048509D01*
X559830Y1048691D01*
X559689Y1048833D01*
X560421Y1049565D01*
X560562Y1049423D01*
G37*
G36*
G01X565401Y1051430D02*
X565219Y1051813D01*
X565749Y1052344D01*
X566133Y1052161D01*
X566274Y1052020D01*
X565542Y1051288D01*
X565401Y1051430D01*
G37*
G36*
G01X565585Y1051048D02*
X565767Y1050664D01*
X565236Y1050134D01*
X564853Y1050316D01*
X564711Y1050457D01*
X565443Y1051189D01*
X565585Y1051048D01*
G37*
G36*
G01X563739Y1049768D02*
X563557Y1050151D01*
X564087Y1050682D01*
X564471Y1050500D01*
X564612Y1050358D01*
X563880Y1049626D01*
X563739Y1049768D01*
G37*
G36*
G01X563923Y1049386D02*
X564105Y1049002D01*
X563575Y1048472D01*
X563191Y1048654D01*
X563050Y1048796D01*
X563781Y1049527D01*
X563923Y1049386D01*
G37*
G36*
G01X562077Y1048106D02*
X561895Y1048490D01*
X562426Y1049020D01*
X562809Y1048838D01*
X562951Y1048697D01*
X562219Y1047965D01*
X562077Y1048106D01*
G37*
G36*
G01X555004Y1078493D02*
X554822Y1078877D01*
X555352Y1079407D01*
X555736Y1079225D01*
X555878Y1079084D01*
X555146Y1078352D01*
X555004Y1078493D01*
G37*
G36*
G01X556850Y1079773D02*
X557032Y1079389D01*
X556502Y1078859D01*
X556118Y1079041D01*
X555977Y1079183D01*
X556708Y1079914D01*
X556850Y1079773D01*
G37*
G36*
G01X557700Y1078923D02*
X557882Y1078539D01*
X557352Y1078009D01*
X556968Y1078191D01*
X556827Y1078333D01*
X557558Y1079064D01*
X557700Y1078923D01*
G37*
G36*
G01X557516Y1079305D02*
X557334Y1079688D01*
X557864Y1080219D01*
X558248Y1080037D01*
X558389Y1079895D01*
X557657Y1079163D01*
X557516Y1079305D01*
G37*
G36*
G01X554815Y1067525D02*
X554997Y1067141D01*
X554467Y1066611D01*
X554083Y1066793D01*
X553942Y1066934D01*
X554673Y1067666D01*
X554815Y1067525D01*
G37*
G36*
G01X554631Y1067906D02*
X554449Y1068290D01*
X554979Y1068820D01*
X555363Y1068638D01*
X555504Y1068497D01*
X554773Y1067765D01*
X554631Y1067906D01*
G37*
G36*
G01X559801Y1072509D02*
X559983Y1072125D01*
X559453Y1071595D01*
X559069Y1071777D01*
X558928Y1071919D01*
X559659Y1072650D01*
X559801Y1072509D01*
G37*
G36*
G01X557955Y1071229D02*
X557773Y1071613D01*
X558303Y1072143D01*
X558687Y1071961D01*
X558828Y1071820D01*
X558097Y1071088D01*
X557955Y1071229D01*
G37*
G36*
G01X556293Y1069568D02*
X556111Y1069951D01*
X556641Y1070482D01*
X557025Y1070300D01*
X557166Y1070158D01*
X556435Y1069426D01*
X556293Y1069568D01*
G37*
G36*
G01X558139Y1070848D02*
X558321Y1070464D01*
X557791Y1069934D01*
X557407Y1070116D01*
X557266Y1070257D01*
X557997Y1070989D01*
X558139Y1070848D01*
G37*
G36*
G01X556477Y1069186D02*
X556659Y1068803D01*
X556129Y1068272D01*
X555745Y1068454D01*
X555604Y1068596D01*
X556335Y1069328D01*
X556477Y1069186D01*
G37*
G36*
G01X561279Y1074552D02*
X561097Y1074936D01*
X561627Y1075466D01*
X562011Y1075284D01*
X562152Y1075143D01*
X561420Y1074411D01*
X561279Y1074552D01*
G37*
G36*
G01X561463Y1074170D02*
X561645Y1073787D01*
X561115Y1073256D01*
X560731Y1073439D01*
X560589Y1073580D01*
X561321Y1074312D01*
X561463Y1074170D01*
G37*
G36*
G01X563125Y1075832D02*
X563307Y1075448D01*
X562776Y1074918D01*
X562393Y1075100D01*
X562251Y1075241D01*
X562983Y1075973D01*
X563125Y1075832D01*
G37*
G36*
G01X562941Y1076214D02*
X562759Y1076597D01*
X563289Y1077127D01*
X563673Y1076945D01*
X563814Y1076804D01*
X563082Y1076072D01*
X562941Y1076214D01*
G37*
G36*
G01X564603Y1077875D02*
X564421Y1078259D01*
X564951Y1078789D01*
X565335Y1078607D01*
X565476Y1078465D01*
X564744Y1077734D01*
X564603Y1077875D01*
G37*
G36*
G01X564787Y1077493D02*
X564969Y1077110D01*
X564438Y1076579D01*
X564055Y1076761D01*
X563913Y1076903D01*
X564645Y1077635D01*
X564787Y1077493D01*
G37*
G36*
G01X566449Y1079155D02*
X566631Y1078771D01*
X566100Y1078241D01*
X565717Y1078423D01*
X565575Y1078564D01*
X566307Y1079296D01*
X566449Y1079155D01*
G37*
G36*
G01X559617Y1072891D02*
X559435Y1073274D01*
X559965Y1073805D01*
X560349Y1073623D01*
X560490Y1073481D01*
X559758Y1072749D01*
X559617Y1072891D01*
G37*
G36*
G01X558177Y1067486D02*
X558359Y1067102D01*
X557828Y1066572D01*
X557445Y1066754D01*
X557303Y1066895D01*
X558035Y1067627D01*
X558177Y1067486D01*
G37*
G36*
G01X556515Y1065824D02*
X556697Y1065440D01*
X556167Y1064910D01*
X555783Y1065092D01*
X555642Y1065234D01*
X556374Y1065966D01*
X556515Y1065824D01*
G37*
G36*
G01X556331Y1066206D02*
X556149Y1066590D01*
X556679Y1067120D01*
X557063Y1066938D01*
X557204Y1066796D01*
X556473Y1066065D01*
X556331Y1066206D01*
G37*
G36*
G01X557993Y1067868D02*
X557811Y1068251D01*
X558341Y1068782D01*
X558725Y1068599D01*
X558866Y1068458D01*
X558134Y1067726D01*
X557993Y1067868D01*
G37*
G36*
G01X554669Y1064544D02*
X554487Y1064928D01*
X555018Y1065458D01*
X555401Y1065276D01*
X555543Y1065135D01*
X554811Y1064403D01*
X554669Y1064544D01*
G37*
G36*
G01X561316Y1071191D02*
X561134Y1071575D01*
X561664Y1072105D01*
X562048Y1071923D01*
X562189Y1071781D01*
X561458Y1071050D01*
X561316Y1071191D01*
G37*
G36*
G01X561500Y1070809D02*
X561682Y1070426D01*
X561152Y1069895D01*
X560768Y1070077D01*
X560627Y1070219D01*
X561359Y1070951D01*
X561500Y1070809D01*
G37*
G36*
G01X559654Y1069529D02*
X559472Y1069913D01*
X560003Y1070443D01*
X560386Y1070261D01*
X560528Y1070120D01*
X559796Y1069388D01*
X559654Y1069529D01*
G37*
G36*
G01X563162Y1072471D02*
X563344Y1072087D01*
X562813Y1071557D01*
X562430Y1071739D01*
X562288Y1071880D01*
X563020Y1072612D01*
X563162Y1072471D01*
G37*
G36*
G01X559838Y1069147D02*
X560020Y1068764D01*
X559490Y1068234D01*
X559106Y1068416D01*
X558965Y1068557D01*
X559697Y1069289D01*
X559838Y1069147D01*
G37*
G36*
G01X564823Y1074133D02*
X565006Y1073749D01*
X564475Y1073219D01*
X564092Y1073401D01*
X563950Y1073542D01*
X564682Y1074274D01*
X564823Y1074133D01*
G37*
G36*
G01X562978Y1072853D02*
X562796Y1073236D01*
X563326Y1073767D01*
X563710Y1073585D01*
X563851Y1073443D01*
X563119Y1072711D01*
X562978Y1072853D01*
G37*
G36*
G01X566485Y1075794D02*
X566667Y1075411D01*
X566137Y1074880D01*
X565753Y1075062D01*
X565612Y1075204D01*
X566344Y1075936D01*
X566485Y1075794D01*
G37*
G36*
G01X564640Y1074514D02*
X564458Y1074898D01*
X564988Y1075428D01*
X565371Y1075246D01*
X565513Y1075105D01*
X564781Y1074373D01*
X564640Y1074514D01*
G37*
G36*
G01X555666Y1066673D02*
X555848Y1066290D01*
X555318Y1065759D01*
X554934Y1065941D01*
X554793Y1066083D01*
X555525Y1066815D01*
X555666Y1066673D01*
G37*
G36*
G01X555482Y1067055D02*
X555300Y1067439D01*
X555830Y1067969D01*
X556214Y1067787D01*
X556356Y1067646D01*
X555624Y1066914D01*
X555482Y1067055D01*
G37*
G36*
G01X557328Y1068335D02*
X557510Y1067951D01*
X556980Y1067421D01*
X556596Y1067603D01*
X556454Y1067744D01*
X557186Y1068476D01*
X557328Y1068335D01*
G37*
G36*
G01X558989Y1069997D02*
X559172Y1069613D01*
X558641Y1069083D01*
X558258Y1069265D01*
X558116Y1069406D01*
X558848Y1070138D01*
X558989Y1069997D01*
G37*
G36*
G01X558806Y1070378D02*
X558624Y1070762D01*
X559154Y1071292D01*
X559537Y1071110D01*
X559679Y1070969D01*
X558947Y1070237D01*
X558806Y1070378D01*
G37*
G36*
G01X557144Y1068717D02*
X556962Y1069100D01*
X557492Y1069631D01*
X557876Y1069449D01*
X558017Y1069307D01*
X557285Y1068575D01*
X557144Y1068717D01*
G37*
G36*
G01X560651Y1071658D02*
X560833Y1071275D01*
X560303Y1070744D01*
X559919Y1070926D01*
X559778Y1071068D01*
X560510Y1071800D01*
X560651Y1071658D01*
G37*
G36*
G01X563975Y1074982D02*
X564157Y1074598D01*
X563626Y1074068D01*
X563243Y1074250D01*
X563101Y1074391D01*
X563833Y1075123D01*
X563975Y1074982D01*
G37*
G36*
G01X562129Y1073702D02*
X561947Y1074085D01*
X562477Y1074616D01*
X562861Y1074434D01*
X563002Y1074292D01*
X562270Y1073560D01*
X562129Y1073702D01*
G37*
G36*
G01X565636Y1076643D02*
X565818Y1076260D01*
X565288Y1075729D01*
X564904Y1075912D01*
X564763Y1076053D01*
X565495Y1076785D01*
X565636Y1076643D01*
G37*
G36*
G01X563791Y1075364D02*
X563609Y1075747D01*
X564139Y1076278D01*
X564523Y1076095D01*
X564664Y1075954D01*
X563932Y1075222D01*
X563791Y1075364D01*
G37*
G36*
G01X565452Y1077025D02*
X565270Y1077409D01*
X565801Y1077939D01*
X566184Y1077757D01*
X566326Y1077616D01*
X565594Y1076884D01*
X565452Y1077025D01*
G37*
G36*
G01X562313Y1073320D02*
X562495Y1072936D01*
X561965Y1072406D01*
X561581Y1072588D01*
X561440Y1072730D01*
X562171Y1073461D01*
X562313Y1073320D01*
G37*
G36*
G01X560467Y1072040D02*
X560285Y1072424D01*
X560816Y1072954D01*
X561199Y1072772D01*
X561341Y1072631D01*
X560609Y1071899D01*
X560467Y1072040D01*
G37*
G36*
G01X559026Y1066636D02*
X559208Y1066253D01*
X558678Y1065722D01*
X558294Y1065904D01*
X558153Y1066046D01*
X558885Y1066778D01*
X559026Y1066636D01*
G37*
G36*
G01X558842Y1067018D02*
X558660Y1067402D01*
X559190Y1067932D01*
X559574Y1067750D01*
X559715Y1067608D01*
X558984Y1066877D01*
X558842Y1067018D01*
G37*
G36*
G01X555519Y1063695D02*
X555337Y1064078D01*
X555867Y1064609D01*
X556251Y1064426D01*
X556392Y1064285D01*
X555660Y1063553D01*
X555519Y1063695D01*
G37*
G36*
G01X557364Y1064974D02*
X557546Y1064591D01*
X557016Y1064061D01*
X556632Y1064243D01*
X556491Y1064384D01*
X557223Y1065116D01*
X557364Y1064974D01*
G37*
G36*
G01X557180Y1065356D02*
X556998Y1065740D01*
X557529Y1066270D01*
X557912Y1066088D01*
X558054Y1065947D01*
X557322Y1065215D01*
X557180Y1065356D01*
G37*
G36*
G01X560688Y1068298D02*
X560870Y1067914D01*
X560339Y1067384D01*
X559956Y1067566D01*
X559814Y1067707D01*
X560546Y1068439D01*
X560688Y1068298D01*
G37*
G36*
G01X560504Y1068680D02*
X560322Y1069063D01*
X560852Y1069594D01*
X561236Y1069412D01*
X561377Y1069270D01*
X560645Y1068538D01*
X560504Y1068680D01*
G37*
G36*
G01X564011Y1071621D02*
X564193Y1071238D01*
X563663Y1070707D01*
X563279Y1070889D01*
X563138Y1071031D01*
X563870Y1071763D01*
X564011Y1071621D01*
G37*
G36*
G01X562349Y1069960D02*
X562531Y1069576D01*
X562001Y1069046D01*
X561618Y1069228D01*
X561476Y1069369D01*
X562208Y1070101D01*
X562349Y1069960D01*
G37*
G36*
G01X562166Y1070341D02*
X561983Y1070725D01*
X562514Y1071255D01*
X562897Y1071073D01*
X563039Y1070932D01*
X562307Y1070200D01*
X562166Y1070341D01*
G37*
G36*
G01X565489Y1073665D02*
X565307Y1074048D01*
X565837Y1074579D01*
X566221Y1074397D01*
X566362Y1074255D01*
X565630Y1073523D01*
X565489Y1073665D01*
G37*
G36*
G01X565673Y1073283D02*
X565855Y1072899D01*
X565325Y1072369D01*
X564941Y1072551D01*
X564800Y1072693D01*
X565531Y1073424D01*
X565673Y1073283D01*
G37*
G36*
G01X563827Y1072003D02*
X563645Y1072387D01*
X564175Y1072917D01*
X564559Y1072735D01*
X564701Y1072594D01*
X563969Y1071862D01*
X563827Y1072003D01*
G37*
G36*
G01X558841Y1063696D02*
X558659Y1064079D01*
X559189Y1064609D01*
X559573Y1064427D01*
X559714Y1064286D01*
X558982Y1063554D01*
X558841Y1063696D01*
G37*
G36*
G01X560686Y1064975D02*
X560868Y1064592D01*
X560338Y1064061D01*
X559954Y1064244D01*
X559813Y1064385D01*
X560545Y1065117D01*
X560686Y1064975D01*
G37*
G36*
G01X560502Y1065357D02*
X560320Y1065741D01*
X560851Y1066271D01*
X561234Y1066089D01*
X561376Y1065948D01*
X560644Y1065216D01*
X560502Y1065357D01*
G37*
G36*
G01X562348Y1066637D02*
X562530Y1066253D01*
X562000Y1065723D01*
X561616Y1065905D01*
X561475Y1066047D01*
X562206Y1066778D01*
X562348Y1066637D01*
G37*
G36*
G01X562164Y1067019D02*
X561982Y1067403D01*
X562512Y1067933D01*
X562896Y1067751D01*
X563037Y1067609D01*
X562305Y1066877D01*
X562164Y1067019D01*
G37*
G36*
G01X564010Y1068299D02*
X564192Y1067915D01*
X563661Y1067385D01*
X563278Y1067567D01*
X563136Y1067708D01*
X563868Y1068440D01*
X564010Y1068299D01*
G37*
G36*
G01X563826Y1068681D02*
X563644Y1069064D01*
X564174Y1069595D01*
X564558Y1069412D01*
X564699Y1069271D01*
X563967Y1068539D01*
X563826Y1068681D01*
G37*
G36*
G01X565671Y1069960D02*
X565853Y1069577D01*
X565323Y1069047D01*
X564939Y1069229D01*
X564798Y1069370D01*
X565530Y1070102D01*
X565671Y1069960D01*
G37*
G36*
G01X565487Y1070342D02*
X565305Y1070726D01*
X565836Y1071256D01*
X566219Y1071074D01*
X566361Y1070933D01*
X565629Y1070201D01*
X565487Y1070342D01*
G37*
G36*
G01X564046Y1064939D02*
X564228Y1064555D01*
X563697Y1064025D01*
X563314Y1064207D01*
X563172Y1064348D01*
X563904Y1065080D01*
X564046Y1064939D01*
G37*
G36*
G01X562200Y1063659D02*
X562018Y1064043D01*
X562548Y1064573D01*
X562932Y1064391D01*
X563073Y1064249D01*
X562342Y1063518D01*
X562200Y1063659D01*
G37*
G36*
G01X563862Y1065321D02*
X563680Y1065704D01*
X564210Y1066235D01*
X564594Y1066052D01*
X564735Y1065911D01*
X564003Y1065179D01*
X563862Y1065321D01*
G37*
G36*
G01X565707Y1066600D02*
X565889Y1066217D01*
X565359Y1065687D01*
X564975Y1065869D01*
X564834Y1066010D01*
X565566Y1066742D01*
X565707Y1066600D01*
G37*
G36*
G01X565523Y1066982D02*
X565341Y1067366D01*
X565872Y1067896D01*
X566255Y1067714D01*
X566397Y1067573D01*
X565665Y1066841D01*
X565523Y1066982D01*
G37*
G36*
G01X564675Y1067831D02*
X564493Y1068215D01*
X565023Y1068745D01*
X565406Y1068563D01*
X565548Y1068422D01*
X564816Y1067690D01*
X564675Y1067831D01*
G37*
G36*
G01X561535Y1064126D02*
X561717Y1063743D01*
X561187Y1063212D01*
X560803Y1063394D01*
X560662Y1063536D01*
X561394Y1064268D01*
X561535Y1064126D01*
G37*
G36*
G01X561351Y1064508D02*
X561169Y1064892D01*
X561699Y1065422D01*
X562083Y1065240D01*
X562225Y1065099D01*
X561493Y1064367D01*
X561351Y1064508D01*
G37*
G36*
G01X563197Y1065788D02*
X563379Y1065404D01*
X562849Y1064874D01*
X562465Y1065056D01*
X562324Y1065198D01*
X563055Y1065929D01*
X563197Y1065788D01*
G37*
G36*
G01X563013Y1066170D02*
X562831Y1066553D01*
X563361Y1067084D01*
X563745Y1066902D01*
X563886Y1066760D01*
X563154Y1066028D01*
X563013Y1066170D01*
G37*
G36*
G01X564858Y1067450D02*
X565041Y1067066D01*
X564510Y1066536D01*
X564127Y1066718D01*
X563985Y1066859D01*
X564717Y1067591D01*
X564858Y1067450D01*
G37*
G36*
G01X566520Y1069111D02*
X566702Y1068728D01*
X566172Y1068197D01*
X565788Y1068379D01*
X565647Y1068521D01*
X566379Y1069253D01*
X566520Y1069111D01*
G37*
G36*
G01X564711Y1064471D02*
X564529Y1064855D01*
X565059Y1065385D01*
X565443Y1065203D01*
X565584Y1065062D01*
X564852Y1064330D01*
X564711Y1064471D01*
G37*
G36*
G01X554968Y1081853D02*
X554786Y1082236D01*
X555316Y1082767D01*
X555700Y1082585D01*
X555841Y1082443D01*
X555109Y1081711D01*
X554968Y1081853D01*
G37*
G36*
G01X555152Y1081471D02*
X555334Y1081087D01*
X554804Y1080557D01*
X554420Y1080739D01*
X554279Y1080881D01*
X555010Y1081612D01*
X555152Y1081471D01*
G37*
G36*
G01X556813Y1083133D02*
X556996Y1082749D01*
X556465Y1082219D01*
X556082Y1082401D01*
X555940Y1082542D01*
X556672Y1083274D01*
X556813Y1083133D01*
G37*
G36*
G01X556630Y1083514D02*
X556448Y1083898D01*
X556978Y1084428D01*
X557362Y1084246D01*
X557503Y1084105D01*
X556771Y1083373D01*
X556630Y1083514D01*
G37*
G36*
G01X558475Y1084794D02*
X558657Y1084411D01*
X558127Y1083880D01*
X557743Y1084063D01*
X557602Y1084204D01*
X558334Y1084936D01*
X558475Y1084794D01*
G37*
G36*
G01X558291Y1085176D02*
X558109Y1085560D01*
X558640Y1086090D01*
X559023Y1085908D01*
X559165Y1085767D01*
X558433Y1085035D01*
X558291Y1085176D01*
G37*
G36*
G01X561153Y1094491D02*
X560789Y1094709D01*
X560936Y1095445D01*
X561356Y1095506D01*
X561552Y1095467D01*
X561349Y1094452D01*
X561153Y1094491D01*
G37*
G36*
G01X561978Y1096580D02*
X562342Y1096362D01*
X562195Y1095626D01*
X561775Y1095565D01*
X561579Y1095604D01*
X561782Y1096619D01*
X561978Y1096580D01*
G37*
G36*
G01X561058Y1091971D02*
X561422Y1091753D01*
X561275Y1091017D01*
X560855Y1090956D01*
X560659Y1090995D01*
X560862Y1092010D01*
X561058Y1091971D01*
G37*
G36*
G01X560598Y1089666D02*
X560962Y1089448D01*
X560815Y1088713D01*
X560395Y1088651D01*
X560198Y1088691D01*
X560401Y1089706D01*
X560598Y1089666D01*
G37*
G36*
G01X560232Y1089882D02*
X559868Y1090100D01*
X560015Y1090836D01*
X560435Y1090897D01*
X560632Y1090858D01*
X560429Y1089843D01*
X560232Y1089882D01*
G37*
G36*
G01X559772Y1087578D02*
X559408Y1087796D01*
X559555Y1088531D01*
X559975Y1088593D01*
X560171Y1088553D01*
X559968Y1087538D01*
X559772Y1087578D01*
G37*
G36*
G01X560693Y1092187D02*
X560328Y1092405D01*
X560475Y1093140D01*
X560896Y1093202D01*
X561092Y1093162D01*
X560889Y1092147D01*
X560693Y1092187D01*
G37*
G36*
G01X561518Y1094275D02*
X561882Y1094057D01*
X561735Y1093322D01*
X561315Y1093260D01*
X561119Y1093300D01*
X561322Y1094315D01*
X561518Y1094275D01*
G37*
G36*
G01X558511Y1081435D02*
X558694Y1081051D01*
X558163Y1080521D01*
X557780Y1080703D01*
X557638Y1080844D01*
X558370Y1081576D01*
X558511Y1081435D01*
G37*
G36*
G01X556666Y1080155D02*
X556484Y1080538D01*
X557014Y1081069D01*
X557398Y1080887D01*
X557539Y1080745D01*
X556807Y1080013D01*
X556666Y1080155D01*
G37*
G36*
G01X558328Y1081816D02*
X558146Y1082200D01*
X558676Y1082730D01*
X559060Y1082548D01*
X559201Y1082407D01*
X558469Y1081675D01*
X558328Y1081816D01*
G37*
G36*
G01X559989Y1083478D02*
X559807Y1083862D01*
X560338Y1084392D01*
X560721Y1084210D01*
X560863Y1084069D01*
X560131Y1083337D01*
X559989Y1083478D01*
G37*
G36*
G01X560173Y1083096D02*
X560355Y1082713D01*
X559825Y1082182D01*
X559441Y1082365D01*
X559300Y1082506D01*
X560032Y1083238D01*
X560173Y1083096D01*
G37*
G36*
G01X563416Y1091500D02*
X563780Y1091282D01*
X563633Y1090547D01*
X563213Y1090485D01*
X563017Y1090524D01*
X563220Y1091539D01*
X563416Y1091500D01*
G37*
G36*
G01X562955Y1089196D02*
X563319Y1088978D01*
X563172Y1088242D01*
X562752Y1088181D01*
X562556Y1088220D01*
X562759Y1089235D01*
X562955Y1089196D01*
G37*
G36*
G01X562494Y1086891D02*
X562859Y1086673D01*
X562712Y1085938D01*
X562292Y1085876D01*
X562095Y1085915D01*
X562298Y1086930D01*
X562494Y1086891D01*
G37*
G36*
G01X563051Y1091716D02*
X562687Y1091934D01*
X562834Y1092669D01*
X563254Y1092731D01*
X563450Y1092691D01*
X563247Y1091677D01*
X563051Y1091716D01*
G37*
G36*
G01X562590Y1089411D02*
X562226Y1089629D01*
X562373Y1090365D01*
X562793Y1090426D01*
X562989Y1090387D01*
X562786Y1089372D01*
X562590Y1089411D01*
G37*
G36*
G01X562130Y1087107D02*
X561765Y1087325D01*
X561912Y1088061D01*
X562333Y1088122D01*
X562529Y1088083D01*
X562326Y1087068D01*
X562130Y1087107D01*
G37*
G36*
G01X564337Y1096109D02*
X564701Y1095891D01*
X564554Y1095155D01*
X564134Y1095094D01*
X563938Y1095133D01*
X564141Y1096148D01*
X564337Y1096109D01*
G37*
G36*
G01X563876Y1093804D02*
X564241Y1093586D01*
X564094Y1092851D01*
X563674Y1092790D01*
X563477Y1092829D01*
X563680Y1093844D01*
X563876Y1093804D01*
G37*
G36*
G01X563512Y1094020D02*
X563147Y1094238D01*
X563294Y1094974D01*
X563715Y1095035D01*
X563911Y1094996D01*
X563708Y1093981D01*
X563512Y1094020D01*
G37*
G36*
G01X559140Y1084327D02*
X558958Y1084711D01*
X559489Y1085241D01*
X559872Y1085059D01*
X560014Y1084918D01*
X559282Y1084186D01*
X559140Y1084327D01*
G37*
G36*
G01X555817Y1081004D02*
X555635Y1081387D01*
X556165Y1081918D01*
X556549Y1081736D01*
X556690Y1081594D01*
X555958Y1080862D01*
X555817Y1081004D01*
G37*
G36*
G01X556001Y1080622D02*
X556183Y1080238D01*
X555653Y1079708D01*
X555269Y1079890D01*
X555128Y1080032D01*
X555859Y1080763D01*
X556001Y1080622D01*
G37*
G36*
G01X557662Y1082284D02*
X557845Y1081900D01*
X557314Y1081370D01*
X556931Y1081552D01*
X556789Y1081693D01*
X557521Y1082425D01*
X557662Y1082284D01*
G37*
G36*
G01X557479Y1082665D02*
X557297Y1083049D01*
X557827Y1083579D01*
X558211Y1083397D01*
X558352Y1083256D01*
X557620Y1082524D01*
X557479Y1082665D01*
G37*
G36*
G01X559324Y1083945D02*
X559506Y1083562D01*
X558976Y1083031D01*
X558592Y1083214D01*
X558451Y1083355D01*
X559183Y1084087D01*
X559324Y1083945D01*
G37*
G36*
G01X560950Y1087342D02*
X560586Y1087561D01*
X560733Y1088296D01*
X561153Y1088357D01*
X561349Y1088318D01*
X561146Y1087303D01*
X560950Y1087342D01*
G37*
G36*
G01X561776Y1089431D02*
X562140Y1089213D01*
X561993Y1088478D01*
X561573Y1088416D01*
X561377Y1088455D01*
X561580Y1089470D01*
X561776Y1089431D01*
G37*
G36*
G01X561411Y1089647D02*
X561047Y1089865D01*
X561194Y1090600D01*
X561614Y1090662D01*
X561810Y1090622D01*
X561607Y1089608D01*
X561411Y1089647D01*
G37*
G36*
G01X561872Y1091951D02*
X561508Y1092169D01*
X561655Y1092905D01*
X562075Y1092966D01*
X562271Y1092927D01*
X562068Y1091912D01*
X561872Y1091951D01*
G37*
G36*
G01X562237Y1091735D02*
X562601Y1091517D01*
X562454Y1090782D01*
X562034Y1090721D01*
X561838Y1090760D01*
X562041Y1091775D01*
X562237Y1091735D01*
G37*
G36*
G01X562698Y1094040D02*
X563062Y1093822D01*
X562915Y1093086D01*
X562495Y1093025D01*
X562299Y1093064D01*
X562502Y1094079D01*
X562698Y1094040D01*
G37*
G36*
G01X562333Y1094256D02*
X561969Y1094474D01*
X562116Y1095209D01*
X562536Y1095270D01*
X562732Y1095231D01*
X562529Y1094216D01*
X562333Y1094256D01*
G37*
G36*
G01X563159Y1096344D02*
X563523Y1096126D01*
X563376Y1095391D01*
X562956Y1095329D01*
X562760Y1095368D01*
X562963Y1096383D01*
X563159Y1096344D01*
G37*
G36*
G01X559361Y1080585D02*
X559544Y1080201D01*
X559013Y1079671D01*
X558630Y1079853D01*
X558488Y1079994D01*
X559220Y1080726D01*
X559361Y1080585D01*
G37*
G36*
G01X561023Y1082246D02*
X561205Y1081863D01*
X560675Y1081332D01*
X560291Y1081515D01*
X560150Y1081656D01*
X560882Y1082388D01*
X561023Y1082246D01*
G37*
G36*
G01X560839Y1082628D02*
X560657Y1083012D01*
X561188Y1083542D01*
X561571Y1083360D01*
X561713Y1083219D01*
X560981Y1082487D01*
X560839Y1082628D01*
G37*
G36*
G01X562685Y1083908D02*
X562867Y1083524D01*
X562337Y1082994D01*
X561953Y1083176D01*
X561812Y1083318D01*
X562543Y1084049D01*
X562685Y1083908D01*
G37*
G36*
G01X559178Y1080966D02*
X558996Y1081350D01*
X559526Y1081880D01*
X559910Y1081698D01*
X560051Y1081557D01*
X559319Y1080825D01*
X559178Y1080966D01*
G37*
G36*
G01X564595Y1091265D02*
X564959Y1091046D01*
X564812Y1090311D01*
X564392Y1090250D01*
X564196Y1090289D01*
X564399Y1091304D01*
X564595Y1091265D01*
G37*
G36*
G01X564135Y1088960D02*
X564499Y1088742D01*
X564352Y1088007D01*
X563932Y1087945D01*
X563736Y1087984D01*
X563938Y1088999D01*
X564135Y1088960D01*
G37*
G36*
G01X564230Y1091480D02*
X563866Y1091698D01*
X564013Y1092434D01*
X564433Y1092495D01*
X564629Y1092456D01*
X564426Y1091441D01*
X564230Y1091480D01*
G37*
G36*
G01X563674Y1086656D02*
X564039Y1086438D01*
X563892Y1085702D01*
X563471Y1085641D01*
X563275Y1085680D01*
X563478Y1086695D01*
X563674Y1086656D01*
G37*
G36*
G01X563770Y1089176D02*
X563405Y1089394D01*
X563552Y1090129D01*
X563973Y1090191D01*
X564169Y1090152D01*
X563966Y1089137D01*
X563770Y1089176D01*
G37*
G36*
G01X563309Y1086871D02*
X562945Y1087089D01*
X563092Y1087825D01*
X563512Y1087886D01*
X563708Y1087847D01*
X563506Y1086832D01*
X563309Y1086871D01*
G37*
G36*
G01X565516Y1095874D02*
X565880Y1095655D01*
X565733Y1094920D01*
X565313Y1094859D01*
X565117Y1094898D01*
X565320Y1095913D01*
X565516Y1095874D01*
G37*
G36*
G01X565055Y1093569D02*
X565420Y1093351D01*
X565273Y1092615D01*
X564853Y1092554D01*
X564656Y1092593D01*
X564859Y1093608D01*
X565055Y1093569D01*
G37*
G36*
G01X564690Y1093785D02*
X564326Y1094003D01*
X564473Y1094738D01*
X564893Y1094800D01*
X565089Y1094760D01*
X564887Y1093746D01*
X564690Y1093785D01*
G37*
G36*
G01X552187Y1087012D02*
X552369Y1086629D01*
X551839Y1086098D01*
X551455Y1086280D01*
X551314Y1086422D01*
X552046Y1087154D01*
X552187Y1087012D01*
G37*
G36*
G01X553849Y1088674D02*
X554031Y1088290D01*
X553500Y1087760D01*
X553117Y1087942D01*
X552975Y1088083D01*
X553707Y1088815D01*
X553849Y1088674D01*
G37*
G36*
G01X552003Y1087394D02*
X551821Y1087778D01*
X552351Y1088308D01*
X552735Y1088126D01*
X552876Y1087984D01*
X552145Y1087253D01*
X552003Y1087394D01*
G37*
G36*
G01X555231Y1094798D02*
X554866Y1095016D01*
X555014Y1095751D01*
X555434Y1095813D01*
X555630Y1095773D01*
X555427Y1094758D01*
X555231Y1094798D01*
G37*
G36*
G01X555595Y1094582D02*
X555960Y1094364D01*
X555812Y1093628D01*
X555392Y1093567D01*
X555196Y1093606D01*
X555399Y1094621D01*
X555595Y1094582D01*
G37*
G36*
G01X554769Y1092493D02*
X554405Y1092712D01*
X554552Y1093447D01*
X554973Y1093508D01*
X555169Y1093469D01*
X554965Y1092454D01*
X554769Y1092493D01*
G37*
G36*
G01X554308Y1090189D02*
X553944Y1090407D01*
X554091Y1091143D01*
X554511Y1091204D01*
X554707Y1091165D01*
X554504Y1090150D01*
X554308Y1090189D01*
G37*
G36*
G01X555134Y1092278D02*
X555498Y1092059D01*
X555351Y1091324D01*
X554931Y1091263D01*
X554735Y1091302D01*
X554938Y1092317D01*
X555134Y1092278D01*
G37*
G36*
G01X553895Y1085304D02*
X554077Y1084921D01*
X553547Y1084390D01*
X553163Y1084572D01*
X553022Y1084714D01*
X553754Y1085446D01*
X553895Y1085304D01*
G37*
G36*
G01X552049Y1084024D02*
X551867Y1084408D01*
X552398Y1084938D01*
X552781Y1084756D01*
X552923Y1084615D01*
X552191Y1083883D01*
X552049Y1084024D01*
G37*
G36*
G01X556665Y1089717D02*
X556301Y1089936D01*
X556448Y1090671D01*
X556868Y1090732D01*
X557064Y1090693D01*
X556861Y1089678D01*
X556665Y1089717D01*
G37*
G36*
G01X557030Y1089501D02*
X557394Y1089283D01*
X557247Y1088548D01*
X556827Y1088487D01*
X556631Y1088526D01*
X556834Y1089541D01*
X557030Y1089501D01*
G37*
G36*
G01X555557Y1086966D02*
X555739Y1086582D01*
X555208Y1086052D01*
X554825Y1086234D01*
X554683Y1086375D01*
X555415Y1087107D01*
X555557Y1086966D01*
G37*
G36*
G01X553711Y1085686D02*
X553529Y1086070D01*
X554059Y1086600D01*
X554443Y1086418D01*
X554584Y1086276D01*
X553853Y1085545D01*
X553711Y1085686D01*
G37*
G36*
G01X557952Y1094110D02*
X558317Y1093892D01*
X558169Y1093156D01*
X557749Y1093095D01*
X557553Y1093134D01*
X557756Y1094149D01*
X557952Y1094110D01*
G37*
G36*
G01X557588Y1094326D02*
X557223Y1094544D01*
X557371Y1095279D01*
X557791Y1095341D01*
X557987Y1095301D01*
X557784Y1094287D01*
X557588Y1094326D01*
G37*
G36*
G01X558414Y1096414D02*
X558778Y1096196D01*
X558631Y1095461D01*
X558211Y1095399D01*
X558015Y1095439D01*
X558218Y1096454D01*
X558414Y1096414D01*
G37*
G36*
G01X557126Y1092022D02*
X556762Y1092240D01*
X556909Y1092975D01*
X557330Y1093036D01*
X557526Y1092997D01*
X557323Y1091982D01*
X557126Y1092022D01*
G37*
G36*
G01X557491Y1091806D02*
X557855Y1091588D01*
X557708Y1090852D01*
X557288Y1090791D01*
X557092Y1090830D01*
X557295Y1091845D01*
X557491Y1091806D01*
G37*
G36*
G01X557235Y1096650D02*
X557600Y1096432D01*
X557452Y1095697D01*
X557032Y1095635D01*
X556836Y1095675D01*
X557039Y1096689D01*
X557235Y1096650D01*
G37*
G36*
G01X556313Y1092042D02*
X556677Y1091823D01*
X556530Y1091088D01*
X556110Y1091027D01*
X555914Y1091066D01*
X556117Y1092081D01*
X556313Y1092042D01*
G37*
G36*
G01X555487Y1089953D02*
X555123Y1090171D01*
X555270Y1090907D01*
X555690Y1090968D01*
X555886Y1090929D01*
X555683Y1089914D01*
X555487Y1089953D01*
G37*
G36*
G01X554702Y1087821D02*
X554884Y1087437D01*
X554353Y1086907D01*
X553970Y1087089D01*
X553828Y1087230D01*
X554560Y1087962D01*
X554702Y1087821D01*
G37*
G36*
G01X553040Y1086159D02*
X553222Y1085776D01*
X552692Y1085245D01*
X552308Y1085427D01*
X552167Y1085569D01*
X552899Y1086301D01*
X553040Y1086159D01*
G37*
G36*
G01X552856Y1086541D02*
X552674Y1086925D01*
X553204Y1087455D01*
X553588Y1087273D01*
X553729Y1087131D01*
X552998Y1086400D01*
X552856Y1086541D01*
G37*
G36*
G01X555948Y1092257D02*
X555584Y1092476D01*
X555731Y1093211D01*
X556151Y1093272D01*
X556347Y1093233D01*
X556144Y1092218D01*
X555948Y1092257D01*
G37*
G36*
G01X556774Y1094346D02*
X557138Y1094128D01*
X556991Y1093392D01*
X556571Y1093331D01*
X556375Y1093370D01*
X556578Y1094385D01*
X556774Y1094346D01*
G37*
G36*
G01X556409Y1094562D02*
X556045Y1094780D01*
X556192Y1095515D01*
X556612Y1095577D01*
X556809Y1095537D01*
X556605Y1094522D01*
X556409Y1094562D01*
G37*
G36*
G01X554562Y1084835D02*
X554380Y1085219D01*
X554910Y1085749D01*
X555294Y1085567D01*
X555435Y1085425D01*
X554704Y1084694D01*
X554562Y1084835D01*
G37*
G36*
G01X554746Y1084453D02*
X554928Y1084070D01*
X554398Y1083539D01*
X554014Y1083721D01*
X553873Y1083863D01*
X554605Y1084595D01*
X554746Y1084453D01*
G37*
G36*
G01X552900Y1083173D02*
X552718Y1083557D01*
X553249Y1084087D01*
X553632Y1083905D01*
X553774Y1083764D01*
X553042Y1083032D01*
X552900Y1083173D01*
G37*
G36*
G01X556224Y1086497D02*
X556042Y1086880D01*
X556572Y1087411D01*
X556956Y1087229D01*
X557097Y1087087D01*
X556365Y1086355D01*
X556224Y1086497D01*
G37*
G36*
G01X558670Y1091570D02*
X559034Y1091352D01*
X558887Y1090616D01*
X558467Y1090555D01*
X558271Y1090594D01*
X558474Y1091609D01*
X558670Y1091570D01*
G37*
G36*
G01X558305Y1091786D02*
X557941Y1092004D01*
X558088Y1092739D01*
X558508Y1092800D01*
X558704Y1092761D01*
X558501Y1091746D01*
X558305Y1091786D01*
G37*
G36*
G01X559131Y1093874D02*
X559495Y1093656D01*
X559348Y1092920D01*
X558928Y1092859D01*
X558732Y1092898D01*
X558935Y1093913D01*
X559131Y1093874D01*
G37*
G36*
G01X558766Y1094090D02*
X558402Y1094308D01*
X558549Y1095044D01*
X558970Y1095105D01*
X559166Y1095065D01*
X558963Y1094051D01*
X558766Y1094090D01*
G37*
G36*
G01X558209Y1089266D02*
X558573Y1089047D01*
X558426Y1088312D01*
X558005Y1088251D01*
X557809Y1088290D01*
X558013Y1089305D01*
X558209Y1089266D01*
G37*
G36*
G01X557844Y1089481D02*
X557480Y1089700D01*
X557627Y1090435D01*
X558047Y1090496D01*
X558243Y1090457D01*
X558040Y1089442D01*
X557844Y1089481D01*
G37*
G36*
G01X556408Y1086115D02*
X556590Y1085731D01*
X556059Y1085201D01*
X555676Y1085383D01*
X555534Y1085524D01*
X556266Y1086256D01*
X556408Y1086115D01*
G37*
G36*
G01X559592Y1096178D02*
X559957Y1095960D01*
X559810Y1095225D01*
X559389Y1095163D01*
X559193Y1095203D01*
X559396Y1096218D01*
X559592Y1096178D01*
G37*
G36*
G01X562438Y1098884D02*
X562803Y1098666D01*
X562655Y1097931D01*
X562235Y1097869D01*
X562039Y1097909D01*
X562242Y1098924D01*
X562438Y1098884D01*
G37*
G36*
G01X562073Y1099100D02*
X561709Y1099318D01*
X561856Y1100054D01*
X562276Y1100115D01*
X562472Y1100076D01*
X562269Y1099061D01*
X562073Y1099100D01*
G37*
G36*
G01X562898Y1101189D02*
X563263Y1100971D01*
X563116Y1100235D01*
X562695Y1100174D01*
X562499Y1100213D01*
X562702Y1101228D01*
X562898Y1101189D01*
G37*
G36*
G01X562533Y1101405D02*
X562169Y1101623D01*
X562316Y1102358D01*
X562736Y1102420D01*
X562932Y1102380D01*
X562729Y1101365D01*
X562533Y1101405D01*
G37*
G36*
G01X561613Y1096796D02*
X561249Y1097014D01*
X561396Y1097749D01*
X561816Y1097811D01*
X562012Y1097771D01*
X561809Y1096756D01*
X561613Y1096796D01*
G37*
G36*
G01X563125Y1108219D02*
X562725Y1108362D01*
Y1109112D01*
X563125Y1109255D01*
X563325D01*
Y1108219D01*
X563125D01*
G37*
G36*
G01X563525Y1108080D02*
X563925Y1107937D01*
Y1107187D01*
X563525Y1107045D01*
X563325D01*
Y1108080D01*
X563525D01*
G37*
G36*
G01X563359Y1103493D02*
X563723Y1103275D01*
X563576Y1102540D01*
X563156Y1102479D01*
X562960Y1102518D01*
X563163Y1103533D01*
X563359Y1103493D01*
G37*
G36*
G01X563125Y1105869D02*
X562725Y1106012D01*
Y1106762D01*
X563125Y1106905D01*
X563325D01*
Y1105869D01*
X563125D01*
G37*
G36*
G01X563525Y1110430D02*
X563925Y1110287D01*
Y1109537D01*
X563525Y1109395D01*
X563325D01*
Y1110430D01*
X563525D01*
G37*
G36*
G01X563125Y1110569D02*
X562725Y1110712D01*
Y1111462D01*
X563125Y1111605D01*
X563325D01*
Y1110569D01*
X563125D01*
G37*
G36*
G01X563525Y1112780D02*
X563925Y1112637D01*
Y1111887D01*
X563525Y1111745D01*
X563325D01*
Y1112780D01*
X563525D01*
G37*
G36*
G01X564798Y1098413D02*
X565162Y1098195D01*
X565015Y1097460D01*
X564595Y1097398D01*
X564399Y1097438D01*
X564602Y1098452D01*
X564798Y1098413D01*
G37*
G36*
G01X563972Y1096325D02*
X563608Y1096543D01*
X563755Y1097278D01*
X564175Y1097339D01*
X564371Y1097300D01*
X564168Y1096285D01*
X563972Y1096325D01*
G37*
G36*
G01X565258Y1100718D02*
X565623Y1100500D01*
X565476Y1099764D01*
X565056Y1099703D01*
X564859Y1099742D01*
X565062Y1100757D01*
X565258Y1100718D01*
G37*
G36*
G01X564433Y1098629D02*
X564069Y1098847D01*
X564216Y1099583D01*
X564636Y1099644D01*
X564832Y1099605D01*
X564629Y1098590D01*
X564433Y1098629D01*
G37*
G36*
G01X564894Y1100933D02*
X564529Y1101152D01*
X564676Y1101887D01*
X565097Y1101948D01*
X565293Y1101909D01*
X565090Y1100894D01*
X564894Y1100933D01*
G37*
G36*
G01X565525Y1108219D02*
X565125Y1108362D01*
Y1109112D01*
X565525Y1109255D01*
X565725D01*
Y1108219D01*
X565525D01*
G37*
G36*
G01Y1105869D02*
X565125Y1106012D01*
Y1106762D01*
X565525Y1106905D01*
X565725D01*
Y1105869D01*
X565525D01*
G37*
G36*
G01X565719Y1103022D02*
X566083Y1102804D01*
X565936Y1102069D01*
X565516Y1102007D01*
X565320Y1102046D01*
X565523Y1103061D01*
X565719Y1103022D01*
G37*
G36*
G01X565525Y1110569D02*
X565125Y1110712D01*
Y1111462D01*
X565525Y1111605D01*
X565725D01*
Y1110569D01*
X565525D01*
G37*
G36*
G01X563620Y1098648D02*
X563984Y1098430D01*
X563837Y1097695D01*
X563417Y1097634D01*
X563221Y1097673D01*
X563424Y1098688D01*
X563620Y1098648D01*
G37*
G36*
G01X562794Y1096560D02*
X562430Y1096778D01*
X562577Y1097513D01*
X562997Y1097575D01*
X563193Y1097536D01*
X562990Y1096521D01*
X562794Y1096560D01*
G37*
G36*
G01X563255Y1098864D02*
X562891Y1099082D01*
X563038Y1099818D01*
X563458Y1099879D01*
X563654Y1099840D01*
X563451Y1098825D01*
X563255Y1098864D01*
G37*
G36*
G01X564081Y1100953D02*
X564445Y1100735D01*
X564298Y1099999D01*
X563878Y1099938D01*
X563682Y1099977D01*
X563885Y1100992D01*
X564081Y1100953D01*
G37*
G36*
G01X563716Y1101169D02*
X563352Y1101387D01*
X563499Y1102122D01*
X563919Y1102183D01*
X564115Y1102144D01*
X563912Y1101129D01*
X563716Y1101169D01*
G37*
G36*
G01X564325Y1108219D02*
X563925Y1108362D01*
Y1109112D01*
X564325Y1109255D01*
X564525D01*
Y1108219D01*
X564325D01*
G37*
G36*
G01X564725Y1108080D02*
X565125Y1107937D01*
Y1107187D01*
X564725Y1107045D01*
X564525D01*
Y1108080D01*
X564725D01*
G37*
G36*
G01X564542Y1103257D02*
X564906Y1103039D01*
X564759Y1102304D01*
X564339Y1102242D01*
X564143Y1102281D01*
X564346Y1103296D01*
X564542Y1103257D01*
G37*
G36*
G01X564325Y1105869D02*
X563925Y1106012D01*
Y1106762D01*
X564325Y1106905D01*
X564525D01*
Y1105869D01*
X564325D01*
G37*
G36*
G01X564725Y1110430D02*
X565125Y1110287D01*
Y1109537D01*
X564725Y1109395D01*
X564525D01*
Y1110430D01*
X564725D01*
G37*
G36*
G01X564325Y1110569D02*
X563925Y1110712D01*
Y1111462D01*
X564325Y1111605D01*
X564525D01*
Y1110569D01*
X564325D01*
G37*
G36*
G01X564725Y1112780D02*
X565125Y1112637D01*
Y1111887D01*
X564725Y1111745D01*
X564525D01*
Y1112780D01*
X564725D01*
G37*
G36*
G01X565976Y1098178D02*
X566340Y1097960D01*
X566193Y1097224D01*
X565773Y1097163D01*
X565577Y1097202D01*
X565780Y1098217D01*
X565976Y1098178D01*
G37*
G36*
G01X565151Y1096089D02*
X564787Y1096307D01*
X564933Y1097043D01*
X565354Y1097104D01*
X565550Y1097065D01*
X565347Y1096050D01*
X565151Y1096089D01*
G37*
G36*
G01X565611Y1098394D02*
X565247Y1098612D01*
X565394Y1099347D01*
X565814Y1099409D01*
X566010Y1099369D01*
X565807Y1098354D01*
X565611Y1098394D01*
G37*
G36*
G01X550344Y1108854D02*
X550744Y1108711D01*
Y1107961D01*
X550344Y1107819D01*
X550144D01*
Y1108854D01*
X550344D01*
G37*
G36*
G01Y1111204D02*
X550744Y1111061D01*
Y1110311D01*
X550344Y1110169D01*
X550144D01*
Y1111204D01*
X550344D01*
G37*
G36*
G01X549944Y1108994D02*
X549544Y1109137D01*
Y1109887D01*
X549944Y1110029D01*
X550144D01*
Y1108994D01*
X549944D01*
G37*
G36*
G01Y1111344D02*
X549544Y1111487D01*
Y1112237D01*
X549944Y1112379D01*
X550144D01*
Y1111344D01*
X549944D01*
G37*
G36*
G01X551544Y1108854D02*
X551944Y1108711D01*
Y1107961D01*
X551544Y1107819D01*
X551344D01*
Y1108854D01*
X551544D01*
G37*
G36*
G01Y1111204D02*
X551944Y1111061D01*
Y1110311D01*
X551544Y1110169D01*
X551344D01*
Y1111204D01*
X551544D01*
G37*
G36*
G01X551144Y1108994D02*
X550744Y1109137D01*
Y1109887D01*
X551144Y1110029D01*
X551344D01*
Y1108994D01*
X551144D01*
G37*
G36*
G01Y1111344D02*
X550744Y1111487D01*
Y1112237D01*
X551144Y1112379D01*
X551344D01*
Y1111344D01*
X551144D01*
G37*
G36*
G01X555692Y1097102D02*
X555328Y1097320D01*
X555475Y1098056D01*
X555895Y1098117D01*
X556091Y1098078D01*
X555888Y1097063D01*
X555692Y1097102D01*
G37*
G36*
G01X556057Y1096886D02*
X556421Y1096668D01*
X556274Y1095933D01*
X555854Y1095871D01*
X555657Y1095911D01*
X555861Y1096925D01*
X556057Y1096886D01*
G37*
G36*
G01X556153Y1099406D02*
X555789Y1099624D01*
X555936Y1100360D01*
X556356Y1100421D01*
X556553Y1100382D01*
X556349Y1099367D01*
X556153Y1099406D01*
G37*
G36*
G01X556518Y1099190D02*
X556882Y1098972D01*
X556735Y1098237D01*
X556315Y1098176D01*
X556119Y1098215D01*
X556322Y1099230D01*
X556518Y1099190D01*
G37*
G36*
G01X556979Y1101495D02*
X557344Y1101277D01*
X557196Y1100541D01*
X556776Y1100480D01*
X556580Y1100519D01*
X556783Y1101534D01*
X556979Y1101495D01*
G37*
G36*
G01X557564Y1109159D02*
X557964Y1109017D01*
Y1108267D01*
X557564Y1108124D01*
X557364D01*
Y1109159D01*
X557564D01*
G37*
G36*
G01X557164Y1106949D02*
X556764Y1107092D01*
Y1107842D01*
X557164Y1107984D01*
X557364D01*
Y1106949D01*
X557164D01*
G37*
G36*
G01X557564Y1106809D02*
X557964Y1106667D01*
Y1105917D01*
X557564Y1105774D01*
X557364D01*
Y1106809D01*
X557564D01*
G37*
G36*
G01X556615Y1101711D02*
X556250Y1101929D01*
X556398Y1102664D01*
X556818Y1102725D01*
X557014Y1102686D01*
X556811Y1101671D01*
X556615Y1101711D01*
G37*
G36*
G01X557164Y1109299D02*
X556764Y1109442D01*
Y1110192D01*
X557164Y1110334D01*
X557364D01*
Y1109299D01*
X557164D01*
G37*
G36*
G01Y1111649D02*
X556764Y1111792D01*
Y1112542D01*
X557164Y1112684D01*
X557364D01*
Y1111649D01*
X557164D01*
G37*
G36*
G01X557564Y1111509D02*
X557964Y1111367D01*
Y1110617D01*
X557564Y1110474D01*
X557364D01*
Y1111509D01*
X557564D01*
G37*
G36*
G01X558049Y1096630D02*
X557685Y1096848D01*
X557832Y1097584D01*
X558252Y1097645D01*
X558448Y1097606D01*
X558245Y1096591D01*
X558049Y1096630D01*
G37*
G36*
G01X558875Y1098719D02*
X559239Y1098500D01*
X559092Y1097765D01*
X558672Y1097704D01*
X558476Y1097743D01*
X558679Y1098758D01*
X558875Y1098719D01*
G37*
G36*
G01X558510Y1098934D02*
X558146Y1099153D01*
X558293Y1099888D01*
X558714Y1099949D01*
X558910Y1099910D01*
X558706Y1098895D01*
X558510Y1098934D01*
G37*
G36*
G01X559336Y1101023D02*
X559701Y1100805D01*
X559553Y1100069D01*
X559133Y1100008D01*
X558937Y1100047D01*
X559140Y1101062D01*
X559336Y1101023D01*
G37*
G36*
G01X558972Y1101239D02*
X558607Y1101457D01*
X558755Y1102192D01*
X559175Y1102254D01*
X559371Y1102214D01*
X559168Y1101199D01*
X558972Y1101239D01*
G37*
G36*
G01X559964Y1109159D02*
X560364Y1109017D01*
Y1108267D01*
X559964Y1108124D01*
X559764D01*
Y1109159D01*
X559964D01*
G37*
G36*
G01X559564Y1106949D02*
X559164Y1107092D01*
Y1107842D01*
X559564Y1107984D01*
X559764D01*
Y1106949D01*
X559564D01*
G37*
G36*
G01X559964Y1106809D02*
X560364Y1106667D01*
Y1105917D01*
X559964Y1105774D01*
X559764D01*
Y1106809D01*
X559964D01*
G37*
G36*
G01X559564Y1109299D02*
X559164Y1109442D01*
Y1110192D01*
X559564Y1110334D01*
X559764D01*
Y1109299D01*
X559564D01*
G37*
G36*
G01Y1111649D02*
X559164Y1111792D01*
Y1112542D01*
X559564Y1112684D01*
X559764D01*
Y1111649D01*
X559564D01*
G37*
G36*
G01X559964Y1111509D02*
X560364Y1111367D01*
Y1110617D01*
X559964Y1110474D01*
X559764D01*
Y1111509D01*
X559964D01*
G37*
G36*
G01X556871Y1096866D02*
X556506Y1097084D01*
X556654Y1097820D01*
X557074Y1097881D01*
X557270Y1097842D01*
X557067Y1096827D01*
X556871Y1096866D01*
G37*
G36*
G01X557332Y1099170D02*
X556968Y1099389D01*
X557115Y1100124D01*
X557535Y1100185D01*
X557731Y1100146D01*
X557528Y1099131D01*
X557332Y1099170D01*
G37*
G36*
G01X557697Y1098955D02*
X558061Y1098736D01*
X557914Y1098001D01*
X557493Y1097940D01*
X557297Y1097979D01*
X557500Y1098994D01*
X557697Y1098955D01*
G37*
G36*
G01X558158Y1101259D02*
X558522Y1101041D01*
X558375Y1100305D01*
X557955Y1100244D01*
X557758Y1100283D01*
X557962Y1101298D01*
X558158Y1101259D01*
G37*
G36*
G01X558364Y1111649D02*
X557964Y1111792D01*
Y1112542D01*
X558364Y1112684D01*
X558564D01*
Y1111649D01*
X558364D01*
G37*
G36*
G01X558764Y1111509D02*
X559164Y1111367D01*
Y1110617D01*
X558764Y1110474D01*
X558564D01*
Y1111509D01*
X558764D01*
G37*
G36*
G01Y1109159D02*
X559164Y1109017D01*
Y1108267D01*
X558764Y1108124D01*
X558564D01*
Y1109159D01*
X558764D01*
G37*
G36*
G01X558364Y1106949D02*
X557964Y1107092D01*
Y1107842D01*
X558364Y1107984D01*
X558564D01*
Y1106949D01*
X558364D01*
G37*
G36*
G01X558764Y1106809D02*
X559164Y1106667D01*
Y1105917D01*
X558764Y1105774D01*
X558564D01*
Y1106809D01*
X558764D01*
G37*
G36*
G01X557793Y1101475D02*
X557429Y1101693D01*
X557576Y1102428D01*
X557996Y1102489D01*
X558192Y1102450D01*
X557989Y1101435D01*
X557793Y1101475D01*
G37*
G36*
G01X558364Y1109299D02*
X557964Y1109442D01*
Y1110192D01*
X558364Y1110334D01*
X558564D01*
Y1109299D01*
X558364D01*
G37*
G36*
G01X559228Y1096394D02*
X558864Y1096612D01*
X559011Y1097348D01*
X559431Y1097409D01*
X559627Y1097370D01*
X559424Y1096355D01*
X559228Y1096394D01*
G37*
G36*
G01X560054Y1098483D02*
X560418Y1098264D01*
X560271Y1097529D01*
X559851Y1097468D01*
X559655Y1097507D01*
X559858Y1098522D01*
X560054Y1098483D01*
G37*
G36*
G01X560515Y1100787D02*
X560879Y1100569D01*
X560732Y1099833D01*
X560312Y1099772D01*
X560116Y1099811D01*
X560319Y1100826D01*
X560515Y1100787D01*
G37*
G36*
G01X559689Y1098698D02*
X559325Y1098917D01*
X559472Y1099652D01*
X559892Y1099713D01*
X560088Y1099674D01*
X559885Y1098659D01*
X559689Y1098698D01*
G37*
G36*
G01X560150Y1101003D02*
X559786Y1101221D01*
X559933Y1101956D01*
X560353Y1102018D01*
X560550Y1101978D01*
X560346Y1100963D01*
X560150Y1101003D01*
G37*
G36*
G01X560764Y1109299D02*
X560364Y1109442D01*
Y1110192D01*
X560764Y1110334D01*
X560964D01*
Y1109299D01*
X560764D01*
G37*
G36*
G01X561164Y1111509D02*
X561564Y1111367D01*
Y1110617D01*
X561164Y1110474D01*
X560964D01*
Y1111509D01*
X561164D01*
G37*
G36*
G01X560764Y1111649D02*
X560364Y1111792D01*
Y1112542D01*
X560764Y1112684D01*
X560964D01*
Y1111649D01*
X560764D01*
G37*
G36*
G01Y1106949D02*
X560364Y1107092D01*
Y1107842D01*
X560764Y1107984D01*
X560964D01*
Y1106949D01*
X560764D01*
G37*
G36*
G01X561164Y1106809D02*
X561564Y1106667D01*
Y1105917D01*
X561164Y1105774D01*
X560964D01*
Y1106809D01*
X561164D01*
G37*
G36*
G01Y1109159D02*
X561564Y1109017D01*
Y1108267D01*
X561164Y1108124D01*
X560964D01*
Y1109159D01*
X561164D01*
G37*
G36*
G01X563125Y1112919D02*
X562725Y1113062D01*
Y1113812D01*
X563125Y1113955D01*
X563325D01*
Y1112919D01*
X563125D01*
G37*
G36*
G01X563525Y1115130D02*
X563925Y1114987D01*
Y1114237D01*
X563525Y1114095D01*
X563325D01*
Y1115130D01*
X563525D01*
G37*
G36*
G01X563125Y1115269D02*
X562725Y1115412D01*
Y1116162D01*
X563125Y1116305D01*
X563325D01*
Y1115269D01*
X563125D01*
G37*
G36*
G01X563525Y1117480D02*
X563925Y1117337D01*
Y1116587D01*
X563525Y1116445D01*
X563325D01*
Y1117480D01*
X563525D01*
G37*
G36*
G01X563125Y1117619D02*
X562725Y1117762D01*
Y1118512D01*
X563125Y1118655D01*
X563325D01*
Y1117619D01*
X563125D01*
G37*
G36*
G01Y1124669D02*
X562725Y1124812D01*
Y1125562D01*
X563125Y1125705D01*
X563325D01*
Y1124669D01*
X563125D01*
G37*
G36*
G01X563525Y1126880D02*
X563925Y1126737D01*
Y1125987D01*
X563525Y1125845D01*
X563325D01*
Y1126880D01*
X563525D01*
G37*
G36*
G01X563125Y1127019D02*
X562725Y1127162D01*
Y1127912D01*
X563125Y1128055D01*
X563325D01*
Y1127019D01*
X563125D01*
G37*
G36*
G01X563525Y1129230D02*
X563925Y1129087D01*
Y1128337D01*
X563525Y1128195D01*
X563325D01*
Y1129230D01*
X563525D01*
G37*
G36*
G01X563125Y1122319D02*
X562725Y1122462D01*
Y1123212D01*
X563125Y1123355D01*
X563325D01*
Y1122319D01*
X563125D01*
G37*
G36*
G01Y1119969D02*
X562725Y1120112D01*
Y1120862D01*
X563125Y1121005D01*
X563325D01*
Y1119969D01*
X563125D01*
G37*
G36*
G01X563525Y1124530D02*
X563925Y1124387D01*
Y1123637D01*
X563525Y1123495D01*
X563325D01*
Y1124530D01*
X563525D01*
G37*
G36*
G01Y1122180D02*
X563925Y1122037D01*
Y1121287D01*
X563525Y1121145D01*
X563325D01*
Y1122180D01*
X563525D01*
G37*
G36*
G01Y1119830D02*
X563925Y1119687D01*
Y1118937D01*
X563525Y1118795D01*
X563325D01*
Y1119830D01*
X563525D01*
G37*
G36*
G01X565525Y1112919D02*
X565125Y1113062D01*
Y1113812D01*
X565525Y1113955D01*
X565725D01*
Y1112919D01*
X565525D01*
G37*
G36*
G01Y1115269D02*
X565125Y1115412D01*
Y1116162D01*
X565525Y1116305D01*
X565725D01*
Y1115269D01*
X565525D01*
G37*
G36*
G01Y1117619D02*
X565125Y1117762D01*
Y1118512D01*
X565525Y1118655D01*
X565725D01*
Y1117619D01*
X565525D01*
G37*
G36*
G01Y1122319D02*
X565125Y1122462D01*
Y1123212D01*
X565525Y1123355D01*
X565725D01*
Y1122319D01*
X565525D01*
G37*
G36*
G01Y1119969D02*
X565125Y1120112D01*
Y1120862D01*
X565525Y1121005D01*
X565725D01*
Y1119969D01*
X565525D01*
G37*
G36*
G01Y1124669D02*
X565125Y1124812D01*
Y1125562D01*
X565525Y1125705D01*
X565725D01*
Y1124669D01*
X565525D01*
G37*
G36*
G01Y1127019D02*
X565125Y1127162D01*
Y1127912D01*
X565525Y1128055D01*
X565725D01*
Y1127019D01*
X565525D01*
G37*
G36*
G01X564325Y1112919D02*
X563925Y1113062D01*
Y1113812D01*
X564325Y1113955D01*
X564525D01*
Y1112919D01*
X564325D01*
G37*
G36*
G01X564725Y1115130D02*
X565125Y1114987D01*
Y1114237D01*
X564725Y1114095D01*
X564525D01*
Y1115130D01*
X564725D01*
G37*
G36*
G01X564325Y1115269D02*
X563925Y1115412D01*
Y1116162D01*
X564325Y1116305D01*
X564525D01*
Y1115269D01*
X564325D01*
G37*
G36*
G01X564725Y1117480D02*
X565125Y1117337D01*
Y1116587D01*
X564725Y1116445D01*
X564525D01*
Y1117480D01*
X564725D01*
G37*
G36*
G01X564325Y1117619D02*
X563925Y1117762D01*
Y1118512D01*
X564325Y1118655D01*
X564525D01*
Y1117619D01*
X564325D01*
G37*
G36*
G01Y1122319D02*
X563925Y1122462D01*
Y1123212D01*
X564325Y1123355D01*
X564525D01*
Y1122319D01*
X564325D01*
G37*
G36*
G01Y1119969D02*
X563925Y1120112D01*
Y1120862D01*
X564325Y1121005D01*
X564525D01*
Y1119969D01*
X564325D01*
G37*
G36*
G01X564725Y1124530D02*
X565125Y1124387D01*
Y1123637D01*
X564725Y1123495D01*
X564525D01*
Y1124530D01*
X564725D01*
G37*
G36*
G01Y1122180D02*
X565125Y1122037D01*
Y1121287D01*
X564725Y1121145D01*
X564525D01*
Y1122180D01*
X564725D01*
G37*
G36*
G01Y1119830D02*
X565125Y1119687D01*
Y1118937D01*
X564725Y1118795D01*
X564525D01*
Y1119830D01*
X564725D01*
G37*
G36*
G01X564325Y1124669D02*
X563925Y1124812D01*
Y1125562D01*
X564325Y1125705D01*
X564525D01*
Y1124669D01*
X564325D01*
G37*
G36*
G01X564725Y1126880D02*
X565125Y1126737D01*
Y1125987D01*
X564725Y1125845D01*
X564525D01*
Y1126880D01*
X564725D01*
G37*
G36*
G01X564325Y1127019D02*
X563925Y1127162D01*
Y1127912D01*
X564325Y1128055D01*
X564525D01*
Y1127019D01*
X564325D01*
G37*
G36*
G01X564725Y1129230D02*
X565125Y1129087D01*
Y1128337D01*
X564725Y1128195D01*
X564525D01*
Y1129230D01*
X564725D01*
G37*
G36*
G01X550344Y1118254D02*
X550744Y1118111D01*
Y1117361D01*
X550344Y1117219D01*
X550144D01*
Y1118254D01*
X550344D01*
G37*
G36*
G01Y1115904D02*
X550744Y1115761D01*
Y1115011D01*
X550344Y1114869D01*
X550144D01*
Y1115904D01*
X550344D01*
G37*
G36*
G01Y1113554D02*
X550744Y1113411D01*
Y1112661D01*
X550344Y1112519D01*
X550144D01*
Y1113554D01*
X550344D01*
G37*
G36*
G01X549944Y1116044D02*
X549544Y1116187D01*
Y1116937D01*
X549944Y1117079D01*
X550144D01*
Y1116044D01*
X549944D01*
G37*
G36*
G01Y1113694D02*
X549544Y1113837D01*
Y1114587D01*
X549944Y1114729D01*
X550144D01*
Y1113694D01*
X549944D01*
G37*
G36*
G01Y1123094D02*
X549544Y1123237D01*
Y1123987D01*
X549944Y1124129D01*
X550144D01*
Y1123094D01*
X549944D01*
G37*
G36*
G01Y1120744D02*
X549544Y1120887D01*
Y1121637D01*
X549944Y1121779D01*
X550144D01*
Y1120744D01*
X549944D01*
G37*
G36*
G01Y1125444D02*
X549544Y1125587D01*
Y1126337D01*
X549944Y1126479D01*
X550144D01*
Y1125444D01*
X549944D01*
G37*
G36*
G01Y1127794D02*
X549544Y1127937D01*
Y1128687D01*
X549944Y1128829D01*
X550144D01*
Y1127794D01*
X549944D01*
G37*
G36*
G01X550344Y1125304D02*
X550744Y1125161D01*
Y1124411D01*
X550344Y1124269D01*
X550144D01*
Y1125304D01*
X550344D01*
G37*
G36*
G01Y1122954D02*
X550744Y1122811D01*
Y1122061D01*
X550344Y1121919D01*
X550144D01*
Y1122954D01*
X550344D01*
G37*
G36*
G01Y1120604D02*
X550744Y1120461D01*
Y1119711D01*
X550344Y1119569D01*
X550144D01*
Y1120604D01*
X550344D01*
G37*
G36*
G01Y1127654D02*
X550744Y1127511D01*
Y1126761D01*
X550344Y1126619D01*
X550144D01*
Y1127654D01*
X550344D01*
G37*
G36*
G01X549944Y1118394D02*
X549544Y1118537D01*
Y1119287D01*
X549944Y1119429D01*
X550144D01*
Y1118394D01*
X549944D01*
G37*
G36*
G01X551544Y1118254D02*
X551944Y1118111D01*
Y1117361D01*
X551544Y1117219D01*
X551344D01*
Y1118254D01*
X551544D01*
G37*
G36*
G01Y1115904D02*
X551944Y1115761D01*
Y1115011D01*
X551544Y1114869D01*
X551344D01*
Y1115904D01*
X551544D01*
G37*
G36*
G01Y1113554D02*
X551944Y1113411D01*
Y1112661D01*
X551544Y1112519D01*
X551344D01*
Y1113554D01*
X551544D01*
G37*
G36*
G01X551144Y1116044D02*
X550744Y1116187D01*
Y1116937D01*
X551144Y1117079D01*
X551344D01*
Y1116044D01*
X551144D01*
G37*
G36*
G01Y1113694D02*
X550744Y1113837D01*
Y1114587D01*
X551144Y1114729D01*
X551344D01*
Y1113694D01*
X551144D01*
G37*
G36*
G01X551544Y1125304D02*
X551944Y1125161D01*
Y1124411D01*
X551544Y1124269D01*
X551344D01*
Y1125304D01*
X551544D01*
G37*
G36*
G01Y1122954D02*
X551944Y1122811D01*
Y1122061D01*
X551544Y1121919D01*
X551344D01*
Y1122954D01*
X551544D01*
G37*
G36*
G01Y1120604D02*
X551944Y1120461D01*
Y1119711D01*
X551544Y1119569D01*
X551344D01*
Y1120604D01*
X551544D01*
G37*
G36*
G01X551144Y1123094D02*
X550744Y1123237D01*
Y1123987D01*
X551144Y1124129D01*
X551344D01*
Y1123094D01*
X551144D01*
G37*
G36*
G01Y1120744D02*
X550744Y1120887D01*
Y1121637D01*
X551144Y1121779D01*
X551344D01*
Y1120744D01*
X551144D01*
G37*
G36*
G01Y1125444D02*
X550744Y1125587D01*
Y1126337D01*
X551144Y1126479D01*
X551344D01*
Y1125444D01*
X551144D01*
G37*
G36*
G01X551544Y1127654D02*
X551944Y1127511D01*
Y1126761D01*
X551544Y1126619D01*
X551344D01*
Y1127654D01*
X551544D01*
G37*
G36*
G01X551144Y1127794D02*
X550744Y1127937D01*
Y1128687D01*
X551144Y1128829D01*
X551344D01*
Y1127794D01*
X551144D01*
G37*
G36*
G01Y1118394D02*
X550744Y1118537D01*
Y1119287D01*
X551144Y1119429D01*
X551344D01*
Y1118394D01*
X551144D01*
G37*
G36*
G01X557164Y1116349D02*
X556764Y1116492D01*
Y1117242D01*
X557164Y1117384D01*
X557364D01*
Y1116349D01*
X557164D01*
G37*
G36*
G01Y1113999D02*
X556764Y1114142D01*
Y1114892D01*
X557164Y1115034D01*
X557364D01*
Y1113999D01*
X557164D01*
G37*
G36*
G01X557564Y1116209D02*
X557964Y1116067D01*
Y1115317D01*
X557564Y1115174D01*
X557364D01*
Y1116209D01*
X557564D01*
G37*
G36*
G01Y1113859D02*
X557964Y1113717D01*
Y1112967D01*
X557564Y1112824D01*
X557364D01*
Y1113859D01*
X557564D01*
G37*
G36*
G01Y1118559D02*
X557964Y1118417D01*
Y1117667D01*
X557564Y1117524D01*
X557364D01*
Y1118559D01*
X557564D01*
G37*
G36*
G01X557164Y1123399D02*
X556764Y1123542D01*
Y1124292D01*
X557164Y1124434D01*
X557364D01*
Y1123399D01*
X557164D01*
G37*
G36*
G01Y1121049D02*
X556764Y1121192D01*
Y1121942D01*
X557164Y1122084D01*
X557364D01*
Y1121049D01*
X557164D01*
G37*
G36*
G01Y1118699D02*
X556764Y1118842D01*
Y1119592D01*
X557164Y1119734D01*
X557364D01*
Y1118699D01*
X557164D01*
G37*
G36*
G01X557564Y1123259D02*
X557964Y1123117D01*
Y1122367D01*
X557564Y1122224D01*
X557364D01*
Y1123259D01*
X557564D01*
G37*
G36*
G01Y1120909D02*
X557964Y1120767D01*
Y1120017D01*
X557564Y1119874D01*
X557364D01*
Y1120909D01*
X557564D01*
G37*
G36*
G01X557164Y1125749D02*
X556764Y1125892D01*
Y1126642D01*
X557164Y1126784D01*
X557364D01*
Y1125749D01*
X557164D01*
G37*
G36*
G01X557564Y1125609D02*
X557964Y1125467D01*
Y1124717D01*
X557564Y1124574D01*
X557364D01*
Y1125609D01*
X557564D01*
G37*
G36*
G01X557164Y1128099D02*
X556764Y1128242D01*
Y1128992D01*
X557164Y1129134D01*
X557364D01*
Y1128099D01*
X557164D01*
G37*
G36*
G01X557564Y1127959D02*
X557964Y1127817D01*
Y1127067D01*
X557564Y1126924D01*
X557364D01*
Y1127959D01*
X557564D01*
G37*
G36*
G01X559564Y1116349D02*
X559164Y1116492D01*
Y1117242D01*
X559564Y1117384D01*
X559764D01*
Y1116349D01*
X559564D01*
G37*
G36*
G01Y1113999D02*
X559164Y1114142D01*
Y1114892D01*
X559564Y1115034D01*
X559764D01*
Y1113999D01*
X559564D01*
G37*
G36*
G01X559964Y1116209D02*
X560364Y1116067D01*
Y1115317D01*
X559964Y1115174D01*
X559764D01*
Y1116209D01*
X559964D01*
G37*
G36*
G01Y1113859D02*
X560364Y1113717D01*
Y1112967D01*
X559964Y1112824D01*
X559764D01*
Y1113859D01*
X559964D01*
G37*
G36*
G01Y1118559D02*
X560364Y1118417D01*
Y1117667D01*
X559964Y1117524D01*
X559764D01*
Y1118559D01*
X559964D01*
G37*
G36*
G01X559564Y1123399D02*
X559164Y1123542D01*
Y1124292D01*
X559564Y1124434D01*
X559764D01*
Y1123399D01*
X559564D01*
G37*
G36*
G01Y1121049D02*
X559164Y1121192D01*
Y1121942D01*
X559564Y1122084D01*
X559764D01*
Y1121049D01*
X559564D01*
G37*
G36*
G01Y1118699D02*
X559164Y1118842D01*
Y1119592D01*
X559564Y1119734D01*
X559764D01*
Y1118699D01*
X559564D01*
G37*
G36*
G01X559964Y1123259D02*
X560364Y1123117D01*
Y1122367D01*
X559964Y1122224D01*
X559764D01*
Y1123259D01*
X559964D01*
G37*
G36*
G01Y1120909D02*
X560364Y1120767D01*
Y1120017D01*
X559964Y1119874D01*
X559764D01*
Y1120909D01*
X559964D01*
G37*
G36*
G01X559564Y1125749D02*
X559164Y1125892D01*
Y1126642D01*
X559564Y1126784D01*
X559764D01*
Y1125749D01*
X559564D01*
G37*
G36*
G01X559964Y1125609D02*
X560364Y1125467D01*
Y1124717D01*
X559964Y1124574D01*
X559764D01*
Y1125609D01*
X559964D01*
G37*
G36*
G01X559564Y1128099D02*
X559164Y1128242D01*
Y1128992D01*
X559564Y1129134D01*
X559764D01*
Y1128099D01*
X559564D01*
G37*
G36*
G01X559964Y1127959D02*
X560364Y1127817D01*
Y1127067D01*
X559964Y1126924D01*
X559764D01*
Y1127959D01*
X559964D01*
G37*
G36*
G01X558764Y1118559D02*
X559164Y1118417D01*
Y1117667D01*
X558764Y1117524D01*
X558564D01*
Y1118559D01*
X558764D01*
G37*
G36*
G01X558364Y1116349D02*
X557964Y1116492D01*
Y1117242D01*
X558364Y1117384D01*
X558564D01*
Y1116349D01*
X558364D01*
G37*
G36*
G01Y1113999D02*
X557964Y1114142D01*
Y1114892D01*
X558364Y1115034D01*
X558564D01*
Y1113999D01*
X558364D01*
G37*
G36*
G01X558764Y1116209D02*
X559164Y1116067D01*
Y1115317D01*
X558764Y1115174D01*
X558564D01*
Y1116209D01*
X558764D01*
G37*
G36*
G01Y1113859D02*
X559164Y1113717D01*
Y1112967D01*
X558764Y1112824D01*
X558564D01*
Y1113859D01*
X558764D01*
G37*
G36*
G01X558364Y1123399D02*
X557964Y1123542D01*
Y1124292D01*
X558364Y1124434D01*
X558564D01*
Y1123399D01*
X558364D01*
G37*
G36*
G01Y1121049D02*
X557964Y1121192D01*
Y1121942D01*
X558364Y1122084D01*
X558564D01*
Y1121049D01*
X558364D01*
G37*
G36*
G01Y1118699D02*
X557964Y1118842D01*
Y1119592D01*
X558364Y1119734D01*
X558564D01*
Y1118699D01*
X558364D01*
G37*
G36*
G01X558764Y1123259D02*
X559164Y1123117D01*
Y1122367D01*
X558764Y1122224D01*
X558564D01*
Y1123259D01*
X558764D01*
G37*
G36*
G01Y1120909D02*
X559164Y1120767D01*
Y1120017D01*
X558764Y1119874D01*
X558564D01*
Y1120909D01*
X558764D01*
G37*
G36*
G01X558364Y1125749D02*
X557964Y1125892D01*
Y1126642D01*
X558364Y1126784D01*
X558564D01*
Y1125749D01*
X558364D01*
G37*
G36*
G01X558764Y1125609D02*
X559164Y1125467D01*
Y1124717D01*
X558764Y1124574D01*
X558564D01*
Y1125609D01*
X558764D01*
G37*
G36*
G01X558364Y1128099D02*
X557964Y1128242D01*
Y1128992D01*
X558364Y1129134D01*
X558564D01*
Y1128099D01*
X558364D01*
G37*
G36*
G01X558764Y1127959D02*
X559164Y1127817D01*
Y1127067D01*
X558764Y1126924D01*
X558564D01*
Y1127959D01*
X558764D01*
G37*
G36*
G01X560764Y1116349D02*
X560364Y1116492D01*
Y1117242D01*
X560764Y1117384D01*
X560964D01*
Y1116349D01*
X560764D01*
G37*
G36*
G01Y1113999D02*
X560364Y1114142D01*
Y1114892D01*
X560764Y1115034D01*
X560964D01*
Y1113999D01*
X560764D01*
G37*
G36*
G01X561164Y1118559D02*
X561564Y1118417D01*
Y1117667D01*
X561164Y1117524D01*
X560964D01*
Y1118559D01*
X561164D01*
G37*
G36*
G01Y1116209D02*
X561564Y1116067D01*
Y1115317D01*
X561164Y1115174D01*
X560964D01*
Y1116209D01*
X561164D01*
G37*
G36*
G01Y1113859D02*
X561564Y1113717D01*
Y1112967D01*
X561164Y1112824D01*
X560964D01*
Y1113859D01*
X561164D01*
G37*
G36*
G01Y1127959D02*
X561564Y1127817D01*
Y1127067D01*
X561164Y1126924D01*
X560964D01*
Y1127959D01*
X561164D01*
G37*
G36*
G01X560764Y1128099D02*
X560364Y1128242D01*
Y1128992D01*
X560764Y1129134D01*
X560964D01*
Y1128099D01*
X560764D01*
G37*
G36*
G01X561164Y1123259D02*
X561564Y1123117D01*
Y1122367D01*
X561164Y1122224D01*
X560964D01*
Y1123259D01*
X561164D01*
G37*
G36*
G01Y1120909D02*
X561564Y1120767D01*
Y1120017D01*
X561164Y1119874D01*
X560964D01*
Y1120909D01*
X561164D01*
G37*
G36*
G01X560764Y1121049D02*
X560364Y1121192D01*
Y1121942D01*
X560764Y1122084D01*
X560964D01*
Y1121049D01*
X560764D01*
G37*
G36*
G01Y1118699D02*
X560364Y1118842D01*
Y1119592D01*
X560764Y1119734D01*
X560964D01*
Y1118699D01*
X560764D01*
G37*
G36*
G01Y1123399D02*
X560364Y1123542D01*
Y1124292D01*
X560764Y1124434D01*
X560964D01*
Y1123399D01*
X560764D01*
G37*
G36*
G01X561164Y1125609D02*
X561564Y1125467D01*
Y1124717D01*
X561164Y1124574D01*
X560964D01*
Y1125609D01*
X561164D01*
G37*
G36*
G01X560764Y1125749D02*
X560364Y1125892D01*
Y1126642D01*
X560764Y1126784D01*
X560964D01*
Y1125749D01*
X560764D01*
G37*
G36*
G01X563525Y1131580D02*
X563925Y1131437D01*
Y1130687D01*
X563525Y1130545D01*
X563325D01*
Y1131580D01*
X563525D01*
G37*
G36*
G01X563125Y1129369D02*
X562725Y1129512D01*
Y1130262D01*
X563125Y1130405D01*
X563325D01*
Y1129369D01*
X563125D01*
G37*
G36*
G01Y1131719D02*
X562725Y1131862D01*
Y1132612D01*
X563125Y1132755D01*
X563325D01*
Y1131719D01*
X563125D01*
G37*
G36*
G01X563525Y1133930D02*
X563925Y1133787D01*
Y1133037D01*
X563525Y1132895D01*
X563325D01*
Y1133930D01*
X563525D01*
G37*
G36*
G01X563125Y1134069D02*
X562725Y1134212D01*
Y1134962D01*
X563125Y1135105D01*
X563325D01*
Y1134069D01*
X563125D01*
G37*
G36*
G01Y1138769D02*
X562725Y1138912D01*
Y1139662D01*
X563125Y1139805D01*
X563325D01*
Y1138769D01*
X563125D01*
G37*
G36*
G01X563525Y1140980D02*
X563925Y1140837D01*
Y1140087D01*
X563525Y1139945D01*
X563325D01*
Y1140980D01*
X563525D01*
G37*
G36*
G01X563125Y1141119D02*
X562725Y1141262D01*
Y1142012D01*
X563125Y1142155D01*
X563325D01*
Y1141119D01*
X563125D01*
G37*
G36*
G01Y1136419D02*
X562725Y1136562D01*
Y1137312D01*
X563125Y1137455D01*
X563325D01*
Y1136419D01*
X563125D01*
G37*
G36*
G01X563525Y1136280D02*
X563925Y1136137D01*
Y1135387D01*
X563525Y1135245D01*
X563325D01*
Y1136280D01*
X563525D01*
G37*
G36*
G01Y1138630D02*
X563925Y1138487D01*
Y1137737D01*
X563525Y1137595D01*
X563325D01*
Y1138630D01*
X563525D01*
G37*
G36*
G01X565525Y1134069D02*
X565125Y1134212D01*
Y1134962D01*
X565525Y1135105D01*
X565725D01*
Y1134069D01*
X565525D01*
G37*
G36*
G01Y1129369D02*
X565125Y1129512D01*
Y1130262D01*
X565525Y1130405D01*
X565725D01*
Y1129369D01*
X565525D01*
G37*
G36*
G01Y1131719D02*
X565125Y1131862D01*
Y1132612D01*
X565525Y1132755D01*
X565725D01*
Y1131719D01*
X565525D01*
G37*
G36*
G01Y1138769D02*
X565125Y1138912D01*
Y1139662D01*
X565525Y1139805D01*
X565725D01*
Y1138769D01*
X565525D01*
G37*
G36*
G01Y1136419D02*
X565125Y1136562D01*
Y1137312D01*
X565525Y1137455D01*
X565725D01*
Y1136419D01*
X565525D01*
G37*
G36*
G01X564325Y1134069D02*
X563925Y1134212D01*
Y1134962D01*
X564325Y1135105D01*
X564525D01*
Y1134069D01*
X564325D01*
G37*
G36*
G01X564725Y1131580D02*
X565125Y1131437D01*
Y1130687D01*
X564725Y1130545D01*
X564525D01*
Y1131580D01*
X564725D01*
G37*
G36*
G01X564325Y1129369D02*
X563925Y1129512D01*
Y1130262D01*
X564325Y1130405D01*
X564525D01*
Y1129369D01*
X564325D01*
G37*
G36*
G01Y1131719D02*
X563925Y1131862D01*
Y1132612D01*
X564325Y1132755D01*
X564525D01*
Y1131719D01*
X564325D01*
G37*
G36*
G01X564725Y1133930D02*
X565125Y1133787D01*
Y1133037D01*
X564725Y1132895D01*
X564525D01*
Y1133930D01*
X564725D01*
G37*
G36*
G01X564325Y1138769D02*
X563925Y1138912D01*
Y1139662D01*
X564325Y1139805D01*
X564525D01*
Y1138769D01*
X564325D01*
G37*
G36*
G01Y1136419D02*
X563925Y1136562D01*
Y1137312D01*
X564325Y1137455D01*
X564525D01*
Y1136419D01*
X564325D01*
G37*
G36*
G01X564725Y1136280D02*
X565125Y1136137D01*
Y1135387D01*
X564725Y1135245D01*
X564525D01*
Y1136280D01*
X564725D01*
G37*
G36*
G01Y1138630D02*
X565125Y1138487D01*
Y1137737D01*
X564725Y1137595D01*
X564525D01*
Y1138630D01*
X564725D01*
G37*
G36*
G01X549944Y1130144D02*
X549544Y1130287D01*
Y1131037D01*
X549944Y1131179D01*
X550144D01*
Y1130144D01*
X549944D01*
G37*
G36*
G01Y1132494D02*
X549544Y1132637D01*
Y1133387D01*
X549944Y1133529D01*
X550144D01*
Y1132494D01*
X549944D01*
G37*
G36*
G01X550344Y1134704D02*
X550744Y1134561D01*
Y1133811D01*
X550344Y1133669D01*
X550144D01*
Y1134704D01*
X550344D01*
G37*
G36*
G01Y1132354D02*
X550744Y1132211D01*
Y1131461D01*
X550344Y1131319D01*
X550144D01*
Y1132354D01*
X550344D01*
G37*
G36*
G01Y1130004D02*
X550744Y1129861D01*
Y1129111D01*
X550344Y1128969D01*
X550144D01*
Y1130004D01*
X550344D01*
G37*
G36*
G01X549944Y1139544D02*
X549544Y1139687D01*
Y1140437D01*
X549944Y1140579D01*
X550144D01*
Y1139544D01*
X549944D01*
G37*
G36*
G01Y1141894D02*
X549544Y1142037D01*
Y1142787D01*
X549944Y1142929D01*
X550144D01*
Y1141894D01*
X549944D01*
G37*
G36*
G01Y1137194D02*
X549544Y1137337D01*
Y1138087D01*
X549944Y1138229D01*
X550144D01*
Y1137194D01*
X549944D01*
G37*
G36*
G01X550344Y1141754D02*
X550744Y1141611D01*
Y1140861D01*
X550344Y1140719D01*
X550144D01*
Y1141754D01*
X550344D01*
G37*
G36*
G01Y1144104D02*
X550744Y1143961D01*
Y1143211D01*
X550344Y1143069D01*
X550144D01*
Y1144104D01*
X550344D01*
G37*
G36*
G01Y1139404D02*
X550744Y1139261D01*
Y1138511D01*
X550344Y1138369D01*
X550144D01*
Y1139404D01*
X550344D01*
G37*
G36*
G01X549944Y1144244D02*
X549544Y1144387D01*
Y1145137D01*
X549944Y1145279D01*
X550144D01*
Y1144244D01*
X549944D01*
G37*
G36*
G01X550344Y1137054D02*
X550744Y1136911D01*
Y1136161D01*
X550344Y1136019D01*
X550144D01*
Y1137054D01*
X550344D01*
G37*
G36*
G01X549944Y1134844D02*
X549544Y1134987D01*
Y1135737D01*
X549944Y1135879D01*
X550144D01*
Y1134844D01*
X549944D01*
G37*
G36*
G01X551144Y1130144D02*
X550744Y1130287D01*
Y1131037D01*
X551144Y1131179D01*
X551344D01*
Y1130144D01*
X551144D01*
G37*
G36*
G01X551544Y1134704D02*
X551944Y1134561D01*
Y1133811D01*
X551544Y1133669D01*
X551344D01*
Y1134704D01*
X551544D01*
G37*
G36*
G01Y1132354D02*
X551944Y1132211D01*
Y1131461D01*
X551544Y1131319D01*
X551344D01*
Y1132354D01*
X551544D01*
G37*
G36*
G01Y1130004D02*
X551944Y1129861D01*
Y1129111D01*
X551544Y1128969D01*
X551344D01*
Y1130004D01*
X551544D01*
G37*
G36*
G01X551144Y1132494D02*
X550744Y1132637D01*
Y1133387D01*
X551144Y1133529D01*
X551344D01*
Y1132494D01*
X551144D01*
G37*
G36*
G01Y1144244D02*
X550744Y1144387D01*
Y1145137D01*
X551144Y1145279D01*
X551344D01*
Y1144244D01*
X551144D01*
G37*
G36*
G01Y1139544D02*
X550744Y1139687D01*
Y1140437D01*
X551144Y1140579D01*
X551344D01*
Y1139544D01*
X551144D01*
G37*
G36*
G01X551544Y1141754D02*
X551944Y1141611D01*
Y1140861D01*
X551544Y1140719D01*
X551344D01*
Y1141754D01*
X551544D01*
G37*
G36*
G01X551144Y1141894D02*
X550744Y1142037D01*
Y1142787D01*
X551144Y1142929D01*
X551344D01*
Y1141894D01*
X551144D01*
G37*
G36*
G01X551544Y1144104D02*
X551944Y1143961D01*
Y1143211D01*
X551544Y1143069D01*
X551344D01*
Y1144104D01*
X551544D01*
G37*
G36*
G01Y1139404D02*
X551944Y1139261D01*
Y1138511D01*
X551544Y1138369D01*
X551344D01*
Y1139404D01*
X551544D01*
G37*
G36*
G01X551144Y1137194D02*
X550744Y1137337D01*
Y1138087D01*
X551144Y1138229D01*
X551344D01*
Y1137194D01*
X551144D01*
G37*
G36*
G01X551544Y1137054D02*
X551944Y1136911D01*
Y1136161D01*
X551544Y1136019D01*
X551344D01*
Y1137054D01*
X551544D01*
G37*
G36*
G01X551144Y1134844D02*
X550744Y1134987D01*
Y1135737D01*
X551144Y1135879D01*
X551344D01*
Y1134844D01*
X551144D01*
G37*
G36*
G01X557164Y1130449D02*
X556764Y1130592D01*
Y1131342D01*
X557164Y1131484D01*
X557364D01*
Y1130449D01*
X557164D01*
G37*
G36*
G01Y1132799D02*
X556764Y1132942D01*
Y1133692D01*
X557164Y1133834D01*
X557364D01*
Y1132799D01*
X557164D01*
G37*
G36*
G01X557564Y1130309D02*
X557964Y1130167D01*
Y1129417D01*
X557564Y1129274D01*
X557364D01*
Y1130309D01*
X557564D01*
G37*
G36*
G01Y1132659D02*
X557964Y1132517D01*
Y1131767D01*
X557564Y1131624D01*
X557364D01*
Y1132659D01*
X557564D01*
G37*
G36*
G01Y1135009D02*
X557964Y1134867D01*
Y1134117D01*
X557564Y1133974D01*
X557364D01*
Y1135009D01*
X557564D01*
G37*
G36*
G01X557164Y1139849D02*
X556764Y1139992D01*
Y1140742D01*
X557164Y1140884D01*
X557364D01*
Y1139849D01*
X557164D01*
G37*
G36*
G01X557564Y1139709D02*
X557964Y1139567D01*
Y1138817D01*
X557564Y1138674D01*
X557364D01*
Y1139709D01*
X557564D01*
G37*
G36*
G01X557164Y1142199D02*
X556764Y1142342D01*
Y1143092D01*
X557164Y1143234D01*
X557364D01*
Y1142199D01*
X557164D01*
G37*
G36*
G01X557564Y1142059D02*
X557964Y1141917D01*
Y1141167D01*
X557564Y1141024D01*
X557364D01*
Y1142059D01*
X557564D01*
G37*
G36*
G01Y1144409D02*
X557964Y1144267D01*
Y1143517D01*
X557564Y1143374D01*
X557364D01*
Y1144409D01*
X557564D01*
G37*
G36*
G01X557164Y1135149D02*
X556764Y1135292D01*
Y1136042D01*
X557164Y1136184D01*
X557364D01*
Y1135149D01*
X557164D01*
G37*
G36*
G01Y1137499D02*
X556764Y1137642D01*
Y1138392D01*
X557164Y1138534D01*
X557364D01*
Y1137499D01*
X557164D01*
G37*
G36*
G01X557564Y1137359D02*
X557964Y1137217D01*
Y1136467D01*
X557564Y1136324D01*
X557364D01*
Y1137359D01*
X557564D01*
G37*
G36*
G01X559564Y1130449D02*
X559164Y1130592D01*
Y1131342D01*
X559564Y1131484D01*
X559764D01*
Y1130449D01*
X559564D01*
G37*
G36*
G01Y1132799D02*
X559164Y1132942D01*
Y1133692D01*
X559564Y1133834D01*
X559764D01*
Y1132799D01*
X559564D01*
G37*
G36*
G01X559964Y1130309D02*
X560364Y1130167D01*
Y1129417D01*
X559964Y1129274D01*
X559764D01*
Y1130309D01*
X559964D01*
G37*
G36*
G01Y1132659D02*
X560364Y1132517D01*
Y1131767D01*
X559964Y1131624D01*
X559764D01*
Y1132659D01*
X559964D01*
G37*
G36*
G01Y1135009D02*
X560364Y1134867D01*
Y1134117D01*
X559964Y1133974D01*
X559764D01*
Y1135009D01*
X559964D01*
G37*
G36*
G01X559564Y1139849D02*
X559164Y1139992D01*
Y1140742D01*
X559564Y1140884D01*
X559764D01*
Y1139849D01*
X559564D01*
G37*
G36*
G01X559964Y1139709D02*
X560364Y1139567D01*
Y1138817D01*
X559964Y1138674D01*
X559764D01*
Y1139709D01*
X559964D01*
G37*
G36*
G01Y1142059D02*
X560364Y1141917D01*
Y1141167D01*
X559964Y1141024D01*
X559764D01*
Y1142059D01*
X559964D01*
G37*
G36*
G01X559564Y1135149D02*
X559164Y1135292D01*
Y1136042D01*
X559564Y1136184D01*
X559764D01*
Y1135149D01*
X559564D01*
G37*
G36*
G01Y1137499D02*
X559164Y1137642D01*
Y1138392D01*
X559564Y1138534D01*
X559764D01*
Y1137499D01*
X559564D01*
G37*
G36*
G01X559964Y1137359D02*
X560364Y1137217D01*
Y1136467D01*
X559964Y1136324D01*
X559764D01*
Y1137359D01*
X559964D01*
G37*
G36*
G01X558764Y1132659D02*
X559164Y1132517D01*
Y1131767D01*
X558764Y1131624D01*
X558564D01*
Y1132659D01*
X558764D01*
G37*
G36*
G01Y1135009D02*
X559164Y1134867D01*
Y1134117D01*
X558764Y1133974D01*
X558564D01*
Y1135009D01*
X558764D01*
G37*
G36*
G01X558364Y1130449D02*
X557964Y1130592D01*
Y1131342D01*
X558364Y1131484D01*
X558564D01*
Y1130449D01*
X558364D01*
G37*
G36*
G01Y1132799D02*
X557964Y1132942D01*
Y1133692D01*
X558364Y1133834D01*
X558564D01*
Y1132799D01*
X558364D01*
G37*
G36*
G01X558764Y1130309D02*
X559164Y1130167D01*
Y1129417D01*
X558764Y1129274D01*
X558564D01*
Y1130309D01*
X558764D01*
G37*
G36*
G01X558364Y1139849D02*
X557964Y1139992D01*
Y1140742D01*
X558364Y1140884D01*
X558564D01*
Y1139849D01*
X558364D01*
G37*
G36*
G01X558764Y1139709D02*
X559164Y1139567D01*
Y1138817D01*
X558764Y1138674D01*
X558564D01*
Y1139709D01*
X558764D01*
G37*
G36*
G01X558364Y1142199D02*
X557964Y1142342D01*
Y1143092D01*
X558364Y1143234D01*
X558564D01*
Y1142199D01*
X558364D01*
G37*
G36*
G01X558764Y1142059D02*
X559164Y1141917D01*
Y1141167D01*
X558764Y1141024D01*
X558564D01*
Y1142059D01*
X558764D01*
G37*
G36*
G01X558364Y1135149D02*
X557964Y1135292D01*
Y1136042D01*
X558364Y1136184D01*
X558564D01*
Y1135149D01*
X558364D01*
G37*
G36*
G01Y1137499D02*
X557964Y1137642D01*
Y1138392D01*
X558364Y1138534D01*
X558564D01*
Y1137499D01*
X558364D01*
G37*
G36*
G01X558764Y1137359D02*
X559164Y1137217D01*
Y1136467D01*
X558764Y1136324D01*
X558564D01*
Y1137359D01*
X558764D01*
G37*
G36*
G01X561164Y1130309D02*
X561564Y1130167D01*
Y1129417D01*
X561164Y1129274D01*
X560964D01*
Y1130309D01*
X561164D01*
G37*
G36*
G01Y1132659D02*
X561564Y1132517D01*
Y1131767D01*
X561164Y1131624D01*
X560964D01*
Y1132659D01*
X561164D01*
G37*
G36*
G01Y1135009D02*
X561564Y1134867D01*
Y1134117D01*
X561164Y1133974D01*
X560964D01*
Y1135009D01*
X561164D01*
G37*
G36*
G01X560764Y1132799D02*
X560364Y1132942D01*
Y1133692D01*
X560764Y1133834D01*
X560964D01*
Y1132799D01*
X560764D01*
G37*
G36*
G01Y1130449D02*
X560364Y1130592D01*
Y1131342D01*
X560764Y1131484D01*
X560964D01*
Y1130449D01*
X560764D01*
G37*
G36*
G01X561164Y1139709D02*
X561564Y1139567D01*
Y1138817D01*
X561164Y1138674D01*
X560964D01*
Y1139709D01*
X561164D01*
G37*
G36*
G01X560764Y1139849D02*
X560364Y1139992D01*
Y1140742D01*
X560764Y1140884D01*
X560964D01*
Y1139849D01*
X560764D01*
G37*
G36*
G01X561164Y1142059D02*
X561564Y1141917D01*
Y1141167D01*
X561164Y1141024D01*
X560964D01*
Y1142059D01*
X561164D01*
G37*
G36*
G01Y1137359D02*
X561564Y1137217D01*
Y1136467D01*
X561164Y1136324D01*
X560964D01*
Y1137359D01*
X561164D01*
G37*
G36*
G01X560764Y1135149D02*
X560364Y1135292D01*
Y1136042D01*
X560764Y1136184D01*
X560964D01*
Y1135149D01*
X560764D01*
G37*
G36*
G01Y1137499D02*
X560364Y1137642D01*
Y1138392D01*
X560764Y1138534D01*
X560964D01*
Y1137499D01*
X560764D01*
G37*
G36*
G01X549944Y1146594D02*
X549544Y1146737D01*
Y1147487D01*
X549944Y1147629D01*
X550144D01*
Y1146594D01*
X549944D01*
G37*
G36*
G01X550344Y1146454D02*
X550744Y1146311D01*
Y1145561D01*
X550344Y1145419D01*
X550144D01*
Y1146454D01*
X550344D01*
G37*
G36*
G01Y1148804D02*
X550744Y1148661D01*
Y1147911D01*
X550344Y1147769D01*
X550144D01*
Y1148804D01*
X550344D01*
G37*
G36*
G01X549944Y1148944D02*
X549544Y1149087D01*
Y1149837D01*
X549944Y1149979D01*
X550144D01*
Y1148944D01*
X549944D01*
G37*
G36*
G01Y1151294D02*
X549544Y1151437D01*
Y1152187D01*
X549944Y1152329D01*
X550144D01*
Y1151294D01*
X549944D01*
G37*
G36*
G01X550344Y1151154D02*
X550744Y1151011D01*
Y1150261D01*
X550344Y1150119D01*
X550144D01*
Y1151154D01*
X550344D01*
G37*
G36*
G01X549944Y1153644D02*
X549544Y1153787D01*
Y1154537D01*
X549944Y1154679D01*
X550144D01*
Y1153644D01*
X549944D01*
G37*
G36*
G01Y1155994D02*
X549544Y1156137D01*
Y1156887D01*
X549944Y1157029D01*
X550144D01*
Y1155994D01*
X549944D01*
G37*
G36*
G01Y1158344D02*
X549544Y1158487D01*
Y1159237D01*
X549944Y1159379D01*
X550144D01*
Y1158344D01*
X549944D01*
G37*
G36*
G01Y1160694D02*
X549544Y1160837D01*
Y1161587D01*
X549944Y1161729D01*
X550144D01*
Y1160694D01*
X549944D01*
G37*
G36*
G01X550344Y1153504D02*
X550744Y1153361D01*
Y1152611D01*
X550344Y1152469D01*
X550144D01*
Y1153504D01*
X550344D01*
G37*
G36*
G01Y1155854D02*
X550744Y1155711D01*
Y1154961D01*
X550344Y1154819D01*
X550144D01*
Y1155854D01*
X550344D01*
G37*
G36*
G01Y1158204D02*
X550744Y1158061D01*
Y1157311D01*
X550344Y1157169D01*
X550144D01*
Y1158204D01*
X550344D01*
G37*
G36*
G01Y1160554D02*
X550744Y1160411D01*
Y1159661D01*
X550344Y1159519D01*
X550144D01*
Y1160554D01*
X550344D01*
G37*
G36*
G01X551544Y1151154D02*
X551944Y1151011D01*
Y1150261D01*
X551544Y1150119D01*
X551344D01*
Y1151154D01*
X551544D01*
G37*
G36*
G01X551144Y1148944D02*
X550744Y1149087D01*
Y1149837D01*
X551144Y1149979D01*
X551344D01*
Y1148944D01*
X551144D01*
G37*
G36*
G01Y1151294D02*
X550744Y1151437D01*
Y1152187D01*
X551144Y1152329D01*
X551344D01*
Y1151294D01*
X551144D01*
G37*
G36*
G01X551544Y1146454D02*
X551944Y1146311D01*
Y1145561D01*
X551544Y1145419D01*
X551344D01*
Y1146454D01*
X551544D01*
G37*
G36*
G01Y1148804D02*
X551944Y1148661D01*
Y1147911D01*
X551544Y1147769D01*
X551344D01*
Y1148804D01*
X551544D01*
G37*
G36*
G01X551144Y1146594D02*
X550744Y1146737D01*
Y1147487D01*
X551144Y1147629D01*
X551344D01*
Y1146594D01*
X551144D01*
G37*
G36*
G01Y1160694D02*
X550744Y1160837D01*
Y1161587D01*
X551144Y1161729D01*
X551344D01*
Y1160694D01*
X551144D01*
G37*
G36*
G01X551544Y1153504D02*
X551944Y1153361D01*
Y1152611D01*
X551544Y1152469D01*
X551344D01*
Y1153504D01*
X551544D01*
G37*
G36*
G01X551144Y1153644D02*
X550744Y1153787D01*
Y1154537D01*
X551144Y1154679D01*
X551344D01*
Y1153644D01*
X551144D01*
G37*
G36*
G01X551544Y1155854D02*
X551944Y1155711D01*
Y1154961D01*
X551544Y1154819D01*
X551344D01*
Y1155854D01*
X551544D01*
G37*
G36*
G01X551144Y1155994D02*
X550744Y1156137D01*
Y1156887D01*
X551144Y1157029D01*
X551344D01*
Y1155994D01*
X551144D01*
G37*
G36*
G01X551544Y1158204D02*
X551944Y1158061D01*
Y1157311D01*
X551544Y1157169D01*
X551344D01*
Y1158204D01*
X551544D01*
G37*
G36*
G01X551144Y1158344D02*
X550744Y1158487D01*
Y1159237D01*
X551144Y1159379D01*
X551344D01*
Y1158344D01*
X551144D01*
G37*
G36*
G01X551544Y1160554D02*
X551944Y1160411D01*
Y1159661D01*
X551544Y1159519D01*
X551344D01*
Y1160554D01*
X551544D01*
G37*
G36*
G01X550344Y1162904D02*
X550744Y1162761D01*
Y1162011D01*
X550344Y1161869D01*
X550144D01*
Y1162904D01*
X550344D01*
G37*
G36*
G01X549944Y1163044D02*
X549544Y1163187D01*
Y1163937D01*
X549944Y1164079D01*
X550144D01*
Y1163044D01*
X549944D01*
G37*
G36*
G01X551144D02*
X550744Y1163187D01*
Y1163937D01*
X551144Y1164079D01*
X551344D01*
Y1163044D01*
X551144D01*
G37*
G36*
G01X551544Y1162904D02*
X551944Y1162761D01*
Y1162011D01*
X551544Y1161869D01*
X551344D01*
Y1162904D01*
X551544D01*
G37*
G36*
G01X557413Y1575686D02*
G03I-720J0D01*
G37*
G36*
G01X562369D02*
G03I-720J0D01*
G37*
G36*
G01X557413Y1580678D02*
G03I-720J0D01*
G37*
G36*
G01X562369D02*
G03I-720J0D01*
G37*
G36*
G01X562713Y1599884D02*
G03I-720J0D01*
G37*
G36*
G01X555609Y1599790D02*
G03I-720J0D01*
G37*
G36*
G01X557413Y1587598D02*
G03I-720J0D01*
G37*
G36*
G01X562369D02*
G03I-720J0D01*
G37*
G36*
G01Y1592590D02*
G03I-720J0D01*
G37*
G36*
G01X557413D02*
G03I-720J0D01*
G37*
G36*
G01X562713Y1616788D02*
G03I-720J0D01*
G37*
G36*
G01Y1604876D02*
G03I-720J0D01*
G37*
G36*
G01Y1611796D02*
G03I-720J0D01*
G37*
G36*
G01X555609D02*
G03I-720J0D01*
G37*
G36*
G01Y1604876D02*
G03I-720J0D01*
G37*
G36*
G01Y1616788D02*
G03I-720J0D01*
G37*
G36*
G01X579340Y45112D02*
G03I-720J0D01*
G37*
G36*
G01X568869Y217916D02*
G03I-720J0D01*
G37*
G36*
G01X581432Y215877D02*
G03I-720J0D01*
G37*
G36*
G01X570388Y229812D02*
G03I-720J0D01*
G37*
G36*
G01X579431Y230109D02*
G03I-720J0D01*
G37*
G36*
G01X581120Y302402D02*
G03I-720J0D01*
G37*
G36*
G01X583156Y361032D02*
G03I-720J0D01*
G37*
G36*
G01X566428Y848264D02*
X566028Y848407D01*
Y849157D01*
X566428Y849299D01*
X566628D01*
Y848264D01*
X566428D01*
G37*
G36*
G01Y850614D02*
X566028Y850757D01*
Y851507D01*
X566428Y851649D01*
X566628D01*
Y850614D01*
X566428D01*
G37*
G36*
G01X566828Y850474D02*
X567228Y850331D01*
Y849581D01*
X566828Y849439D01*
X566628D01*
Y850474D01*
X566828D01*
G37*
G36*
G01X567628Y850614D02*
X567228Y850757D01*
Y851507D01*
X567628Y851649D01*
X567828D01*
Y850614D01*
X567628D01*
G37*
G36*
G01X576028Y866781D02*
X575628Y866923D01*
Y867673D01*
X576028Y867816D01*
X576228D01*
Y866781D01*
X576028D01*
G37*
G36*
G01X576428Y868991D02*
X576828Y868848D01*
Y868098D01*
X576428Y867956D01*
X576228D01*
Y868991D01*
X576428D01*
G37*
G36*
G01X577628D02*
X578028Y868848D01*
Y868098D01*
X577628Y867956D01*
X577428D01*
Y868991D01*
X577628D01*
G37*
G36*
G01X577228Y866781D02*
X576828Y866923D01*
Y867673D01*
X577228Y867816D01*
X577428D01*
Y866781D01*
X577228D01*
G37*
G36*
G01X574828D02*
X574428Y866923D01*
Y867673D01*
X574828Y867816D01*
X575028D01*
Y866781D01*
X574828D01*
G37*
G36*
G01Y864431D02*
X574428Y864573D01*
Y865323D01*
X574828Y865466D01*
X575028D01*
Y864431D01*
X574828D01*
G37*
G36*
G01X575228Y866641D02*
X575628Y866498D01*
Y865748D01*
X575228Y865606D01*
X575028D01*
Y866641D01*
X575228D01*
G37*
G36*
G01Y868991D02*
X575628Y868848D01*
Y868098D01*
X575228Y867956D01*
X575028D01*
Y868991D01*
X575228D01*
G37*
G36*
G01X569228Y866924D02*
X569628Y866781D01*
Y866031D01*
X569228Y865889D01*
X569028D01*
Y866924D01*
X569228D01*
G37*
G36*
G01Y864574D02*
X569628Y864431D01*
Y863681D01*
X569228Y863539D01*
X569028D01*
Y864574D01*
X569228D01*
G37*
G36*
G01Y852824D02*
X569628Y852681D01*
Y851931D01*
X569228Y851789D01*
X569028D01*
Y852824D01*
X569228D01*
G37*
G36*
G01Y862224D02*
X569628Y862081D01*
Y861331D01*
X569228Y861189D01*
X569028D01*
Y862224D01*
X569228D01*
G37*
G36*
G01Y859874D02*
X569628Y859731D01*
Y858981D01*
X569228Y858839D01*
X569028D01*
Y859874D01*
X569228D01*
G37*
G36*
G01Y857524D02*
X569628Y857381D01*
Y856631D01*
X569228Y856489D01*
X569028D01*
Y857524D01*
X569228D01*
G37*
G36*
G01Y855174D02*
X569628Y855031D01*
Y854281D01*
X569228Y854139D01*
X569028D01*
Y855174D01*
X569228D01*
G37*
G36*
G01X568828Y864714D02*
X568428Y864857D01*
Y865607D01*
X568828Y865749D01*
X569028D01*
Y864714D01*
X568828D01*
G37*
G36*
G01Y862364D02*
X568428Y862507D01*
Y863257D01*
X568828Y863399D01*
X569028D01*
Y862364D01*
X568828D01*
G37*
G36*
G01Y867064D02*
X568428Y867207D01*
Y867957D01*
X568828Y868099D01*
X569028D01*
Y867064D01*
X568828D01*
G37*
G36*
G01Y852964D02*
X568428Y853107D01*
Y853857D01*
X568828Y853999D01*
X569028D01*
Y852964D01*
X568828D01*
G37*
G36*
G01Y860014D02*
X568428Y860157D01*
Y860907D01*
X568828Y861049D01*
X569028D01*
Y860014D01*
X568828D01*
G37*
G36*
G01Y857664D02*
X568428Y857807D01*
Y858557D01*
X568828Y858699D01*
X569028D01*
Y857664D01*
X568828D01*
G37*
G36*
G01Y855314D02*
X568428Y855457D01*
Y856207D01*
X568828Y856349D01*
X569028D01*
Y855314D01*
X568828D01*
G37*
G36*
G01X566428Y864714D02*
X566028Y864857D01*
Y865607D01*
X566428Y865749D01*
X566628D01*
Y864714D01*
X566428D01*
G37*
G36*
G01Y862364D02*
X566028Y862507D01*
Y863257D01*
X566428Y863399D01*
X566628D01*
Y862364D01*
X566428D01*
G37*
G36*
G01Y867064D02*
X566028Y867207D01*
Y867957D01*
X566428Y868099D01*
X566628D01*
Y867064D01*
X566428D01*
G37*
G36*
G01X566828Y866924D02*
X567228Y866781D01*
Y866031D01*
X566828Y865889D01*
X566628D01*
Y866924D01*
X566828D01*
G37*
G36*
G01Y864574D02*
X567228Y864431D01*
Y863681D01*
X566828Y863539D01*
X566628D01*
Y864574D01*
X566828D01*
G37*
G36*
G01X566428Y852964D02*
X566028Y853107D01*
Y853857D01*
X566428Y853999D01*
X566628D01*
Y852964D01*
X566428D01*
G37*
G36*
G01Y860014D02*
X566028Y860157D01*
Y860907D01*
X566428Y861049D01*
X566628D01*
Y860014D01*
X566428D01*
G37*
G36*
G01Y857664D02*
X566028Y857807D01*
Y858557D01*
X566428Y858699D01*
X566628D01*
Y857664D01*
X566428D01*
G37*
G36*
G01Y855314D02*
X566028Y855457D01*
Y856207D01*
X566428Y856349D01*
X566628D01*
Y855314D01*
X566428D01*
G37*
G36*
G01X566828Y852824D02*
X567228Y852681D01*
Y851931D01*
X566828Y851789D01*
X566628D01*
Y852824D01*
X566828D01*
G37*
G36*
G01Y862224D02*
X567228Y862081D01*
Y861331D01*
X566828Y861189D01*
X566628D01*
Y862224D01*
X566828D01*
G37*
G36*
G01Y859874D02*
X567228Y859731D01*
Y858981D01*
X566828Y858839D01*
X566628D01*
Y859874D01*
X566828D01*
G37*
G36*
G01Y857524D02*
X567228Y857381D01*
Y856631D01*
X566828Y856489D01*
X566628D01*
Y857524D01*
X566828D01*
G37*
G36*
G01Y855174D02*
X567228Y855031D01*
Y854281D01*
X566828Y854139D01*
X566628D01*
Y855174D01*
X566828D01*
G37*
G36*
G01X568028Y866924D02*
X568428Y866781D01*
Y866031D01*
X568028Y865889D01*
X567828D01*
Y866924D01*
X568028D01*
G37*
G36*
G01Y864574D02*
X568428Y864431D01*
Y863681D01*
X568028Y863539D01*
X567828D01*
Y864574D01*
X568028D01*
G37*
G36*
G01X567628Y864714D02*
X567228Y864857D01*
Y865607D01*
X567628Y865749D01*
X567828D01*
Y864714D01*
X567628D01*
G37*
G36*
G01Y862364D02*
X567228Y862507D01*
Y863257D01*
X567628Y863399D01*
X567828D01*
Y862364D01*
X567628D01*
G37*
G36*
G01Y867064D02*
X567228Y867207D01*
Y867957D01*
X567628Y868099D01*
X567828D01*
Y867064D01*
X567628D01*
G37*
G36*
G01X568028Y852824D02*
X568428Y852681D01*
Y851931D01*
X568028Y851789D01*
X567828D01*
Y852824D01*
X568028D01*
G37*
G36*
G01X567628Y852964D02*
X567228Y853107D01*
Y853857D01*
X567628Y853999D01*
X567828D01*
Y852964D01*
X567628D01*
G37*
G36*
G01X568028Y862224D02*
X568428Y862081D01*
Y861331D01*
X568028Y861189D01*
X567828D01*
Y862224D01*
X568028D01*
G37*
G36*
G01Y859874D02*
X568428Y859731D01*
Y858981D01*
X568028Y858839D01*
X567828D01*
Y859874D01*
X568028D01*
G37*
G36*
G01Y857524D02*
X568428Y857381D01*
Y856631D01*
X568028Y856489D01*
X567828D01*
Y857524D01*
X568028D01*
G37*
G36*
G01Y855174D02*
X568428Y855031D01*
Y854281D01*
X568028Y854139D01*
X567828D01*
Y855174D01*
X568028D01*
G37*
G36*
G01X567628Y860014D02*
X567228Y860157D01*
Y860907D01*
X567628Y861049D01*
X567828D01*
Y860014D01*
X567628D01*
G37*
G36*
G01Y857664D02*
X567228Y857807D01*
Y858557D01*
X567628Y858699D01*
X567828D01*
Y857664D01*
X567628D01*
G37*
G36*
G01Y855314D02*
X567228Y855457D01*
Y856207D01*
X567628Y856349D01*
X567828D01*
Y855314D01*
X567628D01*
G37*
G36*
G01X578428Y883231D02*
X578028Y883373D01*
Y884123D01*
X578428Y884266D01*
X578628D01*
Y883231D01*
X578428D01*
G37*
G36*
G01Y880881D02*
X578028Y881023D01*
Y881773D01*
X578428Y881916D01*
X578628D01*
Y880881D01*
X578428D01*
G37*
G36*
G01Y878531D02*
X578028Y878673D01*
Y879423D01*
X578428Y879566D01*
X578628D01*
Y878531D01*
X578428D01*
G37*
G36*
G01Y871481D02*
X578028Y871623D01*
Y872373D01*
X578428Y872516D01*
X578628D01*
Y871481D01*
X578428D01*
G37*
G36*
G01X578828Y878391D02*
X579228Y878248D01*
Y877498D01*
X578828Y877356D01*
X578628D01*
Y878391D01*
X578828D01*
G37*
G36*
G01Y876041D02*
X579228Y875898D01*
Y875148D01*
X578828Y875006D01*
X578628D01*
Y876041D01*
X578828D01*
G37*
G36*
G01Y873691D02*
X579228Y873548D01*
Y872798D01*
X578828Y872656D01*
X578628D01*
Y873691D01*
X578828D01*
G37*
G36*
G01X578428Y876181D02*
X578028Y876323D01*
Y877073D01*
X578428Y877216D01*
X578628D01*
Y876181D01*
X578428D01*
G37*
G36*
G01Y873831D02*
X578028Y873973D01*
Y874723D01*
X578428Y874866D01*
X578628D01*
Y873831D01*
X578428D01*
G37*
G36*
G01X578828Y883091D02*
X579228Y882948D01*
Y882198D01*
X578828Y882056D01*
X578628D01*
Y883091D01*
X578828D01*
G37*
G36*
G01Y880741D02*
X579228Y880598D01*
Y879848D01*
X578828Y879706D01*
X578628D01*
Y880741D01*
X578828D01*
G37*
G36*
G01X576028Y880881D02*
X575628Y881023D01*
Y881773D01*
X576028Y881916D01*
X576228D01*
Y880881D01*
X576028D01*
G37*
G36*
G01Y883231D02*
X575628Y883373D01*
Y884123D01*
X576028Y884266D01*
X576228D01*
Y883231D01*
X576028D01*
G37*
G36*
G01Y869131D02*
X575628Y869273D01*
Y870023D01*
X576028Y870166D01*
X576228D01*
Y869131D01*
X576028D01*
G37*
G36*
G01X576428Y871341D02*
X576828Y871198D01*
Y870448D01*
X576428Y870306D01*
X576228D01*
Y871341D01*
X576428D01*
G37*
G36*
G01X576028Y871481D02*
X575628Y871623D01*
Y872373D01*
X576028Y872516D01*
X576228D01*
Y871481D01*
X576028D01*
G37*
G36*
G01X576428Y876041D02*
X576828Y875898D01*
Y875148D01*
X576428Y875006D01*
X576228D01*
Y876041D01*
X576428D01*
G37*
G36*
G01Y873691D02*
X576828Y873548D01*
Y872798D01*
X576428Y872656D01*
X576228D01*
Y873691D01*
X576428D01*
G37*
G36*
G01X576028Y876181D02*
X575628Y876323D01*
Y877073D01*
X576028Y877216D01*
X576228D01*
Y876181D01*
X576028D01*
G37*
G36*
G01Y873831D02*
X575628Y873973D01*
Y874723D01*
X576028Y874866D01*
X576228D01*
Y873831D01*
X576028D01*
G37*
G36*
G01X576428Y878391D02*
X576828Y878248D01*
Y877498D01*
X576428Y877356D01*
X576228D01*
Y878391D01*
X576428D01*
G37*
G36*
G01Y880741D02*
X576828Y880598D01*
Y879848D01*
X576428Y879706D01*
X576228D01*
Y880741D01*
X576428D01*
G37*
G36*
G01Y883091D02*
X576828Y882948D01*
Y882198D01*
X576428Y882056D01*
X576228D01*
Y883091D01*
X576428D01*
G37*
G36*
G01X576028Y878531D02*
X575628Y878673D01*
Y879423D01*
X576028Y879566D01*
X576228D01*
Y878531D01*
X576028D01*
G37*
G36*
G01X577628Y880741D02*
X578028Y880598D01*
Y879848D01*
X577628Y879706D01*
X577428D01*
Y880741D01*
X577628D01*
G37*
G36*
G01Y878391D02*
X578028Y878248D01*
Y877498D01*
X577628Y877356D01*
X577428D01*
Y878391D01*
X577628D01*
G37*
G36*
G01X577228Y883231D02*
X576828Y883373D01*
Y884123D01*
X577228Y884266D01*
X577428D01*
Y883231D01*
X577228D01*
G37*
G36*
G01Y880881D02*
X576828Y881023D01*
Y881773D01*
X577228Y881916D01*
X577428D01*
Y880881D01*
X577228D01*
G37*
G36*
G01Y878531D02*
X576828Y878673D01*
Y879423D01*
X577228Y879566D01*
X577428D01*
Y878531D01*
X577228D01*
G37*
G36*
G01Y869131D02*
X576828Y869273D01*
Y870023D01*
X577228Y870166D01*
X577428D01*
Y869131D01*
X577228D01*
G37*
G36*
G01X577628Y871341D02*
X578028Y871198D01*
Y870448D01*
X577628Y870306D01*
X577428D01*
Y871341D01*
X577628D01*
G37*
G36*
G01X577228Y871481D02*
X576828Y871623D01*
Y872373D01*
X577228Y872516D01*
X577428D01*
Y871481D01*
X577228D01*
G37*
G36*
G01X577628Y876041D02*
X578028Y875898D01*
Y875148D01*
X577628Y875006D01*
X577428D01*
Y876041D01*
X577628D01*
G37*
G36*
G01Y873691D02*
X578028Y873548D01*
Y872798D01*
X577628Y872656D01*
X577428D01*
Y873691D01*
X577628D01*
G37*
G36*
G01X577228Y876181D02*
X576828Y876323D01*
Y877073D01*
X577228Y877216D01*
X577428D01*
Y876181D01*
X577228D01*
G37*
G36*
G01Y873831D02*
X576828Y873973D01*
Y874723D01*
X577228Y874866D01*
X577428D01*
Y873831D01*
X577228D01*
G37*
G36*
G01X577628Y883091D02*
X578028Y882948D01*
Y882198D01*
X577628Y882056D01*
X577428D01*
Y883091D01*
X577628D01*
G37*
G36*
G01X574828Y883231D02*
X574428Y883373D01*
Y884123D01*
X574828Y884266D01*
X575028D01*
Y883231D01*
X574828D01*
G37*
G36*
G01Y880881D02*
X574428Y881023D01*
Y881773D01*
X574828Y881916D01*
X575028D01*
Y880881D01*
X574828D01*
G37*
G36*
G01Y878531D02*
X574428Y878673D01*
Y879423D01*
X574828Y879566D01*
X575028D01*
Y878531D01*
X574828D01*
G37*
G36*
G01X575228Y883091D02*
X575628Y882948D01*
Y882198D01*
X575228Y882056D01*
X575028D01*
Y883091D01*
X575228D01*
G37*
G36*
G01Y880741D02*
X575628Y880598D01*
Y879848D01*
X575228Y879706D01*
X575028D01*
Y880741D01*
X575228D01*
G37*
G36*
G01Y878391D02*
X575628Y878248D01*
Y877498D01*
X575228Y877356D01*
X575028D01*
Y878391D01*
X575228D01*
G37*
G36*
G01X574828Y869131D02*
X574428Y869273D01*
Y870023D01*
X574828Y870166D01*
X575028D01*
Y869131D01*
X574828D01*
G37*
G36*
G01X575228Y871341D02*
X575628Y871198D01*
Y870448D01*
X575228Y870306D01*
X575028D01*
Y871341D01*
X575228D01*
G37*
G36*
G01X574828Y871481D02*
X574428Y871623D01*
Y872373D01*
X574828Y872516D01*
X575028D01*
Y871481D01*
X574828D01*
G37*
G36*
G01Y876181D02*
X574428Y876323D01*
Y877073D01*
X574828Y877216D01*
X575028D01*
Y876181D01*
X574828D01*
G37*
G36*
G01Y873831D02*
X574428Y873973D01*
Y874723D01*
X574828Y874866D01*
X575028D01*
Y873831D01*
X574828D01*
G37*
G36*
G01X575228Y876041D02*
X575628Y875898D01*
Y875148D01*
X575228Y875006D01*
X575028D01*
Y876041D01*
X575228D01*
G37*
G36*
G01Y873691D02*
X575628Y873548D01*
Y872798D01*
X575228Y872656D01*
X575028D01*
Y873691D01*
X575228D01*
G37*
G36*
G01X569228Y878674D02*
X569628Y878531D01*
Y877781D01*
X569228Y877639D01*
X569028D01*
Y878674D01*
X569228D01*
G37*
G36*
G01Y881024D02*
X569628Y880881D01*
Y880131D01*
X569228Y879989D01*
X569028D01*
Y881024D01*
X569228D01*
G37*
G36*
G01Y883374D02*
X569628Y883231D01*
Y882481D01*
X569228Y882339D01*
X569028D01*
Y883374D01*
X569228D01*
G37*
G36*
G01Y873974D02*
X569628Y873831D01*
Y873081D01*
X569228Y872939D01*
X569028D01*
Y873974D01*
X569228D01*
G37*
G36*
G01Y876324D02*
X569628Y876181D01*
Y875431D01*
X569228Y875289D01*
X569028D01*
Y876324D01*
X569228D01*
G37*
G36*
G01Y871624D02*
X569628Y871481D01*
Y870731D01*
X569228Y870589D01*
X569028D01*
Y871624D01*
X569228D01*
G37*
G36*
G01Y869274D02*
X569628Y869131D01*
Y868381D01*
X569228Y868239D01*
X569028D01*
Y869274D01*
X569228D01*
G37*
G36*
G01X568828Y878814D02*
X568428Y878957D01*
Y879707D01*
X568828Y879849D01*
X569028D01*
Y878814D01*
X568828D01*
G37*
G36*
G01Y881164D02*
X568428Y881307D01*
Y882057D01*
X568828Y882199D01*
X569028D01*
Y881164D01*
X568828D01*
G37*
G36*
G01Y883514D02*
X568428Y883657D01*
Y884407D01*
X568828Y884549D01*
X569028D01*
Y883514D01*
X568828D01*
G37*
G36*
G01Y874114D02*
X568428Y874257D01*
Y875007D01*
X568828Y875149D01*
X569028D01*
Y874114D01*
X568828D01*
G37*
G36*
G01Y876464D02*
X568428Y876607D01*
Y877357D01*
X568828Y877499D01*
X569028D01*
Y876464D01*
X568828D01*
G37*
G36*
G01Y871764D02*
X568428Y871907D01*
Y872657D01*
X568828Y872799D01*
X569028D01*
Y871764D01*
X568828D01*
G37*
G36*
G01Y869414D02*
X568428Y869557D01*
Y870307D01*
X568828Y870449D01*
X569028D01*
Y869414D01*
X568828D01*
G37*
G36*
G01X566828Y869274D02*
X567228Y869131D01*
Y868381D01*
X566828Y868239D01*
X566628D01*
Y869274D01*
X566828D01*
G37*
G36*
G01X566428Y878814D02*
X566028Y878957D01*
Y879707D01*
X566428Y879849D01*
X566628D01*
Y878814D01*
X566428D01*
G37*
G36*
G01Y881164D02*
X566028Y881307D01*
Y882057D01*
X566428Y882199D01*
X566628D01*
Y881164D01*
X566428D01*
G37*
G36*
G01Y883514D02*
X566028Y883657D01*
Y884407D01*
X566428Y884549D01*
X566628D01*
Y883514D01*
X566428D01*
G37*
G36*
G01X566828Y878674D02*
X567228Y878531D01*
Y877781D01*
X566828Y877639D01*
X566628D01*
Y878674D01*
X566828D01*
G37*
G36*
G01Y881024D02*
X567228Y880881D01*
Y880131D01*
X566828Y879989D01*
X566628D01*
Y881024D01*
X566828D01*
G37*
G36*
G01Y883374D02*
X567228Y883231D01*
Y882481D01*
X566828Y882339D01*
X566628D01*
Y883374D01*
X566828D01*
G37*
G36*
G01X566428Y871764D02*
X566028Y871907D01*
Y872657D01*
X566428Y872799D01*
X566628D01*
Y871764D01*
X566428D01*
G37*
G36*
G01Y874114D02*
X566028Y874257D01*
Y875007D01*
X566428Y875149D01*
X566628D01*
Y874114D01*
X566428D01*
G37*
G36*
G01Y876464D02*
X566028Y876607D01*
Y877357D01*
X566428Y877499D01*
X566628D01*
Y876464D01*
X566428D01*
G37*
G36*
G01X566828Y873974D02*
X567228Y873831D01*
Y873081D01*
X566828Y872939D01*
X566628D01*
Y873974D01*
X566828D01*
G37*
G36*
G01Y876324D02*
X567228Y876181D01*
Y875431D01*
X566828Y875289D01*
X566628D01*
Y876324D01*
X566828D01*
G37*
G36*
G01X566428Y869414D02*
X566028Y869557D01*
Y870307D01*
X566428Y870449D01*
X566628D01*
Y869414D01*
X566428D01*
G37*
G36*
G01X566828Y871624D02*
X567228Y871481D01*
Y870731D01*
X566828Y870589D01*
X566628D01*
Y871624D01*
X566828D01*
G37*
G36*
G01X568028Y876324D02*
X568428Y876181D01*
Y875431D01*
X568028Y875289D01*
X567828D01*
Y876324D01*
X568028D01*
G37*
G36*
G01X567628Y871764D02*
X567228Y871907D01*
Y872657D01*
X567628Y872799D01*
X567828D01*
Y871764D01*
X567628D01*
G37*
G36*
G01Y874114D02*
X567228Y874257D01*
Y875007D01*
X567628Y875149D01*
X567828D01*
Y874114D01*
X567628D01*
G37*
G36*
G01Y876464D02*
X567228Y876607D01*
Y877357D01*
X567628Y877499D01*
X567828D01*
Y876464D01*
X567628D01*
G37*
G36*
G01Y869414D02*
X567228Y869557D01*
Y870307D01*
X567628Y870449D01*
X567828D01*
Y869414D01*
X567628D01*
G37*
G36*
G01X568028Y871624D02*
X568428Y871481D01*
Y870731D01*
X568028Y870589D01*
X567828D01*
Y871624D01*
X568028D01*
G37*
G36*
G01Y869274D02*
X568428Y869131D01*
Y868381D01*
X568028Y868239D01*
X567828D01*
Y869274D01*
X568028D01*
G37*
G36*
G01Y878674D02*
X568428Y878531D01*
Y877781D01*
X568028Y877639D01*
X567828D01*
Y878674D01*
X568028D01*
G37*
G36*
G01Y881024D02*
X568428Y880881D01*
Y880131D01*
X568028Y879989D01*
X567828D01*
Y881024D01*
X568028D01*
G37*
G36*
G01Y883374D02*
X568428Y883231D01*
Y882481D01*
X568028Y882339D01*
X567828D01*
Y883374D01*
X568028D01*
G37*
G36*
G01X567628Y878814D02*
X567228Y878957D01*
Y879707D01*
X567628Y879849D01*
X567828D01*
Y878814D01*
X567628D01*
G37*
G36*
G01Y881164D02*
X567228Y881307D01*
Y882057D01*
X567628Y882199D01*
X567828D01*
Y881164D01*
X567628D01*
G37*
G36*
G01Y883514D02*
X567228Y883657D01*
Y884407D01*
X567628Y884549D01*
X567828D01*
Y883514D01*
X567628D01*
G37*
G36*
G01X568028Y873974D02*
X568428Y873831D01*
Y873081D01*
X568028Y872939D01*
X567828D01*
Y873974D01*
X568028D01*
G37*
G36*
G01X581828Y895962D02*
X581428Y896105D01*
Y896855D01*
X581828Y896997D01*
X582028D01*
Y895962D01*
X581828D01*
G37*
G36*
G01Y893612D02*
X581428Y893755D01*
Y894505D01*
X581828Y894647D01*
X582028D01*
Y893612D01*
X581828D01*
G37*
G36*
G01Y898312D02*
X581428Y898455D01*
Y899205D01*
X581828Y899347D01*
X582028D01*
Y898312D01*
X581828D01*
G37*
G36*
G01Y891262D02*
X581428Y891405D01*
Y892155D01*
X581828Y892297D01*
X582028D01*
Y891262D01*
X581828D01*
G37*
G36*
G01X580628D02*
X580228Y891405D01*
Y892155D01*
X580628Y892297D01*
X580828D01*
Y891262D01*
X580628D01*
G37*
G36*
G01X581028Y900522D02*
X581428Y900379D01*
Y899629D01*
X581028Y899487D01*
X580828D01*
Y900522D01*
X581028D01*
G37*
G36*
G01X580628Y893612D02*
X580228Y893755D01*
Y894505D01*
X580628Y894647D01*
X580828D01*
Y893612D01*
X580628D01*
G37*
G36*
G01Y895962D02*
X580228Y896105D01*
Y896855D01*
X580628Y896997D01*
X580828D01*
Y895962D01*
X580628D01*
G37*
G36*
G01X581028Y893472D02*
X581428Y893329D01*
Y892579D01*
X581028Y892437D01*
X580828D01*
Y893472D01*
X581028D01*
G37*
G36*
G01Y895822D02*
X581428Y895679D01*
Y894929D01*
X581028Y894787D01*
X580828D01*
Y895822D01*
X581028D01*
G37*
G36*
G01Y898172D02*
X581428Y898029D01*
Y897279D01*
X581028Y897137D01*
X580828D01*
Y898172D01*
X581028D01*
G37*
G36*
G01X580628Y898312D02*
X580228Y898455D01*
Y899205D01*
X580628Y899347D01*
X580828D01*
Y898312D01*
X580628D01*
G37*
G36*
G01X578828Y885441D02*
X579228Y885298D01*
Y884548D01*
X578828Y884406D01*
X578628D01*
Y885441D01*
X578828D01*
G37*
G36*
G01Y890141D02*
X579228Y889998D01*
Y889248D01*
X578828Y889106D01*
X578628D01*
Y890141D01*
X578828D01*
G37*
G36*
G01Y892491D02*
X579228Y892348D01*
Y891598D01*
X578828Y891456D01*
X578628D01*
Y892491D01*
X578828D01*
G37*
G36*
G01X578428Y887931D02*
X578028Y888073D01*
Y888823D01*
X578428Y888966D01*
X578628D01*
Y887931D01*
X578428D01*
G37*
G36*
G01Y890281D02*
X578028Y890423D01*
Y891173D01*
X578428Y891316D01*
X578628D01*
Y890281D01*
X578428D01*
G37*
G36*
G01Y885581D02*
X578028Y885723D01*
Y886473D01*
X578428Y886616D01*
X578628D01*
Y885581D01*
X578428D01*
G37*
G36*
G01X578828Y887791D02*
X579228Y887648D01*
Y886898D01*
X578828Y886756D01*
X578628D01*
Y887791D01*
X578828D01*
G37*
G36*
G01X578428Y899681D02*
X578028Y899823D01*
Y900573D01*
X578428Y900716D01*
X578628D01*
Y899681D01*
X578428D01*
G37*
G36*
G01X578828Y894841D02*
X579228Y894698D01*
Y893948D01*
X578828Y893806D01*
X578628D01*
Y894841D01*
X578828D01*
G37*
G36*
G01Y897191D02*
X579228Y897048D01*
Y896298D01*
X578828Y896156D01*
X578628D01*
Y897191D01*
X578828D01*
G37*
G36*
G01X578428Y892631D02*
X578028Y892773D01*
Y893523D01*
X578428Y893666D01*
X578628D01*
Y892631D01*
X578428D01*
G37*
G36*
G01Y894981D02*
X578028Y895123D01*
Y895873D01*
X578428Y896016D01*
X578628D01*
Y894981D01*
X578428D01*
G37*
G36*
G01Y897331D02*
X578028Y897473D01*
Y898223D01*
X578428Y898366D01*
X578628D01*
Y897331D01*
X578428D01*
G37*
G36*
G01X578828Y899541D02*
X579228Y899398D01*
Y898648D01*
X578828Y898506D01*
X578628D01*
Y899541D01*
X578828D01*
G37*
G36*
G01X576428Y885441D02*
X576828Y885298D01*
Y884548D01*
X576428Y884406D01*
X576228D01*
Y885441D01*
X576428D01*
G37*
G36*
G01X576028Y887931D02*
X575628Y888073D01*
Y888823D01*
X576028Y888966D01*
X576228D01*
Y887931D01*
X576028D01*
G37*
G36*
G01Y890281D02*
X575628Y890423D01*
Y891173D01*
X576028Y891316D01*
X576228D01*
Y890281D01*
X576028D01*
G37*
G36*
G01Y885581D02*
X575628Y885723D01*
Y886473D01*
X576028Y886616D01*
X576228D01*
Y885581D01*
X576028D01*
G37*
G36*
G01X576428Y887791D02*
X576828Y887648D01*
Y886898D01*
X576428Y886756D01*
X576228D01*
Y887791D01*
X576428D01*
G37*
G36*
G01Y890141D02*
X576828Y889998D01*
Y889248D01*
X576428Y889106D01*
X576228D01*
Y890141D01*
X576428D01*
G37*
G36*
G01Y892491D02*
X576828Y892348D01*
Y891598D01*
X576428Y891456D01*
X576228D01*
Y892491D01*
X576428D01*
G37*
G36*
G01Y894841D02*
X576828Y894698D01*
Y893948D01*
X576428Y893806D01*
X576228D01*
Y894841D01*
X576428D01*
G37*
G36*
G01Y897191D02*
X576828Y897048D01*
Y896298D01*
X576428Y896156D01*
X576228D01*
Y897191D01*
X576428D01*
G37*
G36*
G01X576028Y892631D02*
X575628Y892773D01*
Y893523D01*
X576028Y893666D01*
X576228D01*
Y892631D01*
X576028D01*
G37*
G36*
G01Y894981D02*
X575628Y895123D01*
Y895873D01*
X576028Y896016D01*
X576228D01*
Y894981D01*
X576028D01*
G37*
G36*
G01Y897331D02*
X575628Y897473D01*
Y898223D01*
X576028Y898366D01*
X576228D01*
Y897331D01*
X576028D01*
G37*
G36*
G01X576428Y899541D02*
X576828Y899398D01*
Y898648D01*
X576428Y898506D01*
X576228D01*
Y899541D01*
X576428D01*
G37*
G36*
G01X577628Y885441D02*
X578028Y885298D01*
Y884548D01*
X577628Y884406D01*
X577428D01*
Y885441D01*
X577628D01*
G37*
G36*
G01Y890141D02*
X578028Y889998D01*
Y889248D01*
X577628Y889106D01*
X577428D01*
Y890141D01*
X577628D01*
G37*
G36*
G01Y892491D02*
X578028Y892348D01*
Y891598D01*
X577628Y891456D01*
X577428D01*
Y892491D01*
X577628D01*
G37*
G36*
G01X577228Y887931D02*
X576828Y888073D01*
Y888823D01*
X577228Y888966D01*
X577428D01*
Y887931D01*
X577228D01*
G37*
G36*
G01Y890281D02*
X576828Y890423D01*
Y891173D01*
X577228Y891316D01*
X577428D01*
Y890281D01*
X577228D01*
G37*
G36*
G01Y885581D02*
X576828Y885723D01*
Y886473D01*
X577228Y886616D01*
X577428D01*
Y885581D01*
X577228D01*
G37*
G36*
G01X577628Y887791D02*
X578028Y887648D01*
Y886898D01*
X577628Y886756D01*
X577428D01*
Y887791D01*
X577628D01*
G37*
G36*
G01Y894841D02*
X578028Y894698D01*
Y893948D01*
X577628Y893806D01*
X577428D01*
Y894841D01*
X577628D01*
G37*
G36*
G01Y897191D02*
X578028Y897048D01*
Y896298D01*
X577628Y896156D01*
X577428D01*
Y897191D01*
X577628D01*
G37*
G36*
G01X577228Y892631D02*
X576828Y892773D01*
Y893523D01*
X577228Y893666D01*
X577428D01*
Y892631D01*
X577228D01*
G37*
G36*
G01Y894981D02*
X576828Y895123D01*
Y895873D01*
X577228Y896016D01*
X577428D01*
Y894981D01*
X577228D01*
G37*
G36*
G01Y897331D02*
X576828Y897473D01*
Y898223D01*
X577228Y898366D01*
X577428D01*
Y897331D01*
X577228D01*
G37*
G36*
G01X577628Y899541D02*
X578028Y899398D01*
Y898648D01*
X577628Y898506D01*
X577428D01*
Y899541D01*
X577628D01*
G37*
G36*
G01X575228Y885441D02*
X575628Y885298D01*
Y884548D01*
X575228Y884406D01*
X575028D01*
Y885441D01*
X575228D01*
G37*
G36*
G01X574828Y887931D02*
X574428Y888073D01*
Y888823D01*
X574828Y888966D01*
X575028D01*
Y887931D01*
X574828D01*
G37*
G36*
G01Y890281D02*
X574428Y890423D01*
Y891173D01*
X574828Y891316D01*
X575028D01*
Y890281D01*
X574828D01*
G37*
G36*
G01X575228Y890141D02*
X575628Y889998D01*
Y889248D01*
X575228Y889106D01*
X575028D01*
Y890141D01*
X575228D01*
G37*
G36*
G01Y892491D02*
X575628Y892348D01*
Y891598D01*
X575228Y891456D01*
X575028D01*
Y892491D01*
X575228D01*
G37*
G36*
G01X574828Y885581D02*
X574428Y885723D01*
Y886473D01*
X574828Y886616D01*
X575028D01*
Y885581D01*
X574828D01*
G37*
G36*
G01X575228Y887791D02*
X575628Y887648D01*
Y886898D01*
X575228Y886756D01*
X575028D01*
Y887791D01*
X575228D01*
G37*
G36*
G01X574828Y894981D02*
X574428Y895123D01*
Y895873D01*
X574828Y896016D01*
X575028D01*
Y894981D01*
X574828D01*
G37*
G36*
G01Y897331D02*
X574428Y897473D01*
Y898223D01*
X574828Y898366D01*
X575028D01*
Y897331D01*
X574828D01*
G37*
G36*
G01Y892631D02*
X574428Y892773D01*
Y893523D01*
X574828Y893666D01*
X575028D01*
Y892631D01*
X574828D01*
G37*
G36*
G01X575228Y894841D02*
X575628Y894698D01*
Y893948D01*
X575228Y893806D01*
X575028D01*
Y894841D01*
X575228D01*
G37*
G36*
G01Y897191D02*
X575628Y897048D01*
Y896298D01*
X575228Y896156D01*
X575028D01*
Y897191D01*
X575228D01*
G37*
G36*
G01Y899541D02*
X575628Y899398D01*
Y898648D01*
X575228Y898506D01*
X575028D01*
Y899541D01*
X575228D01*
G37*
G36*
G01X566818Y900107D02*
X567202Y900289D01*
X567732Y899759D01*
X567550Y899375D01*
X567408Y899234D01*
X566676Y899966D01*
X566818Y900107D01*
G37*
G36*
G01X568098Y898261D02*
X567714Y898079D01*
X567184Y898610D01*
X567366Y898993D01*
X567507Y899135D01*
X568239Y898403D01*
X568098Y898261D01*
G37*
G36*
G01X569228Y885724D02*
X569628Y885581D01*
Y884831D01*
X569228Y884689D01*
X569028D01*
Y885724D01*
X569228D01*
G37*
G36*
G01Y890424D02*
X569628Y890281D01*
Y889531D01*
X569228Y889389D01*
X569028D01*
Y890424D01*
X569228D01*
G37*
G36*
G01Y888074D02*
X569628Y887931D01*
Y887181D01*
X569228Y887039D01*
X569028D01*
Y888074D01*
X569228D01*
G37*
G36*
G01X568828Y888214D02*
X568428Y888357D01*
Y889107D01*
X568828Y889249D01*
X569028D01*
Y888214D01*
X568828D01*
G37*
G36*
G01Y890564D02*
X568428Y890707D01*
Y891457D01*
X568828Y891599D01*
X569028D01*
Y890564D01*
X568828D01*
G37*
G36*
G01Y885864D02*
X568428Y886007D01*
Y886757D01*
X568828Y886899D01*
X569028D01*
Y885864D01*
X568828D01*
G37*
G36*
G01X569228Y895124D02*
X569628Y894981D01*
Y894231D01*
X569228Y894089D01*
X569028D01*
Y895124D01*
X569228D01*
G37*
G36*
G01Y892774D02*
X569628Y892631D01*
Y891881D01*
X569228Y891739D01*
X569028D01*
Y892774D01*
X569228D01*
G37*
G36*
G01X568828Y892914D02*
X568428Y893057D01*
Y893807D01*
X568828Y893949D01*
X569028D01*
Y892914D01*
X568828D01*
G37*
G36*
G01Y895264D02*
X568428Y895407D01*
Y896157D01*
X568828Y896299D01*
X569028D01*
Y895264D01*
X568828D01*
G37*
G36*
G01X566828Y885724D02*
X567228Y885581D01*
Y884831D01*
X566828Y884689D01*
X566628D01*
Y885724D01*
X566828D01*
G37*
G36*
G01X566428Y888214D02*
X566028Y888357D01*
Y889107D01*
X566428Y889249D01*
X566628D01*
Y888214D01*
X566428D01*
G37*
G36*
G01Y890564D02*
X566028Y890707D01*
Y891457D01*
X566428Y891599D01*
X566628D01*
Y890564D01*
X566428D01*
G37*
G36*
G01Y885864D02*
X566028Y886007D01*
Y886757D01*
X566428Y886899D01*
X566628D01*
Y885864D01*
X566428D01*
G37*
G36*
G01X566828Y890424D02*
X567228Y890281D01*
Y889531D01*
X566828Y889389D01*
X566628D01*
Y890424D01*
X566828D01*
G37*
G36*
G01Y888074D02*
X567228Y887931D01*
Y887181D01*
X566828Y887039D01*
X566628D01*
Y888074D01*
X566828D01*
G37*
G36*
G01Y895124D02*
X567228Y894981D01*
Y894231D01*
X566828Y894089D01*
X566628D01*
Y895124D01*
X566828D01*
G37*
G36*
G01X566428Y892914D02*
X566028Y893057D01*
Y893807D01*
X566428Y893949D01*
X566628D01*
Y892914D01*
X566428D01*
G37*
G36*
G01X566828Y892774D02*
X567228Y892631D01*
Y891881D01*
X566828Y891739D01*
X566628D01*
Y892774D01*
X566828D01*
G37*
G36*
G01X568028Y885724D02*
X568428Y885581D01*
Y884831D01*
X568028Y884689D01*
X567828D01*
Y885724D01*
X568028D01*
G37*
G36*
G01Y890424D02*
X568428Y890281D01*
Y889531D01*
X568028Y889389D01*
X567828D01*
Y890424D01*
X568028D01*
G37*
G36*
G01X567628Y888214D02*
X567228Y888357D01*
Y889107D01*
X567628Y889249D01*
X567828D01*
Y888214D01*
X567628D01*
G37*
G36*
G01Y890564D02*
X567228Y890707D01*
Y891457D01*
X567628Y891599D01*
X567828D01*
Y890564D01*
X567628D01*
G37*
G36*
G01X568028Y888074D02*
X568428Y887931D01*
Y887181D01*
X568028Y887039D01*
X567828D01*
Y888074D01*
X568028D01*
G37*
G36*
G01X567628Y885864D02*
X567228Y886007D01*
Y886757D01*
X567628Y886899D01*
X567828D01*
Y885864D01*
X567628D01*
G37*
G36*
G01X567249Y897412D02*
X566865Y897230D01*
X566335Y897761D01*
X566517Y898144D01*
X566658Y898286D01*
X567390Y897554D01*
X567249Y897412D01*
G37*
G36*
G01X565969Y899258D02*
X566353Y899440D01*
X566883Y898910D01*
X566701Y898526D01*
X566559Y898385D01*
X565827Y899117D01*
X565969Y899258D01*
G37*
G36*
G01X568028Y895124D02*
X568428Y894981D01*
Y894231D01*
X568028Y894089D01*
X567828D01*
Y895124D01*
X568028D01*
G37*
G36*
G01X567628Y895264D02*
X567228Y895407D01*
Y896157D01*
X567628Y896299D01*
X567828D01*
Y895264D01*
X567628D01*
G37*
G36*
G01X568028Y892774D02*
X568428Y892631D01*
Y891881D01*
X568028Y891739D01*
X567828D01*
Y892774D01*
X568028D01*
G37*
G36*
G01X567628Y892914D02*
X567228Y893057D01*
Y893807D01*
X567628Y893949D01*
X567828D01*
Y892914D01*
X567628D01*
G37*
G36*
G01X580004Y916845D02*
X579621Y916663D01*
X579090Y917193D01*
X579272Y917577D01*
X579414Y917718D01*
X580146Y916986D01*
X580004Y916845D01*
G37*
G36*
G01X580386Y917029D02*
X580770Y917211D01*
X581300Y916681D01*
X581118Y916297D01*
X580977Y916156D01*
X580245Y916887D01*
X580386Y917029D01*
G37*
G36*
G01X581666Y915183D02*
X581282Y915001D01*
X580752Y915531D01*
X580934Y915915D01*
X581075Y916056D01*
X581807Y915325D01*
X581666Y915183D01*
G37*
G36*
G01X582048Y915367D02*
X582431Y915549D01*
X582962Y915019D01*
X582780Y914635D01*
X582638Y914494D01*
X581906Y915226D01*
X582048Y915367D01*
G37*
G36*
G01X574490Y914434D02*
X574874Y914617D01*
X575404Y914086D01*
X575222Y913703D01*
X575081Y913561D01*
X574349Y914293D01*
X574490Y914434D01*
G37*
G36*
G01X574109Y914251D02*
X573725Y914069D01*
X573195Y914599D01*
X573377Y914982D01*
X573518Y915124D01*
X574250Y914392D01*
X574109Y914251D01*
G37*
G36*
G01X575770Y912589D02*
X575387Y912407D01*
X574856Y912937D01*
X575038Y913321D01*
X575180Y913462D01*
X575912Y912730D01*
X575770Y912589D01*
G37*
G36*
G01X572447Y915912D02*
X572063Y915730D01*
X571533Y916261D01*
X571715Y916644D01*
X571856Y916786D01*
X572588Y916054D01*
X572447Y915912D01*
G37*
G36*
G01X572829Y916096D02*
X573212Y916278D01*
X573743Y915748D01*
X573561Y915364D01*
X573419Y915223D01*
X572687Y915955D01*
X572829Y916096D01*
G37*
G36*
G01X576152Y912773D02*
X576536Y912955D01*
X577066Y912424D01*
X576884Y912041D01*
X576743Y911899D01*
X576011Y912631D01*
X576152Y912773D01*
G37*
G36*
G01X577432Y910927D02*
X577048Y910745D01*
X576518Y911275D01*
X576700Y911659D01*
X576842Y911800D01*
X577573Y911069D01*
X577432Y910927D01*
G37*
G36*
G01X577814Y911111D02*
X578197Y911293D01*
X578728Y910763D01*
X578546Y910379D01*
X578404Y910238D01*
X577672Y910970D01*
X577814Y911111D01*
G37*
G36*
G01X579475Y909449D02*
X579859Y909631D01*
X580389Y909101D01*
X580207Y908717D01*
X580066Y908576D01*
X579334Y909308D01*
X579475Y909449D01*
G37*
G36*
G01X581137Y907788D02*
X581521Y907970D01*
X582051Y907439D01*
X581869Y907056D01*
X581728Y906914D01*
X580996Y907646D01*
X581137Y907788D01*
G37*
G36*
G01X579094Y909265D02*
X578710Y909083D01*
X578180Y909614D01*
X578362Y909997D01*
X578503Y910139D01*
X579235Y909407D01*
X579094Y909265D01*
G37*
G36*
G01X580755Y907604D02*
X580372Y907422D01*
X579841Y907952D01*
X580024Y908336D01*
X580165Y908477D01*
X580897Y907745D01*
X580755Y907604D01*
G37*
G36*
G01X582417Y905942D02*
X582033Y905760D01*
X581503Y906290D01*
X581685Y906674D01*
X581827Y906815D01*
X582558Y906084D01*
X582417Y905942D01*
G37*
G36*
G01X569087Y915876D02*
X568704Y915694D01*
X568173Y916224D01*
X568355Y916608D01*
X568497Y916749D01*
X569229Y916017D01*
X569087Y915876D01*
G37*
G36*
G01X570749Y914214D02*
X570365Y914032D01*
X569835Y914563D01*
X570017Y914946D01*
X570158Y915088D01*
X570890Y914356D01*
X570749Y914214D01*
G37*
G36*
G01X572411Y912553D02*
X572027Y912371D01*
X571497Y912901D01*
X571679Y913284D01*
X571820Y913426D01*
X572552Y912694D01*
X572411Y912553D01*
G37*
G36*
G01X574072Y910891D02*
X573689Y910709D01*
X573158Y911239D01*
X573340Y911623D01*
X573482Y911764D01*
X574214Y911032D01*
X574072Y910891D01*
G37*
G36*
G01X569469Y916060D02*
X569853Y916242D01*
X570383Y915712D01*
X570201Y915328D01*
X570059Y915187D01*
X569328Y915918D01*
X569469Y916060D01*
G37*
G36*
G01X571131Y914398D02*
X571514Y914580D01*
X572045Y914050D01*
X571863Y913666D01*
X571721Y913525D01*
X570989Y914257D01*
X571131Y914398D01*
G37*
G36*
G01X572792Y912736D02*
X573176Y912919D01*
X573706Y912388D01*
X573524Y912005D01*
X573383Y911863D01*
X572651Y912595D01*
X572792Y912736D01*
G37*
G36*
G01X575734Y909229D02*
X575350Y909047D01*
X574820Y909577D01*
X575002Y909961D01*
X575144Y910102D01*
X575875Y909371D01*
X575734Y909229D01*
G37*
G36*
G01X574454Y911075D02*
X574838Y911257D01*
X575368Y910726D01*
X575186Y910343D01*
X575045Y910201D01*
X574313Y910933D01*
X574454Y911075D01*
G37*
G36*
G01X581828Y900662D02*
X581428Y900805D01*
Y901555D01*
X581828Y901697D01*
X582028D01*
Y900662D01*
X581828D01*
G37*
G36*
G01X577396Y907567D02*
X577012Y907385D01*
X576482Y907916D01*
X576664Y908299D01*
X576805Y908441D01*
X577537Y907709D01*
X577396Y907567D01*
G37*
G36*
G01X576116Y909413D02*
X576499Y909595D01*
X577030Y909065D01*
X576848Y908681D01*
X576706Y908540D01*
X575974Y909272D01*
X576116Y909413D01*
G37*
G36*
G01X577777Y907751D02*
X578161Y907933D01*
X578691Y907403D01*
X578509Y907019D01*
X578368Y906878D01*
X577636Y907610D01*
X577777Y907751D01*
G37*
G36*
G01X579057Y905906D02*
X578674Y905724D01*
X578143Y906254D01*
X578326Y906638D01*
X578467Y906779D01*
X579199Y906047D01*
X579057Y905906D01*
G37*
G36*
G01X579439Y906090D02*
X579823Y906272D01*
X580353Y905741D01*
X580171Y905358D01*
X580030Y905216D01*
X579298Y905948D01*
X579439Y906090D01*
G37*
G36*
G01X580719Y904244D02*
X580335Y904062D01*
X579805Y904592D01*
X579987Y904976D01*
X580129Y905117D01*
X580860Y904386D01*
X580719Y904244D01*
G37*
G36*
G01X571598Y915063D02*
X571214Y914881D01*
X570684Y915412D01*
X570866Y915795D01*
X571007Y915937D01*
X571739Y915205D01*
X571598Y915063D01*
G37*
G36*
G01X573260Y913402D02*
X572876Y913220D01*
X572346Y913750D01*
X572528Y914133D01*
X572669Y914275D01*
X573401Y913543D01*
X573260Y913402D01*
G37*
G36*
G01X574921Y911740D02*
X574538Y911558D01*
X574007Y912088D01*
X574189Y912472D01*
X574331Y912613D01*
X575063Y911881D01*
X574921Y911740D01*
G37*
G36*
G01X571980Y915247D02*
X572363Y915429D01*
X572894Y914899D01*
X572712Y914515D01*
X572570Y914374D01*
X571838Y915106D01*
X571980Y915247D01*
G37*
G36*
G01X573641Y913585D02*
X574025Y913768D01*
X574555Y913237D01*
X574373Y912854D01*
X574232Y912712D01*
X573500Y913444D01*
X573641Y913585D01*
G37*
G36*
G01X575303Y911924D02*
X575687Y912106D01*
X576217Y911575D01*
X576035Y911192D01*
X575894Y911050D01*
X575162Y911782D01*
X575303Y911924D01*
G37*
G36*
G01X570318Y916909D02*
X570702Y917091D01*
X571232Y916561D01*
X571050Y916177D01*
X570908Y916036D01*
X570177Y916767D01*
X570318Y916909D01*
G37*
G36*
G01X569936Y916725D02*
X569553Y916543D01*
X569022Y917073D01*
X569204Y917457D01*
X569346Y917598D01*
X570078Y916866D01*
X569936Y916725D01*
G37*
G36*
G01X576583Y910078D02*
X576199Y909896D01*
X575669Y910426D01*
X575851Y910810D01*
X575993Y910951D01*
X576724Y910220D01*
X576583Y910078D01*
G37*
G36*
G01X576965Y910262D02*
X577348Y910444D01*
X577879Y909914D01*
X577697Y909530D01*
X577555Y909389D01*
X576823Y910121D01*
X576965Y910262D01*
G37*
G36*
G01X578245Y908416D02*
X577861Y908234D01*
X577331Y908765D01*
X577513Y909148D01*
X577654Y909290D01*
X578386Y908558D01*
X578245Y908416D01*
G37*
G36*
G01X579906Y906755D02*
X579523Y906573D01*
X578992Y907103D01*
X579175Y907487D01*
X579316Y907628D01*
X580048Y906896D01*
X579906Y906755D01*
G37*
G36*
G01X578626Y908600D02*
X579010Y908782D01*
X579540Y908252D01*
X579358Y907868D01*
X579217Y907727D01*
X578485Y908459D01*
X578626Y908600D01*
G37*
G36*
G01X580288Y906939D02*
X580672Y907121D01*
X581202Y906590D01*
X581020Y906207D01*
X580879Y906065D01*
X580147Y906797D01*
X580288Y906939D01*
G37*
G36*
G01X581568Y905093D02*
X581184Y904911D01*
X580654Y905441D01*
X580836Y905825D01*
X580978Y905966D01*
X581709Y905235D01*
X581568Y905093D01*
G37*
G36*
G01X581950Y905277D02*
X582334Y905459D01*
X582864Y904929D01*
X582682Y904545D01*
X582540Y904404D01*
X581808Y905136D01*
X581950Y905277D01*
G37*
G36*
G01X566576Y916689D02*
X566193Y916507D01*
X565663Y917037D01*
X565845Y917421D01*
X565986Y917562D01*
X566718Y916830D01*
X566576Y916689D01*
G37*
G36*
G01X568238Y915027D02*
X567855Y914845D01*
X567324Y915375D01*
X567506Y915759D01*
X567648Y915900D01*
X568380Y915168D01*
X568238Y915027D01*
G37*
G36*
G01X566958Y916873D02*
X567342Y917055D01*
X567872Y916524D01*
X567690Y916141D01*
X567549Y915999D01*
X566817Y916731D01*
X566958Y916873D01*
G37*
G36*
G01X569900Y913365D02*
X569516Y913183D01*
X568986Y913714D01*
X569168Y914097D01*
X569309Y914239D01*
X570041Y913507D01*
X569900Y913365D01*
G37*
G36*
G01X571562Y911704D02*
X571178Y911522D01*
X570648Y912052D01*
X570830Y912435D01*
X570971Y912577D01*
X571703Y911845D01*
X571562Y911704D01*
G37*
G36*
G01X570282Y913549D02*
X570665Y913731D01*
X571196Y913201D01*
X571014Y912817D01*
X570872Y912676D01*
X570140Y913408D01*
X570282Y913549D01*
G37*
G36*
G01X571943Y911887D02*
X572327Y912070D01*
X572857Y911539D01*
X572675Y911156D01*
X572534Y911014D01*
X571802Y911746D01*
X571943Y911887D01*
G37*
G36*
G01X573223Y910042D02*
X572840Y909860D01*
X572309Y910390D01*
X572491Y910774D01*
X572633Y910915D01*
X573365Y910183D01*
X573223Y910042D01*
G37*
G36*
G01X574885Y908380D02*
X574501Y908198D01*
X573971Y908728D01*
X574153Y909112D01*
X574295Y909253D01*
X575026Y908522D01*
X574885Y908380D01*
G37*
G36*
G01X573605Y910226D02*
X573989Y910408D01*
X574519Y909877D01*
X574337Y909494D01*
X574196Y909352D01*
X573464Y910084D01*
X573605Y910226D01*
G37*
G36*
G01X575267Y908564D02*
X575650Y908746D01*
X576181Y908216D01*
X575999Y907832D01*
X575857Y907691D01*
X575125Y908423D01*
X575267Y908564D01*
G37*
G36*
G01X568620Y915211D02*
X569004Y915393D01*
X569534Y914863D01*
X569352Y914479D01*
X569210Y914338D01*
X568479Y915069D01*
X568620Y915211D01*
G37*
G36*
G01X580628Y900662D02*
X580228Y900805D01*
Y901555D01*
X580628Y901697D01*
X580828D01*
Y900662D01*
X580628D01*
G37*
G36*
G01X576547Y906718D02*
X576163Y906536D01*
X575633Y907067D01*
X575815Y907450D01*
X575956Y907592D01*
X576688Y906860D01*
X576547Y906718D01*
G37*
G36*
G01X576928Y906902D02*
X577312Y907084D01*
X577842Y906554D01*
X577660Y906170D01*
X577519Y906029D01*
X576787Y906761D01*
X576928Y906902D01*
G37*
G36*
G01X578208Y905057D02*
X577825Y904875D01*
X577294Y905405D01*
X577477Y905789D01*
X577618Y905930D01*
X578350Y905198D01*
X578208Y905057D01*
G37*
G36*
G01X578590Y905241D02*
X578974Y905423D01*
X579504Y904892D01*
X579322Y904509D01*
X579181Y904367D01*
X578449Y905099D01*
X578590Y905241D01*
G37*
G36*
G01X579870Y903395D02*
X579486Y903213D01*
X578956Y903743D01*
X579138Y904127D01*
X579280Y904268D01*
X580011Y903537D01*
X579870Y903395D01*
G37*
G36*
G01X566578Y913367D02*
X566195Y913185D01*
X565664Y913715D01*
X565846Y914099D01*
X565988Y914240D01*
X566720Y913508D01*
X566578Y913367D01*
G37*
G36*
G01X566960Y913551D02*
X567344Y913733D01*
X567874Y913203D01*
X567692Y912819D01*
X567550Y912678D01*
X566819Y913409D01*
X566960Y913551D01*
G37*
G36*
G01X568240Y911705D02*
X567856Y911523D01*
X567326Y912054D01*
X567508Y912437D01*
X567649Y912579D01*
X568381Y911847D01*
X568240Y911705D01*
G37*
G36*
G01X573225Y906720D02*
X572841Y906538D01*
X572311Y907068D01*
X572493Y907452D01*
X572635Y907593D01*
X573366Y906862D01*
X573225Y906720D01*
G37*
G36*
G01X571945Y908566D02*
X572329Y908748D01*
X572859Y908217D01*
X572677Y907834D01*
X572536Y907692D01*
X571804Y908424D01*
X571945Y908566D01*
G37*
G36*
G01X571563Y908382D02*
X571180Y908200D01*
X570649Y908730D01*
X570831Y909114D01*
X570973Y909255D01*
X571705Y908523D01*
X571563Y908382D01*
G37*
G36*
G01X573607Y906904D02*
X573990Y907086D01*
X574521Y906556D01*
X574339Y906172D01*
X574197Y906031D01*
X573465Y906763D01*
X573607Y906904D01*
G37*
G36*
G01X569902Y910044D02*
X569518Y909862D01*
X568988Y910392D01*
X569170Y910775D01*
X569311Y910917D01*
X570043Y910185D01*
X569902Y910044D01*
G37*
G36*
G01X570283Y910227D02*
X570667Y910410D01*
X571197Y909879D01*
X571015Y909496D01*
X570874Y909354D01*
X570142Y910086D01*
X570283Y910227D01*
G37*
G36*
G01X568622Y911889D02*
X569005Y912071D01*
X569536Y911541D01*
X569354Y911157D01*
X569212Y911016D01*
X568480Y911748D01*
X568622Y911889D01*
G37*
G36*
G01X574887Y905058D02*
X574503Y904876D01*
X573973Y905407D01*
X574155Y905790D01*
X574296Y905932D01*
X575028Y905200D01*
X574887Y905058D01*
G37*
G36*
G01X575268Y905242D02*
X575652Y905424D01*
X576182Y904894D01*
X576000Y904510D01*
X575859Y904369D01*
X575127Y905101D01*
X575268Y905242D01*
G37*
G36*
G01X576548Y903397D02*
X576165Y903215D01*
X575634Y903745D01*
X575817Y904129D01*
X575958Y904270D01*
X576690Y903538D01*
X576548Y903397D01*
G37*
G36*
G01X576930Y903581D02*
X577314Y903763D01*
X577844Y903232D01*
X577662Y902849D01*
X577521Y902707D01*
X576789Y903439D01*
X576930Y903581D01*
G37*
G36*
G01X566924Y910191D02*
X567307Y910373D01*
X567838Y909843D01*
X567656Y909459D01*
X567514Y909318D01*
X566782Y910050D01*
X566924Y910191D01*
G37*
G36*
G01X568204Y908346D02*
X567820Y908164D01*
X567290Y908694D01*
X567472Y909077D01*
X567613Y909219D01*
X568345Y908487D01*
X568204Y908346D01*
G37*
G36*
G01X575232Y901883D02*
X575616Y902065D01*
X576146Y901534D01*
X575964Y901151D01*
X575823Y901009D01*
X575091Y901741D01*
X575232Y901883D01*
G37*
G36*
G01X569865Y906684D02*
X569482Y906502D01*
X568951Y907032D01*
X569133Y907416D01*
X569275Y907557D01*
X570007Y906825D01*
X569865Y906684D01*
G37*
G36*
G01X570247Y906868D02*
X570631Y907050D01*
X571161Y906519D01*
X570979Y906136D01*
X570838Y905994D01*
X570106Y906726D01*
X570247Y906868D01*
G37*
G36*
G01X568585Y908529D02*
X568969Y908712D01*
X569499Y908181D01*
X569317Y907798D01*
X569176Y907656D01*
X568444Y908388D01*
X568585Y908529D01*
G37*
G36*
G01X571527Y905022D02*
X571143Y904840D01*
X570613Y905370D01*
X570795Y905754D01*
X570937Y905895D01*
X571668Y905164D01*
X571527Y905022D01*
G37*
G36*
G01X571909Y905206D02*
X572292Y905388D01*
X572823Y904858D01*
X572641Y904474D01*
X572499Y904333D01*
X571767Y905065D01*
X571909Y905206D01*
G37*
G36*
G01X573189Y903360D02*
X572805Y903178D01*
X572275Y903709D01*
X572457Y904092D01*
X572598Y904234D01*
X573330Y903502D01*
X573189Y903360D01*
G37*
G36*
G01X573570Y903544D02*
X573954Y903726D01*
X574484Y903196D01*
X574302Y902812D01*
X574161Y902671D01*
X573429Y903403D01*
X573570Y903544D01*
G37*
G36*
G01X574850Y901699D02*
X574467Y901517D01*
X573936Y902047D01*
X574119Y902431D01*
X574260Y902572D01*
X574992Y901840D01*
X574850Y901699D01*
G37*
G36*
G01X566111Y912702D02*
X566495Y912884D01*
X567025Y912354D01*
X566843Y911970D01*
X566701Y911829D01*
X565970Y912560D01*
X566111Y912702D01*
G37*
G36*
G01X567391Y910856D02*
X567007Y910674D01*
X566477Y911205D01*
X566659Y911588D01*
X566800Y911730D01*
X567532Y910998D01*
X567391Y910856D01*
G37*
G36*
G01X569053Y909195D02*
X568669Y909013D01*
X568139Y909543D01*
X568321Y909926D01*
X568462Y910068D01*
X569194Y909336D01*
X569053Y909195D01*
G37*
G36*
G01X567773Y911040D02*
X568156Y911222D01*
X568687Y910692D01*
X568505Y910308D01*
X568363Y910167D01*
X567631Y910899D01*
X567773Y911040D01*
G37*
G36*
G01X572376Y905871D02*
X571992Y905689D01*
X571462Y906219D01*
X571644Y906603D01*
X571786Y906744D01*
X572517Y906013D01*
X572376Y905871D01*
G37*
G36*
G01X571096Y907717D02*
X571480Y907899D01*
X572010Y907368D01*
X571828Y906985D01*
X571687Y906843D01*
X570955Y907575D01*
X571096Y907717D01*
G37*
G36*
G01X570714Y907533D02*
X570331Y907351D01*
X569800Y907881D01*
X569982Y908265D01*
X570124Y908406D01*
X570856Y907674D01*
X570714Y907533D01*
G37*
G36*
G01X569434Y909378D02*
X569818Y909561D01*
X570348Y909030D01*
X570166Y908647D01*
X570025Y908505D01*
X569293Y909237D01*
X569434Y909378D01*
G37*
G36*
G01X572758Y906055D02*
X573141Y906237D01*
X573672Y905707D01*
X573490Y905323D01*
X573348Y905182D01*
X572616Y905914D01*
X572758Y906055D01*
G37*
G36*
G01X574038Y904209D02*
X573654Y904027D01*
X573124Y904558D01*
X573306Y904941D01*
X573447Y905083D01*
X574179Y904351D01*
X574038Y904209D01*
G37*
G36*
G01X575699Y902548D02*
X575316Y902366D01*
X574785Y902896D01*
X574968Y903280D01*
X575109Y903421D01*
X575841Y902689D01*
X575699Y902548D01*
G37*
G36*
G01X574419Y904393D02*
X574803Y904575D01*
X575333Y904045D01*
X575151Y903661D01*
X575010Y903520D01*
X574278Y904252D01*
X574419Y904393D01*
G37*
G36*
G01X576081Y902732D02*
X576465Y902914D01*
X576995Y902383D01*
X576813Y902000D01*
X576672Y901858D01*
X575940Y902590D01*
X576081Y902732D01*
G37*
G36*
G01X566075Y909342D02*
X566458Y909524D01*
X566989Y908994D01*
X566807Y908610D01*
X566665Y908469D01*
X565933Y909201D01*
X566075Y909342D01*
G37*
G36*
G01X567355Y907497D02*
X566971Y907315D01*
X566441Y907845D01*
X566623Y908228D01*
X566764Y908370D01*
X567496Y907638D01*
X567355Y907497D01*
G37*
G36*
G01X569016Y905835D02*
X568633Y905653D01*
X568102Y906183D01*
X568284Y906567D01*
X568426Y906708D01*
X569158Y905976D01*
X569016Y905835D01*
G37*
G36*
G01X567736Y907680D02*
X568120Y907863D01*
X568650Y907332D01*
X568468Y906949D01*
X568327Y906807D01*
X567595Y907539D01*
X567736Y907680D01*
G37*
G36*
G01X574001Y900850D02*
X573618Y900668D01*
X573087Y901198D01*
X573270Y901582D01*
X573411Y901723D01*
X574143Y900991D01*
X574001Y900850D01*
G37*
G36*
G01X570678Y904173D02*
X570294Y903991D01*
X569764Y904521D01*
X569946Y904905D01*
X570088Y905046D01*
X570819Y904315D01*
X570678Y904173D01*
G37*
G36*
G01X569398Y906019D02*
X569782Y906201D01*
X570312Y905670D01*
X570130Y905287D01*
X569989Y905145D01*
X569257Y905877D01*
X569398Y906019D01*
G37*
G36*
G01X572340Y902511D02*
X571956Y902329D01*
X571426Y902860D01*
X571608Y903243D01*
X571749Y903385D01*
X572481Y902653D01*
X572340Y902511D01*
G37*
G36*
G01X571060Y904357D02*
X571443Y904539D01*
X571974Y904009D01*
X571792Y903625D01*
X571650Y903484D01*
X570918Y904216D01*
X571060Y904357D01*
G37*
G36*
G01X572721Y902695D02*
X573105Y902877D01*
X573635Y902347D01*
X573453Y901963D01*
X573312Y901822D01*
X572580Y902554D01*
X572721Y902695D01*
G37*
G36*
G01X582517Y916034D02*
X582133Y915852D01*
X581603Y916382D01*
X581785Y916766D01*
X581926Y916907D01*
X582658Y916175D01*
X582517Y916034D01*
G37*
G36*
G01X577170Y933753D02*
X577554Y933936D01*
X578084Y933405D01*
X577902Y933022D01*
X577761Y932880D01*
X577029Y933612D01*
X577170Y933753D01*
G37*
G36*
G01X578450Y931908D02*
X578067Y931726D01*
X577536Y932256D01*
X577718Y932640D01*
X577860Y932781D01*
X578592Y932049D01*
X578450Y931908D01*
G37*
G36*
G01X575091Y931872D02*
X574707Y931690D01*
X574177Y932220D01*
X574359Y932603D01*
X574500Y932745D01*
X575232Y932013D01*
X575091Y931872D01*
G37*
G36*
G01X573811Y933717D02*
X574194Y933899D01*
X574725Y933369D01*
X574543Y932985D01*
X574401Y932844D01*
X573669Y933576D01*
X573811Y933717D01*
G37*
G36*
G01X576752Y930210D02*
X576369Y930028D01*
X575838Y930558D01*
X576020Y930942D01*
X576162Y931083D01*
X576894Y930351D01*
X576752Y930210D01*
G37*
G36*
G01X575472Y932055D02*
X575856Y932238D01*
X576386Y931707D01*
X576204Y931324D01*
X576063Y931182D01*
X575331Y931914D01*
X575472Y932055D01*
G37*
G36*
G01X577134Y930394D02*
X577518Y930576D01*
X578048Y930046D01*
X577866Y929662D01*
X577725Y929520D01*
X576993Y930252D01*
X577134Y930394D01*
G37*
G36*
G01X575940Y932721D02*
X575556Y932539D01*
X575026Y933069D01*
X575208Y933452D01*
X575349Y933594D01*
X576081Y932862D01*
X575940Y932721D01*
G37*
G36*
G01X577602Y931059D02*
X577218Y930877D01*
X576688Y931407D01*
X576870Y931790D01*
X577011Y931932D01*
X577743Y931200D01*
X577602Y931059D01*
G37*
G36*
G01X576322Y932904D02*
X576705Y933086D01*
X577236Y932556D01*
X577054Y932172D01*
X576912Y932031D01*
X576180Y932763D01*
X576322Y932904D01*
G37*
G36*
G01X577984Y931242D02*
X578367Y931424D01*
X578898Y930894D01*
X578716Y930510D01*
X578574Y930369D01*
X577842Y931101D01*
X577984Y931242D01*
G37*
G36*
G01X572580Y932684D02*
X572196Y932502D01*
X571666Y933033D01*
X571848Y933416D01*
X571989Y933558D01*
X572721Y932826D01*
X572580Y932684D01*
G37*
G36*
G01X574242Y931023D02*
X573858Y930841D01*
X573328Y931371D01*
X573510Y931754D01*
X573651Y931896D01*
X574383Y931164D01*
X574242Y931023D01*
G37*
G36*
G01X575903Y929361D02*
X575520Y929179D01*
X574989Y929709D01*
X575171Y930093D01*
X575313Y930234D01*
X576045Y929502D01*
X575903Y929361D01*
G37*
G36*
G01X574623Y931206D02*
X575007Y931389D01*
X575537Y930858D01*
X575355Y930475D01*
X575214Y930333D01*
X574482Y931065D01*
X574623Y931206D01*
G37*
G36*
G01X572962Y932868D02*
X573345Y933050D01*
X573876Y932520D01*
X573694Y932136D01*
X573552Y931995D01*
X572820Y932727D01*
X572962Y932868D01*
G37*
G36*
G01X576285Y929545D02*
X576669Y929727D01*
X577199Y929197D01*
X577017Y928813D01*
X576876Y928671D01*
X576144Y929403D01*
X576285Y929545D01*
G37*
G36*
G01X568412Y931840D02*
X568028Y931657D01*
X567498Y932188D01*
X567680Y932571D01*
X567821Y932713D01*
X568553Y931981D01*
X568412Y931840D01*
G37*
G36*
G01X567132Y933685D02*
X567515Y933867D01*
X568046Y933337D01*
X567864Y932953D01*
X567722Y932812D01*
X566990Y933544D01*
X567132Y933685D01*
G37*
G36*
G01X573779Y927038D02*
X574162Y927220D01*
X574693Y926690D01*
X574510Y926306D01*
X574369Y926165D01*
X573637Y926897D01*
X573779Y927038D01*
G37*
G36*
G01X575058Y925193D02*
X574675Y925011D01*
X574145Y925541D01*
X574327Y925925D01*
X574468Y926066D01*
X575200Y925334D01*
X575058Y925193D01*
G37*
G36*
G01X568793Y932023D02*
X569177Y932205D01*
X569707Y931675D01*
X569525Y931291D01*
X569384Y931150D01*
X568652Y931882D01*
X568793Y932023D01*
G37*
G36*
G01X570073Y930178D02*
X569690Y929996D01*
X569159Y930526D01*
X569341Y930910D01*
X569483Y931051D01*
X570215Y930319D01*
X570073Y930178D01*
G37*
G36*
G01X573397Y926854D02*
X573013Y926672D01*
X572483Y927203D01*
X572665Y927586D01*
X572806Y927728D01*
X573538Y926996D01*
X573397Y926854D01*
G37*
G36*
G01X572117Y928700D02*
X572500Y928882D01*
X573031Y928352D01*
X572849Y927968D01*
X572707Y927827D01*
X571975Y928559D01*
X572117Y928700D01*
G37*
G36*
G01X571735Y928516D02*
X571351Y928334D01*
X570821Y928864D01*
X571003Y929248D01*
X571145Y929389D01*
X571876Y928658D01*
X571735Y928516D01*
G37*
G36*
G01X570455Y930362D02*
X570839Y930544D01*
X571369Y930013D01*
X571187Y929630D01*
X571046Y929488D01*
X570314Y930220D01*
X570455Y930362D01*
G37*
G36*
G01X576720Y923531D02*
X576337Y923349D01*
X575806Y923879D01*
X575988Y924263D01*
X576130Y924404D01*
X576862Y923672D01*
X576720Y923531D01*
G37*
G36*
G01X577102Y923715D02*
X577486Y923897D01*
X578016Y923367D01*
X577834Y922983D01*
X577692Y922842D01*
X576961Y923573D01*
X577102Y923715D01*
G37*
G36*
G01X575440Y925377D02*
X575824Y925559D01*
X576354Y925028D01*
X576172Y924645D01*
X576031Y924503D01*
X575299Y925235D01*
X575440Y925377D01*
G37*
G36*
G01X578382Y921869D02*
X577998Y921687D01*
X577468Y922218D01*
X577650Y922601D01*
X577791Y922743D01*
X578523Y922011D01*
X578382Y921869D01*
G37*
G36*
G01X580044Y920208D02*
X579660Y920026D01*
X579130Y920556D01*
X579312Y920939D01*
X579453Y921081D01*
X580185Y920349D01*
X580044Y920208D01*
G37*
G36*
G01X578764Y922053D02*
X579147Y922235D01*
X579678Y921705D01*
X579496Y921321D01*
X579354Y921180D01*
X578622Y921912D01*
X578764Y922053D01*
G37*
G36*
G01X581705Y918546D02*
X581322Y918364D01*
X580791Y918894D01*
X580973Y919278D01*
X581115Y919419D01*
X581847Y918687D01*
X581705Y918546D01*
G37*
G36*
G01X580425Y920391D02*
X580809Y920574D01*
X581339Y920043D01*
X581157Y919660D01*
X581016Y919518D01*
X580284Y920250D01*
X580425Y920391D01*
G37*
G36*
G01X566711Y930139D02*
X566327Y929956D01*
X565797Y930487D01*
X565979Y930870D01*
X566120Y931012D01*
X566852Y930280D01*
X566711Y930139D01*
G37*
G36*
G01X567092Y930322D02*
X567476Y930504D01*
X568006Y929974D01*
X567824Y929591D01*
X567683Y929449D01*
X566951Y930181D01*
X567092Y930322D01*
G37*
G36*
G01X568372Y928477D02*
X567989Y928295D01*
X567458Y928825D01*
X567640Y929209D01*
X567782Y929350D01*
X568514Y928618D01*
X568372Y928477D01*
G37*
G36*
G01X573357Y923492D02*
X572974Y923310D01*
X572444Y923840D01*
X572626Y924224D01*
X572767Y924365D01*
X573499Y923633D01*
X573357Y923492D01*
G37*
G36*
G01X575019Y921830D02*
X574636Y921648D01*
X574105Y922178D01*
X574287Y922562D01*
X574429Y922703D01*
X575161Y921971D01*
X575019Y921830D01*
G37*
G36*
G01X573739Y923676D02*
X574123Y923858D01*
X574653Y923327D01*
X574471Y922944D01*
X574330Y922802D01*
X573598Y923534D01*
X573739Y923676D01*
G37*
G36*
G01X572078Y925337D02*
X572461Y925519D01*
X572992Y924989D01*
X572809Y924605D01*
X572668Y924464D01*
X571936Y925196D01*
X572078Y925337D01*
G37*
G36*
G01X571696Y925153D02*
X571312Y924971D01*
X570782Y925502D01*
X570964Y925885D01*
X571105Y926027D01*
X571837Y925295D01*
X571696Y925153D01*
G37*
G36*
G01X570034Y926815D02*
X569651Y926633D01*
X569120Y927163D01*
X569302Y927547D01*
X569444Y927688D01*
X570176Y926957D01*
X570034Y926815D01*
G37*
G36*
G01X568754Y928661D02*
X569138Y928843D01*
X569668Y928312D01*
X569486Y927929D01*
X569345Y927787D01*
X568613Y928519D01*
X568754Y928661D01*
G37*
G36*
G01X570416Y926999D02*
X570799Y927181D01*
X571330Y926651D01*
X571148Y926267D01*
X571006Y926126D01*
X570274Y926857D01*
X570416Y926999D01*
G37*
G36*
G01X578724Y918690D02*
X579108Y918873D01*
X579638Y918342D01*
X579456Y917959D01*
X579315Y917817D01*
X578583Y918549D01*
X578724Y918690D01*
G37*
G36*
G01X576681Y920168D02*
X576297Y919986D01*
X575767Y920516D01*
X575949Y920900D01*
X576090Y921042D01*
X576822Y920310D01*
X576681Y920168D01*
G37*
G36*
G01X575401Y922014D02*
X575785Y922196D01*
X576315Y921666D01*
X576133Y921282D01*
X575991Y921141D01*
X575260Y921872D01*
X575401Y922014D01*
G37*
G36*
G01X577063Y920352D02*
X577446Y920534D01*
X577977Y920004D01*
X577795Y919620D01*
X577653Y919479D01*
X576921Y920211D01*
X577063Y920352D01*
G37*
G36*
G01X578343Y918507D02*
X577959Y918325D01*
X577429Y918855D01*
X577611Y919238D01*
X577752Y919380D01*
X578484Y918648D01*
X578343Y918507D01*
G37*
G36*
G01X566182Y922743D02*
X566565Y922925D01*
X567096Y922395D01*
X566914Y922011D01*
X566772Y921870D01*
X566040Y922602D01*
X566182Y922743D01*
G37*
G36*
G01X567844Y921081D02*
X568227Y921263D01*
X568758Y920733D01*
X568575Y920349D01*
X568434Y920208D01*
X567702Y920940D01*
X567844Y921081D01*
G37*
G36*
G01X567462Y920897D02*
X567078Y920715D01*
X566548Y921246D01*
X566730Y921629D01*
X566871Y921771D01*
X567603Y921039D01*
X567462Y920897D01*
G37*
G36*
G01X569123Y919236D02*
X568740Y919054D01*
X568210Y919584D01*
X568392Y919968D01*
X568533Y920109D01*
X569265Y919377D01*
X569123Y919236D01*
G37*
G36*
G01X570785Y917574D02*
X570402Y917392D01*
X569871Y917922D01*
X570053Y918306D01*
X570195Y918447D01*
X570927Y917715D01*
X570785Y917574D01*
G37*
G36*
G01X571167Y917758D02*
X571551Y917940D01*
X572081Y917410D01*
X571899Y917026D01*
X571757Y916885D01*
X571026Y917616D01*
X571167Y917758D01*
G37*
G36*
G01X569505Y919420D02*
X569889Y919602D01*
X570419Y919071D01*
X570237Y918688D01*
X570096Y918546D01*
X569364Y919278D01*
X569505Y919420D01*
G37*
G36*
G01X567807Y917722D02*
X568191Y917904D01*
X568721Y917373D01*
X568539Y916990D01*
X568398Y916848D01*
X567666Y917580D01*
X567807Y917722D01*
G37*
G36*
G01X567425Y917538D02*
X567042Y917356D01*
X566512Y917886D01*
X566694Y918270D01*
X566835Y918411D01*
X567567Y917679D01*
X567425Y917538D01*
G37*
G36*
G01X566146Y919383D02*
X566529Y919565D01*
X567060Y919035D01*
X566877Y918651D01*
X566736Y918510D01*
X566004Y919242D01*
X566146Y919383D01*
G37*
G36*
G01X566613Y920048D02*
X566229Y919866D01*
X565699Y920397D01*
X565881Y920780D01*
X566022Y920922D01*
X566754Y920190D01*
X566613Y920048D01*
G37*
G36*
G01X566995Y920232D02*
X567378Y920414D01*
X567909Y919884D01*
X567726Y919500D01*
X567585Y919359D01*
X566853Y920091D01*
X566995Y920232D01*
G37*
G36*
G01X568274Y918387D02*
X567891Y918205D01*
X567361Y918735D01*
X567543Y919119D01*
X567684Y919260D01*
X568416Y918528D01*
X568274Y918387D01*
G37*
G36*
G01X568656Y918571D02*
X569040Y918753D01*
X569570Y918222D01*
X569388Y917839D01*
X569247Y917697D01*
X568515Y918429D01*
X568656Y918571D01*
G37*
G36*
G01X571305Y931211D02*
X571688Y931393D01*
X572219Y930863D01*
X572037Y930479D01*
X571895Y930338D01*
X571163Y931070D01*
X571305Y931211D01*
G37*
G36*
G01X570923Y931027D02*
X570539Y930845D01*
X570009Y931376D01*
X570191Y931759D01*
X570332Y931901D01*
X571064Y931169D01*
X570923Y931027D01*
G37*
G36*
G01X569643Y932873D02*
X570027Y933055D01*
X570557Y932525D01*
X570375Y932141D01*
X570233Y932000D01*
X569502Y932731D01*
X569643Y932873D01*
G37*
G36*
G01X574628Y927888D02*
X575012Y928070D01*
X575542Y927540D01*
X575360Y927156D01*
X575219Y927014D01*
X574487Y927746D01*
X574628Y927888D01*
G37*
G36*
G01X574246Y927704D02*
X573863Y927522D01*
X573332Y928052D01*
X573514Y928436D01*
X573656Y928577D01*
X574388Y927845D01*
X574246Y927704D01*
G37*
G36*
G01X572966Y929549D02*
X573350Y929732D01*
X573880Y929201D01*
X573698Y928818D01*
X573557Y928676D01*
X572825Y929408D01*
X572966Y929549D01*
G37*
G36*
G01X572585Y929366D02*
X572201Y929184D01*
X571671Y929714D01*
X571853Y930097D01*
X571994Y930239D01*
X572726Y929507D01*
X572585Y929366D01*
G37*
G36*
G01X575908Y926042D02*
X575524Y925860D01*
X574994Y926390D01*
X575176Y926774D01*
X575318Y926915D01*
X576049Y926184D01*
X575908Y926042D01*
G37*
G36*
G01X569261Y932689D02*
X568878Y932507D01*
X568347Y933037D01*
X568529Y933421D01*
X568671Y933562D01*
X569403Y932830D01*
X569261Y932689D01*
G37*
G36*
G01X576290Y926226D02*
X576673Y926408D01*
X577204Y925878D01*
X577022Y925494D01*
X576880Y925353D01*
X576148Y926085D01*
X576290Y926226D01*
G37*
G36*
G01X577570Y924381D02*
X577186Y924198D01*
X576656Y924729D01*
X576838Y925112D01*
X576979Y925254D01*
X577711Y924522D01*
X577570Y924381D01*
G37*
G36*
G01X577951Y924564D02*
X578335Y924746D01*
X578865Y924216D01*
X578683Y923832D01*
X578542Y923691D01*
X577810Y924423D01*
X577951Y924564D01*
G37*
G36*
G01X579613Y922903D02*
X579997Y923085D01*
X580527Y922554D01*
X580345Y922171D01*
X580204Y922029D01*
X579472Y922761D01*
X579613Y922903D01*
G37*
G36*
G01X581275Y921241D02*
X581659Y921423D01*
X582189Y920893D01*
X582007Y920509D01*
X581865Y920368D01*
X581133Y921100D01*
X581275Y921241D01*
G37*
G36*
G01X579231Y922719D02*
X578848Y922537D01*
X578317Y923067D01*
X578500Y923451D01*
X578641Y923592D01*
X579373Y922860D01*
X579231Y922719D01*
G37*
G36*
G01X580893Y921057D02*
X580509Y920875D01*
X579979Y921405D01*
X580161Y921789D01*
X580303Y921930D01*
X581034Y921199D01*
X580893Y921057D01*
G37*
G36*
G01X582555Y919395D02*
X582171Y919213D01*
X581641Y919744D01*
X581823Y920127D01*
X581964Y920269D01*
X582696Y919537D01*
X582555Y919395D01*
G37*
G36*
G01X566280Y932833D02*
X566664Y933016D01*
X567194Y932485D01*
X567012Y932102D01*
X566871Y931960D01*
X566139Y932692D01*
X566280Y932833D01*
G37*
G36*
G01X567560Y930988D02*
X567177Y930806D01*
X566646Y931336D01*
X566828Y931720D01*
X566970Y931861D01*
X567702Y931129D01*
X567560Y930988D01*
G37*
G36*
G01X567942Y931172D02*
X568326Y931354D01*
X568856Y930824D01*
X568674Y930440D01*
X568532Y930299D01*
X567801Y931030D01*
X567942Y931172D01*
G37*
G36*
G01X570884Y927665D02*
X570500Y927483D01*
X569970Y928013D01*
X570152Y928397D01*
X570293Y928538D01*
X571025Y927806D01*
X570884Y927665D01*
G37*
G36*
G01X571266Y927849D02*
X571649Y928031D01*
X572180Y927501D01*
X571998Y927117D01*
X571856Y926976D01*
X571124Y927707D01*
X571266Y927849D01*
G37*
G36*
G01X569604Y929510D02*
X569987Y929692D01*
X570518Y929162D01*
X570336Y928778D01*
X570194Y928637D01*
X569462Y929369D01*
X569604Y929510D01*
G37*
G36*
G01X572546Y926003D02*
X572162Y925821D01*
X571632Y926352D01*
X571814Y926735D01*
X571955Y926877D01*
X572687Y926145D01*
X572546Y926003D01*
G37*
G36*
G01X572928Y926187D02*
X573311Y926369D01*
X573842Y925839D01*
X573659Y925455D01*
X573518Y925314D01*
X572786Y926046D01*
X572928Y926187D01*
G37*
G36*
G01X574208Y924342D02*
X573824Y924160D01*
X573294Y924690D01*
X573476Y925074D01*
X573617Y925215D01*
X574349Y924483D01*
X574208Y924342D01*
G37*
G36*
G01X575869Y922680D02*
X575486Y922498D01*
X574955Y923028D01*
X575137Y923412D01*
X575279Y923553D01*
X576011Y922822D01*
X575869Y922680D01*
G37*
G36*
G01X574589Y924526D02*
X574973Y924708D01*
X575503Y924177D01*
X575321Y923794D01*
X575180Y923652D01*
X574448Y924384D01*
X574589Y924526D01*
G37*
G36*
G01X569222Y929326D02*
X568838Y929144D01*
X568308Y929675D01*
X568490Y930058D01*
X568632Y930200D01*
X569363Y929468D01*
X569222Y929326D01*
G37*
G36*
G01X580855Y917696D02*
X580471Y917513D01*
X579941Y918044D01*
X580123Y918427D01*
X580264Y918569D01*
X580996Y917837D01*
X580855Y917696D01*
G37*
G36*
G01X581237Y917879D02*
X581620Y918061D01*
X582151Y917531D01*
X581969Y917148D01*
X581827Y917006D01*
X581095Y917738D01*
X581237Y917879D01*
G37*
G36*
G01X577531Y921019D02*
X577148Y920837D01*
X576617Y921367D01*
X576799Y921750D01*
X576941Y921892D01*
X577673Y921160D01*
X577531Y921019D01*
G37*
G36*
G01X576251Y922864D02*
X576635Y923046D01*
X577165Y922516D01*
X576983Y922132D01*
X576842Y921991D01*
X576110Y922723D01*
X576251Y922864D01*
G37*
G36*
G01X577913Y921203D02*
X578297Y921385D01*
X578827Y920854D01*
X578645Y920471D01*
X578504Y920329D01*
X577772Y921061D01*
X577913Y921203D01*
G37*
G36*
G01X579193Y919357D02*
X578809Y919175D01*
X578279Y919705D01*
X578461Y920089D01*
X578603Y920230D01*
X579334Y919499D01*
X579193Y919357D01*
G37*
G36*
G01X579575Y919541D02*
X579959Y919723D01*
X580489Y919193D01*
X580307Y918809D01*
X580165Y918668D01*
X579433Y919400D01*
X579575Y919541D01*
G37*
G36*
G01X566818Y943540D02*
X566435Y943358D01*
X565904Y943888D01*
X566086Y944272D01*
X566228Y944413D01*
X566960Y943681D01*
X566818Y943540D01*
G37*
G36*
G01X567200Y943724D02*
X567584Y943906D01*
X568114Y943375D01*
X567932Y942992D01*
X567791Y942850D01*
X567059Y943582D01*
X567200Y943724D01*
G37*
G36*
G01X568480Y941878D02*
X568096Y941696D01*
X567566Y942226D01*
X567748Y942610D01*
X567890Y942751D01*
X568621Y942020D01*
X568480Y941878D01*
G37*
G36*
G01X568862Y942062D02*
X569245Y942244D01*
X569776Y941714D01*
X569594Y941330D01*
X569452Y941189D01*
X568720Y941921D01*
X568862Y942062D01*
G37*
G36*
G01X570524Y940400D02*
X570907Y940582D01*
X571438Y940052D01*
X571255Y939668D01*
X571114Y939527D01*
X570382Y940259D01*
X570524Y940400D01*
G37*
G36*
G01X570142Y940216D02*
X569758Y940034D01*
X569228Y940565D01*
X569410Y940948D01*
X569551Y941090D01*
X570283Y940358D01*
X570142Y940216D01*
G37*
G36*
G01X572185Y938739D02*
X572569Y938921D01*
X573099Y938390D01*
X572917Y938007D01*
X572776Y937865D01*
X572044Y938597D01*
X572185Y938739D01*
G37*
G36*
G01X571803Y938555D02*
X571420Y938373D01*
X570890Y938903D01*
X571072Y939287D01*
X571213Y939428D01*
X571945Y938696D01*
X571803Y938555D01*
G37*
G36*
G01X573465Y936893D02*
X573082Y936711D01*
X572551Y937241D01*
X572733Y937625D01*
X572875Y937766D01*
X573607Y937034D01*
X573465Y936893D01*
G37*
G36*
G01X573847Y937077D02*
X574231Y937259D01*
X574761Y936729D01*
X574579Y936345D01*
X574437Y936204D01*
X573706Y936935D01*
X573847Y937077D01*
G37*
G36*
G01X575127Y935231D02*
X574743Y935049D01*
X574213Y935580D01*
X574395Y935963D01*
X574536Y936105D01*
X575268Y935373D01*
X575127Y935231D01*
G37*
G36*
G01X576789Y933570D02*
X576405Y933388D01*
X575875Y933918D01*
X576057Y934301D01*
X576198Y934443D01*
X576930Y933711D01*
X576789Y933570D01*
G37*
G36*
G01X575509Y935415D02*
X575892Y935597D01*
X576423Y935067D01*
X576241Y934683D01*
X576099Y934542D01*
X575367Y935274D01*
X575509Y935415D01*
G37*
G36*
G01X566782Y940180D02*
X566398Y939998D01*
X565868Y940528D01*
X566050Y940912D01*
X566192Y941053D01*
X566923Y940322D01*
X566782Y940180D01*
G37*
G36*
G01X567164Y940364D02*
X567547Y940546D01*
X568078Y940016D01*
X567896Y939632D01*
X567754Y939491D01*
X567022Y940223D01*
X567164Y940364D01*
G37*
G36*
G01X568444Y938518D02*
X568060Y938336D01*
X567530Y938867D01*
X567712Y939250D01*
X567853Y939392D01*
X568585Y938660D01*
X568444Y938518D01*
G37*
G36*
G01X573429Y933533D02*
X573045Y933351D01*
X572515Y933882D01*
X572697Y934265D01*
X572838Y934407D01*
X573570Y933675D01*
X573429Y933533D01*
G37*
G36*
G01X572149Y935379D02*
X572533Y935561D01*
X573063Y935031D01*
X572881Y934647D01*
X572739Y934506D01*
X572008Y935237D01*
X572149Y935379D01*
G37*
G36*
G01X571767Y935195D02*
X571384Y935013D01*
X570853Y935543D01*
X571035Y935927D01*
X571177Y936068D01*
X571909Y935336D01*
X571767Y935195D01*
G37*
G36*
G01X568826Y938702D02*
X569209Y938884D01*
X569740Y938354D01*
X569557Y937970D01*
X569416Y937829D01*
X568684Y938561D01*
X568826Y938702D01*
G37*
G36*
G01X570105Y936857D02*
X569722Y936675D01*
X569192Y937205D01*
X569374Y937589D01*
X569515Y937730D01*
X570247Y936998D01*
X570105Y936857D01*
G37*
G36*
G01X570487Y937041D02*
X570871Y937223D01*
X571401Y936692D01*
X571219Y936309D01*
X571078Y936167D01*
X570346Y936899D01*
X570487Y937041D01*
G37*
G36*
G01X566351Y942875D02*
X566735Y943057D01*
X567265Y942526D01*
X567083Y942143D01*
X566942Y942001D01*
X566210Y942733D01*
X566351Y942875D01*
G37*
G36*
G01X567631Y941029D02*
X567247Y940847D01*
X566717Y941377D01*
X566899Y941761D01*
X567041Y941902D01*
X567772Y941171D01*
X567631Y941029D01*
G37*
G36*
G01X568013Y941213D02*
X568396Y941395D01*
X568927Y940865D01*
X568745Y940481D01*
X568603Y940340D01*
X567871Y941072D01*
X568013Y941213D01*
G37*
G36*
G01X574660Y934566D02*
X575043Y934748D01*
X575574Y934218D01*
X575392Y933834D01*
X575250Y933693D01*
X574518Y934425D01*
X574660Y934566D01*
G37*
G36*
G01X574278Y934382D02*
X573894Y934200D01*
X573364Y934731D01*
X573546Y935114D01*
X573687Y935256D01*
X574419Y934524D01*
X574278Y934382D01*
G37*
G36*
G01X572616Y936044D02*
X572233Y935862D01*
X571702Y936392D01*
X571884Y936776D01*
X572026Y936917D01*
X572758Y936185D01*
X572616Y936044D01*
G37*
G36*
G01X570954Y937706D02*
X570571Y937524D01*
X570041Y938054D01*
X570223Y938438D01*
X570364Y938579D01*
X571096Y937847D01*
X570954Y937706D01*
G37*
G36*
G01X571336Y937890D02*
X571720Y938072D01*
X572250Y937541D01*
X572068Y937158D01*
X571927Y937016D01*
X571195Y937748D01*
X571336Y937890D01*
G37*
G36*
G01X569675Y939551D02*
X570058Y939733D01*
X570589Y939203D01*
X570406Y938819D01*
X570265Y938678D01*
X569533Y939410D01*
X569675Y939551D01*
G37*
G36*
G01X572998Y936228D02*
X573382Y936410D01*
X573912Y935880D01*
X573730Y935496D01*
X573588Y935355D01*
X572857Y936086D01*
X572998Y936228D01*
G37*
G36*
G01X569293Y939367D02*
X568909Y939185D01*
X568379Y939716D01*
X568561Y940099D01*
X568702Y940241D01*
X569434Y939509D01*
X569293Y939367D01*
G37*
G36*
G01X566315Y939515D02*
X566698Y939697D01*
X567229Y939167D01*
X567047Y938783D01*
X566905Y938642D01*
X566173Y939374D01*
X566315Y939515D01*
G37*
G36*
G01X567595Y937669D02*
X567211Y937487D01*
X566681Y938018D01*
X566863Y938401D01*
X567004Y938543D01*
X567736Y937811D01*
X567595Y937669D01*
G37*
G36*
G01X567977Y937853D02*
X568360Y938035D01*
X568891Y937505D01*
X568708Y937121D01*
X568567Y936980D01*
X567835Y937712D01*
X567977Y937853D01*
G37*
G36*
G01X571300Y934530D02*
X571684Y934712D01*
X572214Y934182D01*
X572032Y933798D01*
X571890Y933657D01*
X571159Y934388D01*
X571300Y934530D01*
G37*
G36*
G01X570918Y934346D02*
X570535Y934164D01*
X570004Y934694D01*
X570186Y935078D01*
X570328Y935219D01*
X571060Y934487D01*
X570918Y934346D01*
G37*
G36*
G01X569638Y936192D02*
X570022Y936374D01*
X570552Y935843D01*
X570370Y935460D01*
X570229Y935318D01*
X569497Y936050D01*
X569638Y936192D01*
G37*
G36*
G01X569256Y936008D02*
X568873Y935826D01*
X568343Y936356D01*
X568525Y936740D01*
X568666Y936881D01*
X569398Y936149D01*
X569256Y936008D01*
G37*
G36*
G01X574119Y946997D02*
X574502Y947179D01*
X575033Y946649D01*
X574851Y946265D01*
X574709Y946124D01*
X573977Y946856D01*
X574119Y946997D01*
G37*
G36*
G01X575399Y945152D02*
X575015Y944969D01*
X574485Y945500D01*
X574667Y945883D01*
X574808Y946025D01*
X575540Y945293D01*
X575399Y945152D01*
G37*
G36*
G01X573737Y946813D02*
X573353Y946631D01*
X572823Y947161D01*
X573005Y947545D01*
X573146Y947687D01*
X573878Y946955D01*
X573737Y946813D01*
G37*
G36*
G01X572457Y948659D02*
X572841Y948841D01*
X573371Y948311D01*
X573189Y947927D01*
X573047Y947786D01*
X572316Y948517D01*
X572457Y948659D01*
G37*
G36*
G01X572075Y948475D02*
X571692Y948293D01*
X571161Y948823D01*
X571343Y949207D01*
X571485Y949348D01*
X572217Y948616D01*
X572075Y948475D01*
G37*
G36*
G01X574586Y947662D02*
X574202Y947480D01*
X573672Y948010D01*
X573854Y948394D01*
X573995Y948536D01*
X574727Y947804D01*
X574586Y947662D01*
G37*
G36*
G01X573306Y949508D02*
X573690Y949690D01*
X574220Y949160D01*
X574038Y948776D01*
X573896Y948635D01*
X573165Y949366D01*
X573306Y949508D01*
G37*
G36*
G01X572924Y949324D02*
X572541Y949142D01*
X572010Y949672D01*
X572192Y950056D01*
X572334Y950197D01*
X573066Y949465D01*
X572924Y949324D01*
G37*
G36*
G01X572888Y945964D02*
X572504Y945782D01*
X571974Y946312D01*
X572156Y946696D01*
X572297Y946838D01*
X573029Y946106D01*
X572888Y945964D01*
G37*
G36*
G01X573270Y946148D02*
X573653Y946330D01*
X574184Y945800D01*
X574002Y945416D01*
X573860Y945275D01*
X573128Y946007D01*
X573270Y946148D01*
G37*
G36*
G01X574550Y944303D02*
X574166Y944120D01*
X573636Y944651D01*
X573818Y945034D01*
X573959Y945176D01*
X574691Y944444D01*
X574550Y944303D01*
G37*
G36*
G01X569565Y949288D02*
X569181Y949106D01*
X568651Y949636D01*
X568833Y950020D01*
X568974Y950161D01*
X569706Y949429D01*
X569565Y949288D01*
G37*
G36*
G01X571226Y947626D02*
X570843Y947444D01*
X570312Y947974D01*
X570494Y948358D01*
X570636Y948499D01*
X571368Y947767D01*
X571226Y947626D01*
G37*
G36*
G01X571608Y947810D02*
X571992Y947992D01*
X572522Y947462D01*
X572340Y947078D01*
X572198Y946937D01*
X571467Y947668D01*
X571608Y947810D01*
G37*
G36*
G01X569946Y949471D02*
X570330Y949654D01*
X570860Y949123D01*
X570678Y948740D01*
X570537Y948598D01*
X569805Y949330D01*
X569946Y949471D01*
G37*
G36*
G01X566750Y933501D02*
X566366Y933319D01*
X565836Y933849D01*
X566018Y934233D01*
X566160Y934374D01*
X566891Y933643D01*
X566750Y933501D01*
G37*
G36*
G01X567981Y934535D02*
X568365Y934717D01*
X568895Y934186D01*
X568713Y933803D01*
X568572Y933661D01*
X567840Y934393D01*
X567981Y934535D01*
G37*
G36*
G01X567599Y934351D02*
X567216Y934169D01*
X566686Y934699D01*
X566868Y935083D01*
X567009Y935224D01*
X567741Y934492D01*
X567599Y934351D01*
G37*
G36*
G01X566320Y936196D02*
X566703Y936378D01*
X567234Y935848D01*
X567051Y935464D01*
X566910Y935323D01*
X566178Y936055D01*
X566320Y936196D01*
G37*
G36*
G01X567641Y955114D02*
X567498Y954714D01*
X566748D01*
X566606Y955114D01*
Y955314D01*
X567641D01*
Y955114D01*
G37*
G36*
G01X573773Y950173D02*
X573390Y949991D01*
X572859Y950521D01*
X573041Y950905D01*
X573183Y951046D01*
X573915Y950314D01*
X573773Y950173D01*
G37*
G36*
G01X572493Y952018D02*
X572877Y952201D01*
X573407Y951670D01*
X573225Y951287D01*
X573084Y951145D01*
X572352Y951877D01*
X572493Y952018D01*
G37*
G36*
G01X572112Y951835D02*
X571728Y951653D01*
X571198Y952183D01*
X571380Y952567D01*
X571521Y952708D01*
X572253Y951976D01*
X572112Y951835D01*
G37*
G36*
G01X570832Y953680D02*
X571215Y953862D01*
X571746Y953332D01*
X571563Y952948D01*
X571422Y952807D01*
X570690Y953539D01*
X570832Y953680D01*
G37*
G36*
G01X570450Y953496D02*
X570066Y953314D01*
X569536Y953845D01*
X569718Y954228D01*
X569859Y954370D01*
X570591Y953638D01*
X570450Y953496D01*
G37*
G36*
G01X570795Y950320D02*
X571179Y950503D01*
X571709Y949972D01*
X571527Y949589D01*
X571386Y949447D01*
X570654Y950179D01*
X570795Y950320D01*
G37*
G36*
G01X570414Y950137D02*
X570030Y949955D01*
X569500Y950485D01*
X569682Y950869D01*
X569823Y951010D01*
X570555Y950278D01*
X570414Y950137D01*
G37*
G36*
G01X569134Y951982D02*
X569517Y952164D01*
X570048Y951634D01*
X569865Y951250D01*
X569724Y951109D01*
X568992Y951841D01*
X569134Y951982D01*
G37*
G36*
G01X567641Y953914D02*
X567498Y953514D01*
X566748D01*
X566606Y953914D01*
Y954114D01*
X567641D01*
Y953914D01*
G37*
G36*
G01X571644Y951169D02*
X572028Y951352D01*
X572558Y950821D01*
X572376Y950438D01*
X572235Y950296D01*
X571503Y951028D01*
X571644Y951169D01*
G37*
G36*
G01X571263Y950986D02*
X570879Y950804D01*
X570349Y951334D01*
X570531Y951718D01*
X570672Y951859D01*
X571404Y951127D01*
X571263Y950986D01*
G37*
G36*
G01X569601Y952647D02*
X569217Y952465D01*
X568687Y952996D01*
X568869Y953379D01*
X569010Y953521D01*
X569742Y952789D01*
X569601Y952647D01*
G37*
G36*
G01X569983Y952831D02*
X570366Y953013D01*
X570897Y952483D01*
X570714Y952099D01*
X570573Y951958D01*
X569841Y952690D01*
X569983Y952831D01*
G37*
G36*
G01X568285Y951133D02*
X568668Y951315D01*
X569199Y950785D01*
X569016Y950401D01*
X568875Y950260D01*
X568143Y950992D01*
X568285Y951133D01*
G37*
G36*
G01X566102Y980588D02*
X566245Y980988D01*
X566995D01*
X567138Y980588D01*
Y980388D01*
X566102D01*
Y980588D01*
G37*
G36*
G01X568312Y980188D02*
X568170Y979788D01*
X567420D01*
X567278Y980188D01*
Y980388D01*
X568312D01*
Y980188D01*
G37*
G36*
G01X570662D02*
X570520Y979788D01*
X569770D01*
X569628Y980188D01*
Y980388D01*
X570662D01*
Y980188D01*
G37*
G36*
G01X568452Y980588D02*
X568595Y980988D01*
X569345D01*
X569488Y980588D01*
Y980388D01*
X568452D01*
Y980588D01*
G37*
G36*
G01X566102Y979388D02*
X566245Y979788D01*
X566995D01*
X567138Y979388D01*
Y979188D01*
X566102D01*
Y979388D01*
G37*
G36*
G01X568312Y978988D02*
X568170Y978588D01*
X567420D01*
X567278Y978988D01*
Y979188D01*
X568312D01*
Y978988D01*
G37*
G36*
G01X568452Y979388D02*
X568595Y979788D01*
X569345D01*
X569488Y979388D01*
Y979188D01*
X568452D01*
Y979388D01*
G37*
G36*
G01X566102Y978188D02*
X566245Y978588D01*
X566995D01*
X567138Y978188D01*
Y977988D01*
X566102D01*
Y978188D01*
G37*
G36*
G01X568312Y977788D02*
X568170Y977388D01*
X567420D01*
X567278Y977788D01*
Y977988D01*
X568312D01*
Y977788D01*
G37*
G36*
G01X568452Y978188D02*
X568595Y978588D01*
X569345D01*
X569488Y978188D01*
Y977988D01*
X568452D01*
Y978188D01*
G37*
G36*
G01X568312Y976588D02*
X568170Y976188D01*
X567420D01*
X567278Y976588D01*
Y976788D01*
X568312D01*
Y976588D01*
G37*
G36*
G01X566102Y976988D02*
X566245Y977388D01*
X566995D01*
X567138Y976988D01*
Y976788D01*
X566102D01*
Y976988D01*
G37*
G36*
G01X568452D02*
X568595Y977388D01*
X569345D01*
X569488Y976988D01*
Y976788D01*
X568452D01*
Y976988D01*
G37*
G36*
G01X566102Y975788D02*
X566245Y976188D01*
X566995D01*
X567138Y975788D01*
Y975588D01*
X566102D01*
Y975788D01*
G37*
G36*
G01X568312Y975388D02*
X568170Y974988D01*
X567420D01*
X567278Y975388D01*
Y975588D01*
X568312D01*
Y975388D01*
G37*
G36*
G01Y974188D02*
X568170Y973788D01*
X567420D01*
X567278Y974188D01*
Y974388D01*
X568312D01*
Y974188D01*
G37*
G36*
G01X566102Y974588D02*
X566245Y974988D01*
X566995D01*
X567138Y974588D01*
Y974388D01*
X566102D01*
Y974588D01*
G37*
G36*
G01Y973388D02*
X566245Y973788D01*
X566995D01*
X567138Y973388D01*
Y973188D01*
X566102D01*
Y973388D01*
G37*
G36*
G01Y972188D02*
X566245Y972588D01*
X566995D01*
X567138Y972188D01*
Y971988D01*
X566102D01*
Y972188D01*
G37*
G36*
G01X567196Y1009513D02*
X567378Y1009130D01*
X566848Y1008599D01*
X566464Y1008781D01*
X566323Y1008923D01*
X567055Y1009655D01*
X567196Y1009513D01*
G37*
G36*
G01X566200Y1007384D02*
X566017Y1007768D01*
X566548Y1008298D01*
X566931Y1008116D01*
X567073Y1007975D01*
X566341Y1007243D01*
X566200Y1007384D01*
G37*
G36*
G01X568045Y1008664D02*
X568227Y1008281D01*
X567697Y1007750D01*
X567313Y1007932D01*
X567172Y1008074D01*
X567904Y1008806D01*
X568045Y1008664D01*
G37*
G36*
G01X567049Y1006535D02*
X566866Y1006919D01*
X567397Y1007449D01*
X567780Y1007267D01*
X567922Y1007126D01*
X567190Y1006394D01*
X567049Y1006535D01*
G37*
G36*
G01X567232Y1006154D02*
X567414Y1005770D01*
X566884Y1005240D01*
X566501Y1005422D01*
X566359Y1005563D01*
X567091Y1006295D01*
X567232Y1006154D01*
G37*
G36*
G01X566343Y1030705D02*
X566161Y1031088D01*
X566691Y1031619D01*
X567075Y1031437D01*
X567216Y1031295D01*
X566484Y1030563D01*
X566343Y1030705D01*
G37*
G36*
G01X566527Y1030323D02*
X566709Y1029939D01*
X566178Y1029409D01*
X565795Y1029591D01*
X565653Y1029732D01*
X566385Y1030464D01*
X566527Y1030323D01*
G37*
G36*
G01X567114Y1046195D02*
X567296Y1045811D01*
X566766Y1045281D01*
X566382Y1045463D01*
X566241Y1045605D01*
X566972Y1046336D01*
X567114Y1046195D01*
G37*
G36*
G01X566930Y1046577D02*
X566748Y1046960D01*
X567278Y1047491D01*
X567662Y1047309D01*
X567803Y1047167D01*
X567071Y1046435D01*
X566930Y1046577D01*
G37*
G36*
G01X566117Y1044066D02*
X565935Y1044450D01*
X566466Y1044980D01*
X566849Y1044798D01*
X566991Y1044657D01*
X566259Y1043925D01*
X566117Y1044066D01*
G37*
G36*
G01X567963Y1045346D02*
X568145Y1044962D01*
X567615Y1044432D01*
X567231Y1044614D01*
X567090Y1044756D01*
X567821Y1045487D01*
X567963Y1045346D01*
G37*
G36*
G01X567779Y1045728D02*
X567597Y1046111D01*
X568127Y1046642D01*
X568511Y1046460D01*
X568652Y1046318D01*
X567920Y1045586D01*
X567779Y1045728D01*
G37*
G36*
G01X569625Y1047008D02*
X569807Y1046624D01*
X569276Y1046094D01*
X568893Y1046276D01*
X568751Y1046417D01*
X569483Y1047149D01*
X569625Y1047008D01*
G37*
G36*
G01X567303Y1036193D02*
X567485Y1035810D01*
X566955Y1035279D01*
X566571Y1035461D01*
X566430Y1035603D01*
X567162Y1036335D01*
X567303Y1036193D01*
G37*
G36*
G01X567119Y1036575D02*
X566937Y1036959D01*
X567468Y1037489D01*
X567851Y1037307D01*
X567993Y1037166D01*
X567261Y1036434D01*
X567119Y1036575D01*
G37*
G36*
G01X568965Y1037855D02*
X569147Y1037471D01*
X568617Y1036941D01*
X568233Y1037123D01*
X568092Y1037265D01*
X568823Y1037996D01*
X568965Y1037855D01*
G37*
G36*
G01X573766Y1043222D02*
X573584Y1043606D01*
X574114Y1044136D01*
X574498Y1043954D01*
X574639Y1043812D01*
X573908Y1043081D01*
X573766Y1043222D01*
G37*
G36*
G01X575612Y1044502D02*
X575794Y1044118D01*
X575263Y1043588D01*
X574880Y1043770D01*
X574738Y1043911D01*
X575470Y1044643D01*
X575612Y1044502D01*
G37*
G36*
G01X573950Y1042840D02*
X574132Y1042456D01*
X573602Y1041926D01*
X573218Y1042108D01*
X573077Y1042250D01*
X573809Y1042982D01*
X573950Y1042840D01*
G37*
G36*
G01X568781Y1038237D02*
X568599Y1038620D01*
X569129Y1039151D01*
X569513Y1038969D01*
X569654Y1038827D01*
X568922Y1038095D01*
X568781Y1038237D01*
G37*
G36*
G01X570443Y1039899D02*
X570261Y1040282D01*
X570791Y1040812D01*
X571175Y1040630D01*
X571316Y1040489D01*
X570584Y1039757D01*
X570443Y1039899D01*
G37*
G36*
G01X572288Y1041178D02*
X572470Y1040795D01*
X571940Y1040264D01*
X571556Y1040447D01*
X571415Y1040588D01*
X572147Y1041320D01*
X572288Y1041178D01*
G37*
G36*
G01X570627Y1039517D02*
X570809Y1039133D01*
X570278Y1038603D01*
X569895Y1038785D01*
X569753Y1038926D01*
X570485Y1039658D01*
X570627Y1039517D01*
G37*
G36*
G01X572104Y1041560D02*
X571922Y1041944D01*
X572453Y1042474D01*
X572836Y1042292D01*
X572978Y1042151D01*
X572246Y1041419D01*
X572104Y1041560D01*
G37*
G36*
G01X577090Y1046545D02*
X576907Y1046929D01*
X577438Y1047459D01*
X577821Y1047277D01*
X577963Y1047136D01*
X577231Y1046404D01*
X577090Y1046545D01*
G37*
G36*
G01X575428Y1044884D02*
X575246Y1045267D01*
X575776Y1045798D01*
X576160Y1045615D01*
X576301Y1045474D01*
X575569Y1044742D01*
X575428Y1044884D01*
G37*
G36*
G01X577273Y1046164D02*
X577455Y1045780D01*
X576925Y1045250D01*
X576541Y1045432D01*
X576400Y1045573D01*
X577132Y1046305D01*
X577273Y1046164D01*
G37*
G36*
G01X578935Y1047825D02*
X579117Y1047442D01*
X578587Y1046911D01*
X578203Y1047093D01*
X578062Y1047235D01*
X578794Y1047967D01*
X578935Y1047825D01*
G37*
G36*
G01X569001Y1034495D02*
X569183Y1034112D01*
X568653Y1033581D01*
X568269Y1033763D01*
X568128Y1033905D01*
X568860Y1034637D01*
X569001Y1034495D01*
G37*
G36*
G01X567156Y1033215D02*
X566974Y1033599D01*
X567504Y1034129D01*
X567887Y1033947D01*
X568029Y1033806D01*
X567297Y1033074D01*
X567156Y1033215D01*
G37*
G36*
G01X567339Y1032834D02*
X567522Y1032450D01*
X566991Y1031920D01*
X566608Y1032102D01*
X566466Y1032243D01*
X567198Y1032975D01*
X567339Y1032834D01*
G37*
G36*
G01X568817Y1034877D02*
X568635Y1035261D01*
X569166Y1035791D01*
X569549Y1035609D01*
X569691Y1035468D01*
X568959Y1034736D01*
X568817Y1034877D01*
G37*
G36*
G01X573802Y1039862D02*
X573620Y1040246D01*
X574151Y1040776D01*
X574534Y1040594D01*
X574676Y1040453D01*
X573944Y1039721D01*
X573802Y1039862D01*
G37*
G36*
G01X572141Y1038201D02*
X571959Y1038584D01*
X572489Y1039114D01*
X572873Y1038932D01*
X573014Y1038791D01*
X572282Y1038059D01*
X572141Y1038201D01*
G37*
G36*
G01X573986Y1039480D02*
X574168Y1039097D01*
X573638Y1038566D01*
X573254Y1038749D01*
X573113Y1038890D01*
X573845Y1039622D01*
X573986Y1039480D01*
G37*
G36*
G01X575648Y1041142D02*
X575830Y1040758D01*
X575300Y1040228D01*
X574916Y1040410D01*
X574775Y1040552D01*
X575507Y1041284D01*
X575648Y1041142D01*
G37*
G36*
G01X570479Y1036539D02*
X570297Y1036922D01*
X570827Y1037453D01*
X571211Y1037271D01*
X571352Y1037129D01*
X570620Y1036397D01*
X570479Y1036539D01*
G37*
G36*
G01X572325Y1037819D02*
X572507Y1037435D01*
X571976Y1036905D01*
X571593Y1037087D01*
X571451Y1037228D01*
X572183Y1037960D01*
X572325Y1037819D01*
G37*
G36*
G01X570663Y1036157D02*
X570845Y1035773D01*
X570315Y1035243D01*
X569931Y1035425D01*
X569790Y1035567D01*
X570521Y1036298D01*
X570663Y1036157D01*
G37*
G36*
G01X577126Y1043186D02*
X576944Y1043569D01*
X577474Y1044100D01*
X577858Y1043917D01*
X577999Y1043776D01*
X577267Y1043044D01*
X577126Y1043186D01*
G37*
G36*
G01X577310Y1042804D02*
X577492Y1042420D01*
X576961Y1041890D01*
X576578Y1042072D01*
X576436Y1042213D01*
X577168Y1042945D01*
X577310Y1042804D01*
G37*
G36*
G01X575464Y1041524D02*
X575282Y1041908D01*
X575812Y1042438D01*
X576196Y1042256D01*
X576337Y1042114D01*
X575606Y1041383D01*
X575464Y1041524D01*
G37*
G36*
G01X580449Y1046509D02*
X580267Y1046893D01*
X580797Y1047423D01*
X581181Y1047241D01*
X581322Y1047099D01*
X580591Y1046368D01*
X580449Y1046509D01*
G37*
G36*
G01X578971Y1044466D02*
X579153Y1044082D01*
X578623Y1043552D01*
X578239Y1043734D01*
X578098Y1043875D01*
X578830Y1044607D01*
X578971Y1044466D01*
G37*
G36*
G01X578788Y1044847D02*
X578605Y1045231D01*
X579136Y1045761D01*
X579519Y1045579D01*
X579661Y1045438D01*
X578929Y1044706D01*
X578788Y1044847D01*
G37*
G36*
G01X580633Y1046127D02*
X580815Y1045744D01*
X580285Y1045213D01*
X579901Y1045395D01*
X579760Y1045537D01*
X580492Y1046269D01*
X580633Y1046127D01*
G37*
G36*
G01X582295Y1047789D02*
X582477Y1047405D01*
X581947Y1046875D01*
X581563Y1047057D01*
X581421Y1047198D01*
X582153Y1047930D01*
X582295Y1047789D01*
G37*
G36*
G01X566307Y1034064D02*
X566125Y1034448D01*
X566655Y1034978D01*
X567038Y1034796D01*
X567180Y1034655D01*
X566448Y1033923D01*
X566307Y1034064D01*
G37*
G36*
G01X568152Y1035344D02*
X568334Y1034961D01*
X567804Y1034430D01*
X567420Y1034612D01*
X567279Y1034754D01*
X568011Y1035486D01*
X568152Y1035344D01*
G37*
G36*
G01X567968Y1035726D02*
X567786Y1036110D01*
X568317Y1036640D01*
X568700Y1036458D01*
X568842Y1036317D01*
X568110Y1035585D01*
X567968Y1035726D01*
G37*
G36*
G01X574615Y1042373D02*
X574433Y1042757D01*
X574963Y1043287D01*
X575347Y1043105D01*
X575488Y1042963D01*
X574757Y1042232D01*
X574615Y1042373D01*
G37*
G36*
G01X572953Y1040711D02*
X572771Y1041095D01*
X573302Y1041625D01*
X573685Y1041443D01*
X573827Y1041302D01*
X573095Y1040570D01*
X572953Y1040711D01*
G37*
G36*
G01X571292Y1039050D02*
X571110Y1039433D01*
X571640Y1039963D01*
X572024Y1039781D01*
X572165Y1039640D01*
X571433Y1038908D01*
X571292Y1039050D01*
G37*
G36*
G01X574799Y1041991D02*
X574981Y1041607D01*
X574451Y1041077D01*
X574067Y1041259D01*
X573926Y1041401D01*
X574658Y1042133D01*
X574799Y1041991D01*
G37*
G36*
G01X573137Y1040329D02*
X573319Y1039946D01*
X572789Y1039415D01*
X572405Y1039598D01*
X572264Y1039739D01*
X572996Y1040471D01*
X573137Y1040329D01*
G37*
G36*
G01X571476Y1038668D02*
X571658Y1038284D01*
X571127Y1037754D01*
X570744Y1037936D01*
X570602Y1038077D01*
X571334Y1038809D01*
X571476Y1038668D01*
G37*
G36*
G01X569814Y1037006D02*
X569996Y1036622D01*
X569466Y1036092D01*
X569082Y1036274D01*
X568941Y1036416D01*
X569672Y1037147D01*
X569814Y1037006D01*
G37*
G36*
G01X569630Y1037388D02*
X569448Y1037771D01*
X569978Y1038302D01*
X570362Y1038120D01*
X570503Y1037978D01*
X569771Y1037246D01*
X569630Y1037388D01*
G37*
G36*
G01X578122Y1045315D02*
X578304Y1044931D01*
X577774Y1044401D01*
X577390Y1044583D01*
X577249Y1044724D01*
X577981Y1045456D01*
X578122Y1045315D01*
G37*
G36*
G01X579784Y1046976D02*
X579966Y1046593D01*
X579436Y1046062D01*
X579052Y1046244D01*
X578911Y1046386D01*
X579643Y1047118D01*
X579784Y1046976D01*
G37*
G36*
G01X577939Y1045696D02*
X577756Y1046080D01*
X578287Y1046610D01*
X578670Y1046428D01*
X578812Y1046287D01*
X578080Y1045555D01*
X577939Y1045696D01*
G37*
G36*
G01X576277Y1044035D02*
X576095Y1044418D01*
X576625Y1044949D01*
X577009Y1044766D01*
X577150Y1044625D01*
X576418Y1043893D01*
X576277Y1044035D01*
G37*
G36*
G01X576461Y1043653D02*
X576643Y1043269D01*
X576112Y1042739D01*
X575729Y1042921D01*
X575587Y1043062D01*
X576319Y1043794D01*
X576461Y1043653D01*
G37*
G36*
G01X568188Y1031985D02*
X568371Y1031601D01*
X567840Y1031071D01*
X567457Y1031253D01*
X567315Y1031394D01*
X568047Y1032126D01*
X568188Y1031985D01*
G37*
G36*
G01X568005Y1032366D02*
X567823Y1032750D01*
X568353Y1033280D01*
X568736Y1033098D01*
X568878Y1032957D01*
X568146Y1032225D01*
X568005Y1032366D01*
G37*
G36*
G01X571512Y1035308D02*
X571694Y1034924D01*
X571164Y1034394D01*
X570780Y1034576D01*
X570639Y1034718D01*
X571370Y1035449D01*
X571512Y1035308D01*
G37*
G36*
G01X569666Y1034028D02*
X569484Y1034412D01*
X570015Y1034942D01*
X570398Y1034760D01*
X570540Y1034619D01*
X569808Y1033887D01*
X569666Y1034028D01*
G37*
G36*
G01X569850Y1033646D02*
X570032Y1033263D01*
X569502Y1032732D01*
X569118Y1032914D01*
X568977Y1033056D01*
X569709Y1033788D01*
X569850Y1033646D01*
G37*
G36*
G01X574835Y1038631D02*
X575017Y1038248D01*
X574487Y1037717D01*
X574103Y1037900D01*
X573962Y1038041D01*
X574694Y1038773D01*
X574835Y1038631D01*
G37*
G36*
G01X574651Y1039013D02*
X574469Y1039397D01*
X575000Y1039927D01*
X575383Y1039745D01*
X575525Y1039604D01*
X574793Y1038872D01*
X574651Y1039013D01*
G37*
G36*
G01X573174Y1036970D02*
X573356Y1036586D01*
X572825Y1036056D01*
X572442Y1036238D01*
X572300Y1036379D01*
X573032Y1037111D01*
X573174Y1036970D01*
G37*
G36*
G01X572990Y1037352D02*
X572808Y1037735D01*
X573338Y1038265D01*
X573722Y1038083D01*
X573863Y1037942D01*
X573131Y1037210D01*
X572990Y1037352D01*
G37*
G36*
G01X571328Y1035690D02*
X571146Y1036073D01*
X571676Y1036604D01*
X572060Y1036422D01*
X572201Y1036280D01*
X571469Y1035548D01*
X571328Y1035690D01*
G37*
G36*
G01X577975Y1042337D02*
X577793Y1042720D01*
X578323Y1043251D01*
X578707Y1043068D01*
X578848Y1042927D01*
X578116Y1042195D01*
X577975Y1042337D01*
G37*
G36*
G01X576497Y1040293D02*
X576679Y1039909D01*
X576149Y1039379D01*
X575765Y1039561D01*
X575624Y1039703D01*
X576356Y1040435D01*
X576497Y1040293D01*
G37*
G36*
G01X578159Y1041955D02*
X578341Y1041571D01*
X577810Y1041041D01*
X577427Y1041223D01*
X577285Y1041364D01*
X578017Y1042096D01*
X578159Y1041955D01*
G37*
G36*
G01X576313Y1040675D02*
X576131Y1041059D01*
X576661Y1041589D01*
X577045Y1041407D01*
X577186Y1041265D01*
X576455Y1040534D01*
X576313Y1040675D01*
G37*
G36*
G01X579820Y1043617D02*
X580002Y1043233D01*
X579472Y1042703D01*
X579088Y1042885D01*
X578947Y1043026D01*
X579679Y1043758D01*
X579820Y1043617D01*
G37*
G36*
G01X579637Y1043998D02*
X579454Y1044382D01*
X579985Y1044912D01*
X580368Y1044730D01*
X580510Y1044589D01*
X579778Y1043857D01*
X579637Y1043998D01*
G37*
G36*
G01X581298Y1045660D02*
X581116Y1046044D01*
X581646Y1046574D01*
X582030Y1046392D01*
X582171Y1046250D01*
X581440Y1045519D01*
X581298Y1045660D01*
G37*
G36*
G01X581482Y1045278D02*
X581664Y1044895D01*
X581134Y1044364D01*
X580750Y1044546D01*
X580609Y1044688D01*
X581341Y1045420D01*
X581482Y1045278D01*
G37*
G36*
G01X567078Y1049555D02*
X567260Y1049171D01*
X566729Y1048641D01*
X566346Y1048823D01*
X566204Y1048964D01*
X566936Y1049696D01*
X567078Y1049555D01*
G37*
G36*
G01X568739Y1051216D02*
X568921Y1050833D01*
X568391Y1050303D01*
X568007Y1050485D01*
X567866Y1050626D01*
X568598Y1051358D01*
X568739Y1051216D01*
G37*
G36*
G01X566894Y1049937D02*
X566712Y1050320D01*
X567242Y1050851D01*
X567626Y1050668D01*
X567767Y1050527D01*
X567035Y1049795D01*
X566894Y1049937D01*
G37*
G36*
G01X575202Y1058245D02*
X575020Y1058629D01*
X575551Y1059159D01*
X575934Y1058977D01*
X576076Y1058836D01*
X575344Y1058104D01*
X575202Y1058245D01*
G37*
G36*
G01X570401Y1052878D02*
X570583Y1052495D01*
X570053Y1051964D01*
X569669Y1052146D01*
X569528Y1052288D01*
X570260Y1053020D01*
X570401Y1052878D01*
G37*
G36*
G01X575386Y1057863D02*
X575568Y1057480D01*
X575038Y1056949D01*
X574654Y1057131D01*
X574513Y1057273D01*
X575245Y1058005D01*
X575386Y1057863D01*
G37*
G36*
G01X572063Y1054540D02*
X572245Y1054156D01*
X571714Y1053626D01*
X571331Y1053808D01*
X571189Y1053949D01*
X571921Y1054681D01*
X572063Y1054540D01*
G37*
G36*
G01X573724Y1056202D02*
X573906Y1055818D01*
X573376Y1055288D01*
X572993Y1055470D01*
X572851Y1055611D01*
X573583Y1056343D01*
X573724Y1056202D01*
G37*
G36*
G01X573541Y1056583D02*
X573358Y1056967D01*
X573889Y1057497D01*
X574272Y1057315D01*
X574414Y1057174D01*
X573682Y1056442D01*
X573541Y1056583D01*
G37*
G36*
G01X571879Y1054922D02*
X571697Y1055305D01*
X572227Y1055836D01*
X572611Y1055654D01*
X572752Y1055512D01*
X572020Y1054780D01*
X571879Y1054922D01*
G37*
G36*
G01X570217Y1053260D02*
X570035Y1053644D01*
X570565Y1054174D01*
X570949Y1053992D01*
X571090Y1053850D01*
X570359Y1053119D01*
X570217Y1053260D01*
G37*
G36*
G01X568555Y1051598D02*
X568373Y1051982D01*
X568904Y1052512D01*
X569287Y1052330D01*
X569429Y1052189D01*
X568697Y1051457D01*
X568555Y1051598D01*
G37*
G36*
G01X577048Y1059525D02*
X577230Y1059141D01*
X576700Y1058611D01*
X576316Y1058793D01*
X576175Y1058935D01*
X576906Y1059666D01*
X577048Y1059525D01*
G37*
G36*
G01X576864Y1059907D02*
X576682Y1060290D01*
X577212Y1060821D01*
X577596Y1060639D01*
X577737Y1060497D01*
X577005Y1059765D01*
X576864Y1059907D01*
G37*
G36*
G01X580371Y1062848D02*
X580553Y1062465D01*
X580023Y1061934D01*
X579639Y1062117D01*
X579498Y1062258D01*
X580230Y1062990D01*
X580371Y1062848D01*
G37*
G36*
G01X578526Y1061568D02*
X578344Y1061952D01*
X578874Y1062482D01*
X579258Y1062300D01*
X579399Y1062159D01*
X578667Y1061427D01*
X578526Y1061568D01*
G37*
G36*
G01X578710Y1061187D02*
X578892Y1060803D01*
X578361Y1060273D01*
X577978Y1060455D01*
X577836Y1060596D01*
X578568Y1061328D01*
X578710Y1061187D01*
G37*
G36*
G01X580187Y1063230D02*
X580005Y1063614D01*
X580536Y1064144D01*
X580919Y1063962D01*
X581061Y1063821D01*
X580329Y1063089D01*
X580187Y1063230D01*
G37*
G36*
G01X570253Y1049900D02*
X570071Y1050284D01*
X570602Y1050814D01*
X570985Y1050632D01*
X571127Y1050491D01*
X570395Y1049759D01*
X570253Y1049900D01*
G37*
G36*
G01X571915Y1051562D02*
X571733Y1051946D01*
X572263Y1052476D01*
X572647Y1052294D01*
X572788Y1052152D01*
X572057Y1051421D01*
X571915Y1051562D01*
G37*
G36*
G01X572099Y1051180D02*
X572281Y1050797D01*
X571751Y1050266D01*
X571367Y1050448D01*
X571226Y1050590D01*
X571958Y1051322D01*
X572099Y1051180D01*
G37*
G36*
G01X573761Y1052842D02*
X573943Y1052458D01*
X573412Y1051928D01*
X573029Y1052110D01*
X572887Y1052251D01*
X573619Y1052983D01*
X573761Y1052842D01*
G37*
G36*
G01X575422Y1054504D02*
X575604Y1054120D01*
X575074Y1053590D01*
X574691Y1053772D01*
X574549Y1053913D01*
X575281Y1054645D01*
X575422Y1054504D01*
G37*
G36*
G01X575239Y1054885D02*
X575056Y1055269D01*
X575587Y1055799D01*
X575970Y1055617D01*
X576112Y1055476D01*
X575380Y1054744D01*
X575239Y1054885D01*
G37*
G36*
G01X573577Y1053224D02*
X573395Y1053607D01*
X573925Y1054138D01*
X574309Y1053956D01*
X574450Y1053814D01*
X573718Y1053082D01*
X573577Y1053224D01*
G37*
G36*
G01X568776Y1047857D02*
X568958Y1047473D01*
X568427Y1046943D01*
X568044Y1047125D01*
X567902Y1047266D01*
X568634Y1047998D01*
X568776Y1047857D01*
G37*
G36*
G01X570437Y1049518D02*
X570619Y1049135D01*
X570089Y1048605D01*
X569705Y1048787D01*
X569564Y1048928D01*
X570296Y1049660D01*
X570437Y1049518D01*
G37*
G36*
G01X568592Y1048239D02*
X568410Y1048622D01*
X568940Y1049153D01*
X569324Y1048970D01*
X569465Y1048829D01*
X568733Y1048097D01*
X568592Y1048239D01*
G37*
G36*
G01X580408Y1059489D02*
X580590Y1059105D01*
X580059Y1058575D01*
X579676Y1058757D01*
X579534Y1058898D01*
X580266Y1059630D01*
X580408Y1059489D01*
G37*
G36*
G01X580224Y1059870D02*
X580042Y1060254D01*
X580572Y1060784D01*
X580956Y1060602D01*
X581097Y1060461D01*
X580365Y1059729D01*
X580224Y1059870D01*
G37*
G36*
G01X577084Y1056165D02*
X577266Y1055782D01*
X576736Y1055251D01*
X576352Y1055433D01*
X576211Y1055575D01*
X576943Y1056307D01*
X577084Y1056165D01*
G37*
G36*
G01X576900Y1056547D02*
X576718Y1056931D01*
X577249Y1057461D01*
X577632Y1057279D01*
X577774Y1057138D01*
X577042Y1056406D01*
X576900Y1056547D01*
G37*
G36*
G01X578746Y1057827D02*
X578928Y1057443D01*
X578398Y1056913D01*
X578014Y1057095D01*
X577873Y1057237D01*
X578604Y1057968D01*
X578746Y1057827D01*
G37*
G36*
G01X578562Y1058209D02*
X578380Y1058592D01*
X578910Y1059123D01*
X579294Y1058941D01*
X579435Y1058799D01*
X578703Y1058067D01*
X578562Y1058209D01*
G37*
G36*
G01X581885Y1061532D02*
X581703Y1061916D01*
X582234Y1062446D01*
X582617Y1062264D01*
X582759Y1062123D01*
X582027Y1061391D01*
X581885Y1061532D01*
G37*
G36*
G01X582069Y1061150D02*
X582251Y1060767D01*
X581721Y1060236D01*
X581337Y1060419D01*
X581196Y1060560D01*
X581928Y1061292D01*
X582069Y1061150D01*
G37*
G36*
G01X567743Y1049088D02*
X567561Y1049471D01*
X568091Y1050002D01*
X568475Y1049819D01*
X568616Y1049678D01*
X567884Y1048946D01*
X567743Y1049088D01*
G37*
G36*
G01X569588Y1050367D02*
X569770Y1049984D01*
X569240Y1049454D01*
X568856Y1049636D01*
X568715Y1049777D01*
X569447Y1050509D01*
X569588Y1050367D01*
G37*
G36*
G01X571250Y1052029D02*
X571432Y1051646D01*
X570902Y1051115D01*
X570518Y1051297D01*
X570377Y1051439D01*
X571109Y1052171D01*
X571250Y1052029D01*
G37*
G36*
G01X569404Y1050749D02*
X569222Y1051133D01*
X569753Y1051663D01*
X570136Y1051481D01*
X570278Y1051340D01*
X569546Y1050608D01*
X569404Y1050749D01*
G37*
G36*
G01X572912Y1053691D02*
X573094Y1053307D01*
X572563Y1052777D01*
X572180Y1052959D01*
X572038Y1053100D01*
X572770Y1053832D01*
X572912Y1053691D01*
G37*
G36*
G01X571066Y1052411D02*
X570884Y1052795D01*
X571414Y1053325D01*
X571798Y1053143D01*
X571939Y1053001D01*
X571208Y1052270D01*
X571066Y1052411D01*
G37*
G36*
G01X574573Y1055353D02*
X574755Y1054969D01*
X574225Y1054439D01*
X573842Y1054621D01*
X573700Y1054762D01*
X574432Y1055494D01*
X574573Y1055353D01*
G37*
G36*
G01X574390Y1055734D02*
X574207Y1056118D01*
X574738Y1056648D01*
X575121Y1056466D01*
X575263Y1056325D01*
X574531Y1055593D01*
X574390Y1055734D01*
G37*
G36*
G01X572728Y1054073D02*
X572546Y1054456D01*
X573076Y1054987D01*
X573460Y1054805D01*
X573601Y1054663D01*
X572869Y1053931D01*
X572728Y1054073D01*
G37*
G36*
G01X566081Y1047426D02*
X565899Y1047809D01*
X566429Y1048340D01*
X566813Y1048158D01*
X566954Y1048016D01*
X566222Y1047284D01*
X566081Y1047426D01*
G37*
G36*
G01X567927Y1048706D02*
X568109Y1048322D01*
X567578Y1047792D01*
X567195Y1047974D01*
X567053Y1048115D01*
X567785Y1048847D01*
X567927Y1048706D01*
G37*
G36*
G01X579559Y1060338D02*
X579741Y1059954D01*
X579210Y1059424D01*
X578827Y1059606D01*
X578685Y1059747D01*
X579417Y1060479D01*
X579559Y1060338D01*
G37*
G36*
G01X577713Y1059058D02*
X577531Y1059441D01*
X578061Y1059972D01*
X578445Y1059790D01*
X578586Y1059648D01*
X577854Y1058916D01*
X577713Y1059058D01*
G37*
G36*
G01X581220Y1061999D02*
X581402Y1061616D01*
X580872Y1061085D01*
X580488Y1061268D01*
X580347Y1061409D01*
X581079Y1062141D01*
X581220Y1061999D01*
G37*
G36*
G01X579375Y1060719D02*
X579193Y1061103D01*
X579723Y1061633D01*
X580107Y1061451D01*
X580248Y1061310D01*
X579516Y1060578D01*
X579375Y1060719D01*
G37*
G36*
G01X576235Y1057014D02*
X576417Y1056631D01*
X575887Y1056100D01*
X575503Y1056282D01*
X575362Y1056424D01*
X576094Y1057156D01*
X576235Y1057014D01*
G37*
G36*
G01X576051Y1057396D02*
X575869Y1057780D01*
X576400Y1058310D01*
X576783Y1058128D01*
X576925Y1057987D01*
X576193Y1057255D01*
X576051Y1057396D01*
G37*
G36*
G01X577897Y1058676D02*
X578079Y1058292D01*
X577549Y1057762D01*
X577165Y1057944D01*
X577024Y1058086D01*
X577755Y1058817D01*
X577897Y1058676D01*
G37*
G36*
G01X581036Y1062381D02*
X580854Y1062765D01*
X581385Y1063295D01*
X581768Y1063113D01*
X581910Y1062972D01*
X581178Y1062240D01*
X581036Y1062381D01*
G37*
G36*
G01X572764Y1050713D02*
X572582Y1051097D01*
X573112Y1051627D01*
X573496Y1051445D01*
X573637Y1051303D01*
X572906Y1050572D01*
X572764Y1050713D01*
G37*
G36*
G01X572948Y1050331D02*
X573130Y1049948D01*
X572600Y1049417D01*
X572216Y1049599D01*
X572075Y1049741D01*
X572807Y1050473D01*
X572948Y1050331D01*
G37*
G36*
G01X571102Y1049051D02*
X570920Y1049435D01*
X571451Y1049965D01*
X571834Y1049783D01*
X571976Y1049642D01*
X571244Y1048910D01*
X571102Y1049051D01*
G37*
G36*
G01X574610Y1051993D02*
X574792Y1051609D01*
X574261Y1051079D01*
X573878Y1051261D01*
X573736Y1051402D01*
X574468Y1052134D01*
X574610Y1051993D01*
G37*
G36*
G01X574426Y1052375D02*
X574244Y1052758D01*
X574774Y1053289D01*
X575158Y1053107D01*
X575299Y1052965D01*
X574567Y1052233D01*
X574426Y1052375D01*
G37*
G36*
G01X569441Y1047390D02*
X569259Y1047773D01*
X569789Y1048304D01*
X570173Y1048121D01*
X570314Y1047980D01*
X569582Y1047248D01*
X569441Y1047390D01*
G37*
G36*
G01X571286Y1048669D02*
X571468Y1048286D01*
X570938Y1047756D01*
X570554Y1047938D01*
X570413Y1048079D01*
X571145Y1048811D01*
X571286Y1048669D01*
G37*
G36*
G01X576271Y1053655D02*
X576453Y1053271D01*
X575923Y1052741D01*
X575540Y1052923D01*
X575398Y1053064D01*
X576130Y1053796D01*
X576271Y1053655D01*
G37*
G36*
G01X576088Y1054036D02*
X575905Y1054420D01*
X576436Y1054950D01*
X576819Y1054768D01*
X576961Y1054627D01*
X576229Y1053895D01*
X576088Y1054036D01*
G37*
G36*
G01X577933Y1055316D02*
X578115Y1054933D01*
X577585Y1054402D01*
X577201Y1054584D01*
X577060Y1054726D01*
X577792Y1055458D01*
X577933Y1055316D01*
G37*
G36*
G01X581257Y1058640D02*
X581439Y1058256D01*
X580908Y1057726D01*
X580525Y1057908D01*
X580383Y1058049D01*
X581115Y1058781D01*
X581257Y1058640D01*
G37*
G36*
G01X579411Y1057360D02*
X579229Y1057743D01*
X579759Y1058274D01*
X580143Y1058092D01*
X580284Y1057950D01*
X579552Y1057218D01*
X579411Y1057360D01*
G37*
G36*
G01X579595Y1056978D02*
X579777Y1056594D01*
X579247Y1056064D01*
X578863Y1056246D01*
X578722Y1056388D01*
X579453Y1057119D01*
X579595Y1056978D01*
G37*
G36*
G01X577749Y1055698D02*
X577567Y1056082D01*
X578098Y1056612D01*
X578481Y1056430D01*
X578623Y1056289D01*
X577891Y1055557D01*
X577749Y1055698D01*
G37*
G36*
G01X581073Y1059021D02*
X580891Y1059405D01*
X581421Y1059935D01*
X581805Y1059753D01*
X581946Y1059612D01*
X581214Y1058880D01*
X581073Y1059021D01*
G37*
G36*
G01X580413Y1049869D02*
X580231Y1050252D01*
X580761Y1050783D01*
X581145Y1050601D01*
X581286Y1050459D01*
X580554Y1049727D01*
X580413Y1049869D01*
G37*
G36*
G01X582075Y1051530D02*
X581893Y1051914D01*
X582423Y1052444D01*
X582806Y1052262D01*
X582948Y1052121D01*
X582216Y1051389D01*
X582075Y1051530D01*
G37*
G36*
G01X582258Y1051149D02*
X582441Y1050765D01*
X581910Y1050235D01*
X581527Y1050417D01*
X581385Y1050558D01*
X582117Y1051290D01*
X582258Y1051149D01*
G37*
G36*
G01X578751Y1048207D02*
X578569Y1048591D01*
X579099Y1049121D01*
X579483Y1048939D01*
X579624Y1048797D01*
X578893Y1048066D01*
X578751Y1048207D01*
G37*
G36*
G01X580597Y1049487D02*
X580779Y1049103D01*
X580249Y1048573D01*
X579865Y1048755D01*
X579723Y1048896D01*
X580455Y1049628D01*
X580597Y1049487D01*
G37*
G36*
G01X581262Y1049020D02*
X581080Y1049403D01*
X581610Y1049934D01*
X581994Y1049752D01*
X582135Y1049610D01*
X581403Y1048878D01*
X581262Y1049020D01*
G37*
G36*
G01X579600Y1047358D02*
X579418Y1047742D01*
X579948Y1048272D01*
X580332Y1048090D01*
X580473Y1047948D01*
X579742Y1047217D01*
X579600Y1047358D01*
G37*
G36*
G01X581446Y1048638D02*
X581628Y1048254D01*
X581098Y1047724D01*
X580714Y1047906D01*
X580572Y1048047D01*
X581304Y1048779D01*
X581446Y1048638D01*
G37*
G36*
G01X568022Y1058581D02*
X568204Y1058197D01*
X567673Y1057667D01*
X567290Y1057849D01*
X567148Y1057990D01*
X567880Y1058722D01*
X568022Y1058581D01*
G37*
G36*
G01X566176Y1057301D02*
X565994Y1057685D01*
X566524Y1058215D01*
X566908Y1058033D01*
X567049Y1057891D01*
X566318Y1057160D01*
X566176Y1057301D01*
G37*
G36*
G01X567838Y1058963D02*
X567656Y1059346D01*
X568186Y1059877D01*
X568570Y1059695D01*
X568711Y1059553D01*
X567979Y1058821D01*
X567838Y1058963D01*
G37*
G36*
G01X573007Y1063566D02*
X573189Y1063182D01*
X572659Y1062652D01*
X572275Y1062834D01*
X572134Y1062976D01*
X572865Y1063707D01*
X573007Y1063566D01*
G37*
G36*
G01X571161Y1062286D02*
X570979Y1062670D01*
X571510Y1063200D01*
X571893Y1063018D01*
X572035Y1062877D01*
X571303Y1062145D01*
X571161Y1062286D01*
G37*
G36*
G01X569683Y1060243D02*
X569865Y1059859D01*
X569335Y1059329D01*
X568952Y1059511D01*
X568810Y1059652D01*
X569542Y1060384D01*
X569683Y1060243D01*
G37*
G36*
G01X569500Y1060624D02*
X569317Y1061008D01*
X569848Y1061538D01*
X570231Y1061356D01*
X570373Y1061215D01*
X569641Y1060483D01*
X569500Y1060624D01*
G37*
G36*
G01X571345Y1061904D02*
X571527Y1061521D01*
X570997Y1060990D01*
X570613Y1061172D01*
X570472Y1061314D01*
X571204Y1062046D01*
X571345Y1061904D01*
G37*
G36*
G01X566213Y1053941D02*
X566031Y1054324D01*
X566561Y1054855D01*
X566945Y1054673D01*
X567086Y1054531D01*
X566354Y1053799D01*
X566213Y1053941D01*
G37*
G36*
G01X568058Y1055221D02*
X568241Y1054837D01*
X567710Y1054307D01*
X567327Y1054489D01*
X567185Y1054630D01*
X567917Y1055362D01*
X568058Y1055221D01*
G37*
G36*
G01X567875Y1055602D02*
X567693Y1055986D01*
X568223Y1056516D01*
X568607Y1056334D01*
X568748Y1056193D01*
X568016Y1055461D01*
X567875Y1055602D01*
G37*
G36*
G01X571382Y1058544D02*
X571564Y1058160D01*
X571034Y1057630D01*
X570650Y1057812D01*
X570509Y1057954D01*
X571240Y1058685D01*
X571382Y1058544D01*
G37*
G36*
G01X569536Y1057264D02*
X569354Y1057648D01*
X569885Y1058178D01*
X570268Y1057996D01*
X570410Y1057855D01*
X569678Y1057123D01*
X569536Y1057264D01*
G37*
G36*
G01X569720Y1056882D02*
X569902Y1056499D01*
X569372Y1055968D01*
X568988Y1056151D01*
X568847Y1056292D01*
X569579Y1057024D01*
X569720Y1056882D01*
G37*
G36*
G01X574521Y1062249D02*
X574339Y1062633D01*
X574870Y1063163D01*
X575253Y1062981D01*
X575395Y1062840D01*
X574663Y1062108D01*
X574521Y1062249D01*
G37*
G36*
G01X573044Y1060206D02*
X573226Y1059822D01*
X572695Y1059292D01*
X572312Y1059474D01*
X572170Y1059615D01*
X572902Y1060347D01*
X573044Y1060206D01*
G37*
G36*
G01X571198Y1058926D02*
X571016Y1059310D01*
X571546Y1059840D01*
X571930Y1059658D01*
X572071Y1059516D01*
X571339Y1058784D01*
X571198Y1058926D01*
G37*
G36*
G01X574705Y1061867D02*
X574887Y1061484D01*
X574357Y1060954D01*
X573973Y1061136D01*
X573832Y1061277D01*
X574564Y1062009D01*
X574705Y1061867D01*
G37*
G36*
G01X572860Y1060588D02*
X572678Y1060971D01*
X573208Y1061502D01*
X573592Y1061319D01*
X573733Y1061178D01*
X573001Y1060446D01*
X572860Y1060588D01*
G37*
G36*
G01X576367Y1063529D02*
X576549Y1063146D01*
X576019Y1062615D01*
X575635Y1062797D01*
X575494Y1062939D01*
X576226Y1063671D01*
X576367Y1063529D01*
G37*
G36*
G01X568871Y1057732D02*
X569053Y1057348D01*
X568522Y1056818D01*
X568139Y1057000D01*
X567997Y1057141D01*
X568729Y1057873D01*
X568871Y1057732D01*
G37*
G36*
G01X567025Y1056452D02*
X566843Y1056836D01*
X567373Y1057366D01*
X567757Y1057184D01*
X567898Y1057042D01*
X567167Y1056311D01*
X567025Y1056452D01*
G37*
G36*
G01X567209Y1056070D02*
X567391Y1055687D01*
X566861Y1055156D01*
X566477Y1055338D01*
X566336Y1055480D01*
X567068Y1056212D01*
X567209Y1056070D01*
G37*
G36*
G01X570349Y1059775D02*
X570166Y1060159D01*
X570697Y1060689D01*
X571080Y1060507D01*
X571222Y1060366D01*
X570490Y1059634D01*
X570349Y1059775D01*
G37*
G36*
G01X573856Y1062717D02*
X574038Y1062333D01*
X573508Y1061803D01*
X573124Y1061985D01*
X572983Y1062127D01*
X573714Y1062858D01*
X573856Y1062717D01*
G37*
G36*
G01X572010Y1061437D02*
X571828Y1061821D01*
X572359Y1062351D01*
X572742Y1062169D01*
X572884Y1062028D01*
X572152Y1061296D01*
X572010Y1061437D01*
G37*
G36*
G01X572194Y1061055D02*
X572376Y1060672D01*
X571846Y1060141D01*
X571462Y1060323D01*
X571321Y1060465D01*
X572053Y1061197D01*
X572194Y1061055D01*
G37*
G36*
G01X573672Y1063099D02*
X573490Y1063482D01*
X574020Y1064013D01*
X574404Y1063831D01*
X574545Y1063689D01*
X573813Y1062957D01*
X573672Y1063099D01*
G37*
G36*
G01X568687Y1058114D02*
X568505Y1058497D01*
X569035Y1059028D01*
X569419Y1058846D01*
X569560Y1058704D01*
X568828Y1057972D01*
X568687Y1058114D01*
G37*
G36*
G01X570532Y1059394D02*
X570714Y1059010D01*
X570184Y1058480D01*
X569801Y1058662D01*
X569659Y1058803D01*
X570391Y1059535D01*
X570532Y1059394D01*
G37*
G36*
G01X568908Y1054371D02*
X569090Y1053988D01*
X568560Y1053457D01*
X568176Y1053639D01*
X568035Y1053781D01*
X568767Y1054513D01*
X568908Y1054371D01*
G37*
G36*
G01X567246Y1052709D02*
X567428Y1052326D01*
X566898Y1051796D01*
X566514Y1051978D01*
X566373Y1052119D01*
X567105Y1052851D01*
X567246Y1052709D01*
G37*
G36*
G01X567062Y1053091D02*
X566880Y1053475D01*
X567411Y1054005D01*
X567794Y1053823D01*
X567936Y1053682D01*
X567204Y1052950D01*
X567062Y1053091D01*
G37*
G36*
G01X573709Y1059738D02*
X573527Y1060122D01*
X574058Y1060652D01*
X574441Y1060470D01*
X574583Y1060329D01*
X573851Y1059597D01*
X573709Y1059738D01*
G37*
G36*
G01X575555Y1061018D02*
X575737Y1060634D01*
X575207Y1060104D01*
X574823Y1060286D01*
X574682Y1060428D01*
X575413Y1061159D01*
X575555Y1061018D01*
G37*
G36*
G01X575371Y1061400D02*
X575189Y1061783D01*
X575719Y1062314D01*
X576103Y1062132D01*
X576244Y1061990D01*
X575512Y1061258D01*
X575371Y1061400D01*
G37*
G36*
G01X572048Y1058076D02*
X571865Y1058460D01*
X572396Y1058990D01*
X572779Y1058808D01*
X572921Y1058667D01*
X572189Y1057935D01*
X572048Y1058076D01*
G37*
G36*
G01X573893Y1059356D02*
X574075Y1058973D01*
X573545Y1058442D01*
X573161Y1058624D01*
X573020Y1058766D01*
X573752Y1059498D01*
X573893Y1059356D01*
G37*
G36*
G01X572231Y1057695D02*
X572413Y1057311D01*
X571883Y1056781D01*
X571500Y1056963D01*
X571358Y1057104D01*
X572090Y1057836D01*
X572231Y1057695D01*
G37*
G36*
G01X570570Y1056033D02*
X570752Y1055649D01*
X570221Y1055119D01*
X569838Y1055301D01*
X569696Y1055442D01*
X570428Y1056174D01*
X570570Y1056033D01*
G37*
G36*
G01X570386Y1056415D02*
X570204Y1056798D01*
X570734Y1057329D01*
X571118Y1057147D01*
X571259Y1057005D01*
X570527Y1056273D01*
X570386Y1056415D01*
G37*
G36*
G01X568724Y1054753D02*
X568542Y1055137D01*
X569072Y1055667D01*
X569456Y1055485D01*
X569597Y1055343D01*
X568866Y1054612D01*
X568724Y1054753D01*
G37*
G36*
G01X577033Y1063061D02*
X576851Y1063445D01*
X577381Y1063975D01*
X577765Y1063793D01*
X577906Y1063652D01*
X577174Y1062920D01*
X577033Y1063061D01*
G37*
G36*
G01X577217Y1062680D02*
X577399Y1062296D01*
X576868Y1061766D01*
X576485Y1061948D01*
X576343Y1062089D01*
X577075Y1062821D01*
X577217Y1062680D01*
G37*
G36*
G01X582033Y1064510D02*
X582215Y1064126D01*
X581685Y1063596D01*
X581301Y1063778D01*
X581160Y1063920D01*
X581891Y1064651D01*
X582033Y1064510D01*
G37*
G36*
G01X581849Y1064892D02*
X581667Y1065276D01*
X582197Y1065806D01*
X582581Y1065624D01*
X582722Y1065482D01*
X581990Y1064750D01*
X581849Y1064892D01*
G37*
G36*
G01X566265Y1079536D02*
X566083Y1079920D01*
X566613Y1080450D01*
X566997Y1080268D01*
X567138Y1080127D01*
X566406Y1079395D01*
X566265Y1079536D01*
G37*
G36*
G01X566301Y1076176D02*
X566119Y1076560D01*
X566650Y1077090D01*
X567033Y1076908D01*
X567175Y1076767D01*
X566443Y1076035D01*
X566301Y1076176D01*
G37*
G36*
G01X568147Y1077456D02*
X568329Y1077072D01*
X567799Y1076542D01*
X567415Y1076724D01*
X567274Y1076866D01*
X568005Y1077597D01*
X568147Y1077456D01*
G37*
G36*
G01X567963Y1077838D02*
X567781Y1078221D01*
X568311Y1078752D01*
X568695Y1078570D01*
X568836Y1078428D01*
X568104Y1077696D01*
X567963Y1077838D01*
G37*
G36*
G01X569809Y1079118D02*
X569991Y1078734D01*
X569460Y1078204D01*
X569077Y1078386D01*
X568935Y1078527D01*
X569667Y1079259D01*
X569809Y1079118D01*
G37*
G36*
G01X568960Y1079967D02*
X569142Y1079583D01*
X568611Y1079053D01*
X568228Y1079235D01*
X568086Y1079376D01*
X568818Y1080108D01*
X568960Y1079967D01*
G37*
G36*
G01X567298Y1078305D02*
X567480Y1077922D01*
X566950Y1077391D01*
X566566Y1077573D01*
X566425Y1077715D01*
X567157Y1078447D01*
X567298Y1078305D01*
G37*
G36*
G01X567114Y1078687D02*
X566932Y1079071D01*
X567462Y1079601D01*
X567846Y1079419D01*
X567987Y1079277D01*
X567256Y1078546D01*
X567114Y1078687D01*
G37*
G36*
G01X568996Y1076606D02*
X569178Y1076223D01*
X568648Y1075692D01*
X568264Y1075874D01*
X568123Y1076016D01*
X568855Y1076748D01*
X568996Y1076606D01*
G37*
G36*
G01X567334Y1074945D02*
X567517Y1074561D01*
X566986Y1074031D01*
X566603Y1074213D01*
X566461Y1074354D01*
X567193Y1075086D01*
X567334Y1074945D01*
G37*
G36*
G01X567151Y1075326D02*
X566969Y1075710D01*
X567499Y1076240D01*
X567883Y1076058D01*
X568024Y1075917D01*
X567292Y1075185D01*
X567151Y1075326D01*
G37*
G36*
G01X568812Y1076988D02*
X568630Y1077372D01*
X569161Y1077902D01*
X569544Y1077720D01*
X569686Y1077579D01*
X568954Y1076847D01*
X568812Y1076988D01*
G37*
G36*
G01X570658Y1078268D02*
X570840Y1077884D01*
X570310Y1077354D01*
X569926Y1077536D01*
X569785Y1077678D01*
X570516Y1078409D01*
X570658Y1078268D01*
G37*
G36*
G01X570474Y1078650D02*
X570292Y1079033D01*
X570822Y1079564D01*
X571206Y1079382D01*
X571347Y1079240D01*
X570615Y1078508D01*
X570474Y1078650D01*
G37*
G36*
G01X567149Y1072004D02*
X566967Y1072388D01*
X567497Y1072918D01*
X567881Y1072736D01*
X568022Y1072594D01*
X567291Y1071863D01*
X567149Y1072004D01*
G37*
G36*
G01X567333Y1071622D02*
X567515Y1071239D01*
X566985Y1070708D01*
X566601Y1070890D01*
X566460Y1071032D01*
X567192Y1071764D01*
X567333Y1071622D01*
G37*
G36*
G01X568995Y1073284D02*
X569177Y1072900D01*
X568646Y1072370D01*
X568263Y1072552D01*
X568121Y1072693D01*
X568853Y1073425D01*
X568995Y1073284D01*
G37*
G36*
G01X572134Y1076989D02*
X571952Y1077373D01*
X572483Y1077903D01*
X572866Y1077721D01*
X573008Y1077580D01*
X572276Y1076848D01*
X572134Y1076989D01*
G37*
G36*
G01X574485Y1080041D02*
X574849Y1079823D01*
X574702Y1079087D01*
X574282Y1079026D01*
X574086Y1079065D01*
X574289Y1080080D01*
X574485Y1080041D01*
G37*
G36*
G01X568811Y1073666D02*
X568629Y1074049D01*
X569159Y1074580D01*
X569543Y1074398D01*
X569684Y1074256D01*
X568952Y1073524D01*
X568811Y1073666D01*
G37*
G36*
G01X570656Y1074946D02*
X570839Y1074562D01*
X570308Y1074032D01*
X569925Y1074214D01*
X569783Y1074355D01*
X570515Y1075087D01*
X570656Y1074946D01*
G37*
G36*
G01X572318Y1076607D02*
X572500Y1076224D01*
X571970Y1075693D01*
X571586Y1075875D01*
X571445Y1076017D01*
X572177Y1076749D01*
X572318Y1076607D01*
G37*
G36*
G01X570473Y1075327D02*
X570290Y1075711D01*
X570821Y1076241D01*
X571204Y1076059D01*
X571346Y1075918D01*
X570614Y1075186D01*
X570473Y1075327D01*
G37*
G36*
G01X567369Y1068262D02*
X567551Y1067879D01*
X567021Y1067348D01*
X566637Y1067530D01*
X566496Y1067672D01*
X567228Y1068404D01*
X567369Y1068262D01*
G37*
G36*
G01X569031Y1069924D02*
X569213Y1069540D01*
X568682Y1069010D01*
X568299Y1069192D01*
X568157Y1069333D01*
X568889Y1070065D01*
X569031Y1069924D01*
G37*
G36*
G01X567185Y1068644D02*
X567003Y1069028D01*
X567533Y1069558D01*
X567917Y1069376D01*
X568058Y1069234D01*
X567327Y1068503D01*
X567185Y1068644D01*
G37*
G36*
G01X573832Y1075291D02*
X573650Y1075674D01*
X574180Y1076205D01*
X574564Y1076023D01*
X574705Y1075881D01*
X573973Y1075149D01*
X573832Y1075291D01*
G37*
G36*
G01X570692Y1071586D02*
X570875Y1071202D01*
X570344Y1070672D01*
X569961Y1070854D01*
X569819Y1070995D01*
X570551Y1071727D01*
X570692Y1071586D01*
G37*
G36*
G01X568847Y1070306D02*
X568665Y1070689D01*
X569195Y1071220D01*
X569579Y1071038D01*
X569720Y1070896D01*
X568988Y1070164D01*
X568847Y1070306D01*
G37*
G36*
G01X572354Y1073247D02*
X572536Y1072864D01*
X572006Y1072333D01*
X571622Y1072515D01*
X571481Y1072657D01*
X572213Y1073389D01*
X572354Y1073247D01*
G37*
G36*
G01X570509Y1071967D02*
X570327Y1072351D01*
X570857Y1072881D01*
X571240Y1072699D01*
X571382Y1072558D01*
X570650Y1071826D01*
X570509Y1071967D01*
G37*
G36*
G01X574016Y1074909D02*
X574198Y1074525D01*
X573668Y1073995D01*
X573284Y1074177D01*
X573143Y1074319D01*
X573874Y1075050D01*
X574016Y1074909D01*
G37*
G36*
G01X575678Y1076571D02*
X575860Y1076187D01*
X575329Y1075657D01*
X574946Y1075839D01*
X574804Y1075980D01*
X575536Y1076712D01*
X575678Y1076571D01*
G37*
G36*
G01X572170Y1073629D02*
X571988Y1074013D01*
X572519Y1074543D01*
X572902Y1074361D01*
X573044Y1074220D01*
X572312Y1073488D01*
X572170Y1073629D01*
G37*
G36*
G01X576840Y1079570D02*
X577204Y1079352D01*
X577057Y1078616D01*
X576637Y1078555D01*
X576441Y1078594D01*
X576644Y1079609D01*
X576840Y1079570D01*
G37*
G36*
G01X566336Y1069493D02*
X566154Y1069877D01*
X566685Y1070407D01*
X567068Y1070225D01*
X567210Y1070084D01*
X566478Y1069352D01*
X566336Y1069493D01*
G37*
G36*
G01X567998Y1071155D02*
X567816Y1071538D01*
X568346Y1072069D01*
X568730Y1071887D01*
X568871Y1071745D01*
X568139Y1071013D01*
X567998Y1071155D01*
G37*
G36*
G01X568182Y1070773D02*
X568364Y1070389D01*
X567834Y1069859D01*
X567450Y1070041D01*
X567309Y1070183D01*
X568040Y1070914D01*
X568182Y1070773D01*
G37*
G36*
G01X569844Y1072435D02*
X570026Y1072051D01*
X569495Y1071521D01*
X569112Y1071703D01*
X568970Y1071844D01*
X569702Y1072576D01*
X569844Y1072435D01*
G37*
G36*
G01X571505Y1074096D02*
X571687Y1073713D01*
X571157Y1073183D01*
X570773Y1073365D01*
X570632Y1073506D01*
X571364Y1074238D01*
X571505Y1074096D01*
G37*
G36*
G01X569660Y1072817D02*
X569478Y1073200D01*
X570008Y1073731D01*
X570392Y1073548D01*
X570533Y1073407D01*
X569801Y1072675D01*
X569660Y1072817D01*
G37*
G36*
G01X571321Y1074478D02*
X571139Y1074862D01*
X571670Y1075392D01*
X572053Y1075210D01*
X572195Y1075069D01*
X571463Y1074337D01*
X571321Y1074478D01*
G37*
G36*
G01X573167Y1075758D02*
X573349Y1075375D01*
X572819Y1074844D01*
X572435Y1075026D01*
X572294Y1075168D01*
X573026Y1075900D01*
X573167Y1075758D01*
G37*
G36*
G01X572983Y1076140D02*
X572801Y1076524D01*
X573331Y1077054D01*
X573715Y1076872D01*
X573856Y1076730D01*
X573125Y1075999D01*
X572983Y1076140D01*
G37*
G36*
G01X574829Y1077420D02*
X575011Y1077036D01*
X574480Y1076506D01*
X574097Y1076688D01*
X573955Y1076829D01*
X574687Y1077561D01*
X574829Y1077420D01*
G37*
G36*
G01X575662Y1079805D02*
X576027Y1079587D01*
X575879Y1078852D01*
X575459Y1078790D01*
X575263Y1078830D01*
X575466Y1079845D01*
X575662Y1079805D01*
G37*
G36*
G01X568034Y1067795D02*
X567852Y1068179D01*
X568382Y1068709D01*
X568766Y1068527D01*
X568907Y1068385D01*
X568175Y1067653D01*
X568034Y1067795D01*
G37*
G36*
G01X568218Y1067413D02*
X568400Y1067029D01*
X567870Y1066499D01*
X567486Y1066681D01*
X567345Y1066823D01*
X568076Y1067554D01*
X568218Y1067413D01*
G37*
G36*
G01X566556Y1065751D02*
X566738Y1065368D01*
X566208Y1064837D01*
X565824Y1065020D01*
X565683Y1065161D01*
X566415Y1065893D01*
X566556Y1065751D01*
G37*
G36*
G01X566372Y1066133D02*
X566190Y1066517D01*
X566721Y1067047D01*
X567104Y1066865D01*
X567246Y1066724D01*
X566514Y1065992D01*
X566372Y1066133D01*
G37*
G36*
G01X571357Y1071118D02*
X571175Y1071502D01*
X571706Y1072032D01*
X572089Y1071850D01*
X572231Y1071709D01*
X571499Y1070977D01*
X571357Y1071118D01*
G37*
G36*
G01X571541Y1070736D02*
X571723Y1070353D01*
X571193Y1069823D01*
X570809Y1070005D01*
X570668Y1070146D01*
X571400Y1070878D01*
X571541Y1070736D01*
G37*
G36*
G01X569696Y1069457D02*
X569514Y1069840D01*
X570044Y1070371D01*
X570428Y1070188D01*
X570569Y1070047D01*
X569837Y1069315D01*
X569696Y1069457D01*
G37*
G36*
G01X573203Y1072398D02*
X573385Y1072015D01*
X572855Y1071484D01*
X572471Y1071666D01*
X572330Y1071808D01*
X573062Y1072540D01*
X573203Y1072398D01*
G37*
G36*
G01X569880Y1069075D02*
X570062Y1068691D01*
X569531Y1068161D01*
X569148Y1068343D01*
X569006Y1068484D01*
X569738Y1069216D01*
X569880Y1069075D01*
G37*
G36*
G01X574865Y1074060D02*
X575047Y1073676D01*
X574516Y1073146D01*
X574133Y1073328D01*
X573991Y1073469D01*
X574723Y1074201D01*
X574865Y1074060D01*
G37*
G36*
G01X573019Y1072780D02*
X572837Y1073164D01*
X573367Y1073694D01*
X573751Y1073512D01*
X573892Y1073370D01*
X573161Y1072639D01*
X573019Y1072780D01*
G37*
G36*
G01X574681Y1074442D02*
X574499Y1074825D01*
X575029Y1075356D01*
X575413Y1075174D01*
X575554Y1075032D01*
X574822Y1074300D01*
X574681Y1074442D01*
G37*
G36*
G01X578019Y1079334D02*
X578383Y1079116D01*
X578236Y1078380D01*
X577815Y1078319D01*
X577619Y1078358D01*
X577822Y1079373D01*
X578019Y1079334D01*
G37*
G36*
G01X576526Y1075722D02*
X576708Y1075338D01*
X576178Y1074808D01*
X575795Y1074990D01*
X575653Y1075131D01*
X576385Y1075863D01*
X576526Y1075722D01*
G37*
G36*
G01X574485Y1065609D02*
X574303Y1065993D01*
X574833Y1066523D01*
X575217Y1066341D01*
X575358Y1066200D01*
X574626Y1065468D01*
X574485Y1065609D01*
G37*
G36*
G01X574669Y1065228D02*
X574851Y1064844D01*
X574320Y1064314D01*
X573937Y1064496D01*
X573795Y1064637D01*
X574527Y1065369D01*
X574669Y1065228D01*
G37*
G36*
G01X572823Y1063948D02*
X572641Y1064331D01*
X573171Y1064862D01*
X573555Y1064680D01*
X573696Y1064538D01*
X572964Y1063806D01*
X572823Y1063948D01*
G37*
G36*
G01X577992Y1068551D02*
X578174Y1068167D01*
X577644Y1067637D01*
X577260Y1067819D01*
X577119Y1067961D01*
X577850Y1068692D01*
X577992Y1068551D01*
G37*
G36*
G01X576330Y1066889D02*
X576512Y1066506D01*
X575982Y1065975D01*
X575598Y1066158D01*
X575457Y1066299D01*
X576189Y1067031D01*
X576330Y1066889D01*
G37*
G36*
G01X576146Y1067271D02*
X575964Y1067655D01*
X576495Y1068185D01*
X576878Y1068003D01*
X577020Y1067862D01*
X576288Y1067130D01*
X576146Y1067271D01*
G37*
G36*
G01X579654Y1070213D02*
X579836Y1069829D01*
X579305Y1069299D01*
X578922Y1069481D01*
X578780Y1069622D01*
X579512Y1070354D01*
X579654Y1070213D01*
G37*
G36*
G01X579470Y1070595D02*
X579288Y1070978D01*
X579818Y1071509D01*
X580202Y1071326D01*
X580343Y1071185D01*
X579611Y1070453D01*
X579470Y1070595D01*
G37*
G36*
G01X577808Y1068933D02*
X577626Y1069317D01*
X578156Y1069847D01*
X578540Y1069665D01*
X578681Y1069523D01*
X577949Y1068791D01*
X577808Y1068933D01*
G37*
G36*
G01X581315Y1071874D02*
X581497Y1071491D01*
X580967Y1070961D01*
X580583Y1071143D01*
X580442Y1071284D01*
X581174Y1072016D01*
X581315Y1071874D01*
G37*
G36*
G01X581131Y1072256D02*
X580949Y1072640D01*
X581480Y1073170D01*
X581863Y1072988D01*
X582005Y1072847D01*
X581273Y1072115D01*
X581131Y1072256D01*
G37*
G36*
G01X578029Y1065191D02*
X578211Y1064807D01*
X577680Y1064277D01*
X577297Y1064459D01*
X577155Y1064600D01*
X577887Y1065332D01*
X578029Y1065191D01*
G37*
G36*
G01X576183Y1063911D02*
X576001Y1064295D01*
X576531Y1064825D01*
X576915Y1064643D01*
X577056Y1064501D01*
X576325Y1063770D01*
X576183Y1063911D01*
G37*
G36*
G01X579690Y1066853D02*
X579872Y1066469D01*
X579342Y1065939D01*
X578959Y1066121D01*
X578817Y1066262D01*
X579549Y1066994D01*
X579690Y1066853D01*
G37*
G36*
G01X577845Y1065573D02*
X577663Y1065956D01*
X578193Y1066487D01*
X578577Y1066305D01*
X578718Y1066163D01*
X577986Y1065431D01*
X577845Y1065573D01*
G37*
G36*
G01X579507Y1067234D02*
X579324Y1067618D01*
X579855Y1068148D01*
X580238Y1067966D01*
X580380Y1067825D01*
X579648Y1067093D01*
X579507Y1067234D01*
G37*
G36*
G01X581352Y1068514D02*
X581534Y1068131D01*
X581004Y1067600D01*
X580620Y1067782D01*
X580479Y1067924D01*
X581211Y1068656D01*
X581352Y1068514D01*
G37*
G36*
G01X581168Y1068896D02*
X580986Y1069280D01*
X581517Y1069810D01*
X581900Y1069628D01*
X582042Y1069487D01*
X581310Y1068755D01*
X581168Y1068896D01*
G37*
G36*
G01X575518Y1064379D02*
X575700Y1063995D01*
X575169Y1063465D01*
X574786Y1063647D01*
X574644Y1063788D01*
X575376Y1064520D01*
X575518Y1064379D01*
G37*
G36*
G01X575334Y1064760D02*
X575152Y1065144D01*
X575682Y1065674D01*
X576066Y1065492D01*
X576207Y1065351D01*
X575475Y1064619D01*
X575334Y1064760D01*
G37*
G36*
G01X577179Y1066040D02*
X577361Y1065657D01*
X576831Y1065126D01*
X576447Y1065309D01*
X576306Y1065450D01*
X577038Y1066182D01*
X577179Y1066040D01*
G37*
G36*
G01X576995Y1066422D02*
X576813Y1066806D01*
X577344Y1067336D01*
X577727Y1067154D01*
X577869Y1067013D01*
X577137Y1066281D01*
X576995Y1066422D01*
G37*
G36*
G01X578841Y1067702D02*
X579023Y1067318D01*
X578493Y1066788D01*
X578109Y1066970D01*
X577968Y1067112D01*
X578699Y1067843D01*
X578841Y1067702D01*
G37*
G36*
G01X578657Y1068084D02*
X578475Y1068468D01*
X579005Y1068998D01*
X579389Y1068816D01*
X579530Y1068674D01*
X578798Y1067942D01*
X578657Y1068084D01*
G37*
G36*
G01X581980Y1071407D02*
X581798Y1071791D01*
X582329Y1072321D01*
X582712Y1072139D01*
X582854Y1071998D01*
X582122Y1071266D01*
X581980Y1071407D01*
G37*
G36*
G01X582164Y1071025D02*
X582346Y1070642D01*
X581816Y1070112D01*
X581432Y1070294D01*
X581291Y1070435D01*
X582023Y1071167D01*
X582164Y1071025D01*
G37*
G36*
G01X580319Y1069746D02*
X580137Y1070129D01*
X580667Y1070660D01*
X581051Y1070477D01*
X581192Y1070336D01*
X580460Y1069604D01*
X580319Y1069746D01*
G37*
G36*
G01X580503Y1069364D02*
X580685Y1068980D01*
X580154Y1068450D01*
X579771Y1068632D01*
X579629Y1068773D01*
X580361Y1069505D01*
X580503Y1069364D01*
G37*
G36*
G01X578878Y1064341D02*
X579060Y1063958D01*
X578530Y1063427D01*
X578146Y1063610D01*
X578005Y1063751D01*
X578737Y1064483D01*
X578878Y1064341D01*
G37*
G36*
G01X580540Y1066003D02*
X580722Y1065619D01*
X580192Y1065089D01*
X579808Y1065271D01*
X579667Y1065413D01*
X580398Y1066144D01*
X580540Y1066003D01*
G37*
G36*
G01X582202Y1067665D02*
X582384Y1067281D01*
X581853Y1066751D01*
X581470Y1066933D01*
X581328Y1067074D01*
X582060Y1067806D01*
X582202Y1067665D01*
G37*
G36*
G01X578694Y1064723D02*
X578512Y1065107D01*
X579043Y1065637D01*
X579426Y1065455D01*
X579568Y1065314D01*
X578836Y1064582D01*
X578694Y1064723D01*
G37*
G36*
G01X580356Y1066385D02*
X580174Y1066769D01*
X580704Y1067299D01*
X581088Y1067117D01*
X581229Y1066975D01*
X580497Y1066243D01*
X580356Y1066385D01*
G37*
G36*
G01X582018Y1068047D02*
X581836Y1068430D01*
X582366Y1068961D01*
X582750Y1068778D01*
X582891Y1068637D01*
X582159Y1067905D01*
X582018Y1068047D01*
G37*
G36*
G01X568111Y1080816D02*
X568293Y1080433D01*
X567762Y1079902D01*
X567379Y1080084D01*
X567237Y1080226D01*
X567969Y1080958D01*
X568111Y1080816D01*
G37*
G36*
G01X569253Y1083615D02*
X569617Y1083397D01*
X569470Y1082661D01*
X569050Y1082600D01*
X568854Y1082639D01*
X569057Y1083654D01*
X569253Y1083615D01*
G37*
G36*
G01X568888Y1083831D02*
X568524Y1084049D01*
X568671Y1084784D01*
X569091Y1084846D01*
X569287Y1084806D01*
X569084Y1083792D01*
X568888Y1083831D01*
G37*
G36*
G01X571191Y1095353D02*
X570826Y1095571D01*
X570973Y1096307D01*
X571394Y1096368D01*
X571590Y1096329D01*
X571387Y1095314D01*
X571191Y1095353D01*
G37*
G36*
G01X570730Y1093048D02*
X570366Y1093267D01*
X570513Y1094002D01*
X570933Y1094063D01*
X571129Y1094024D01*
X570926Y1093009D01*
X570730Y1093048D01*
G37*
G36*
G01X571556Y1095137D02*
X571920Y1094919D01*
X571773Y1094184D01*
X571353Y1094122D01*
X571157Y1094161D01*
X571359Y1095176D01*
X571556Y1095137D01*
G37*
G36*
G01X571095Y1092833D02*
X571459Y1092615D01*
X571312Y1091879D01*
X570892Y1091818D01*
X570696Y1091857D01*
X570899Y1092872D01*
X571095Y1092833D01*
G37*
G36*
G01X569349Y1086135D02*
X568984Y1086353D01*
X569131Y1087089D01*
X569552Y1087150D01*
X569748Y1087111D01*
X569545Y1086096D01*
X569349Y1086135D01*
G37*
G36*
G01X569809Y1088440D02*
X569445Y1088658D01*
X569592Y1089393D01*
X570012Y1089455D01*
X570208Y1089415D01*
X570005Y1088400D01*
X569809Y1088440D01*
G37*
G36*
G01X570270Y1090744D02*
X569905Y1090962D01*
X570052Y1091698D01*
X570473Y1091759D01*
X570669Y1091720D01*
X570466Y1090705D01*
X570270Y1090744D01*
G37*
G36*
G01X570635Y1090528D02*
X570999Y1090310D01*
X570852Y1089575D01*
X570432Y1089513D01*
X570236Y1089553D01*
X570438Y1090568D01*
X570635Y1090528D01*
G37*
G36*
G01X570174Y1088224D02*
X570538Y1088006D01*
X570391Y1087270D01*
X569971Y1087209D01*
X569775Y1087248D01*
X569978Y1088263D01*
X570174Y1088224D01*
G37*
G36*
G01X569714Y1085919D02*
X570078Y1085701D01*
X569931Y1084966D01*
X569511Y1084905D01*
X569315Y1084944D01*
X569517Y1085959D01*
X569714Y1085919D01*
G37*
G36*
G01X572070Y1085448D02*
X572434Y1085230D01*
X572287Y1084494D01*
X571867Y1084433D01*
X571671Y1084472D01*
X571874Y1085487D01*
X572070Y1085448D01*
G37*
G36*
G01X571244Y1083360D02*
X570880Y1083578D01*
X571027Y1084313D01*
X571447Y1084374D01*
X571643Y1084335D01*
X571440Y1083320D01*
X571244Y1083360D01*
G37*
G36*
G01X570783Y1081055D02*
X570419Y1081273D01*
X570566Y1082009D01*
X570986Y1082070D01*
X571182Y1082031D01*
X570979Y1081016D01*
X570783Y1081055D01*
G37*
G36*
G01X571609Y1083144D02*
X571973Y1082926D01*
X571826Y1082190D01*
X571406Y1082129D01*
X571210Y1082168D01*
X571413Y1083183D01*
X571609Y1083144D01*
G37*
G36*
G01X573549Y1094881D02*
X573185Y1095099D01*
X573332Y1095835D01*
X573752Y1095896D01*
X573948Y1095857D01*
X573745Y1094842D01*
X573549Y1094881D01*
G37*
G36*
G01X573914Y1094665D02*
X574278Y1094447D01*
X574131Y1093712D01*
X573711Y1093651D01*
X573515Y1093690D01*
X573718Y1094705D01*
X573914Y1094665D01*
G37*
G36*
G01X573088Y1092577D02*
X572724Y1092795D01*
X572871Y1093530D01*
X573291Y1093592D01*
X573487Y1093553D01*
X573284Y1092538D01*
X573088Y1092577D01*
G37*
G36*
G01X572166Y1087968D02*
X571802Y1088186D01*
X571949Y1088922D01*
X572369Y1088983D01*
X572565Y1088944D01*
X572362Y1087929D01*
X572166Y1087968D01*
G37*
G36*
G01X571705Y1085664D02*
X571341Y1085882D01*
X571488Y1086617D01*
X571908Y1086679D01*
X572104Y1086640D01*
X571901Y1085625D01*
X571705Y1085664D01*
G37*
G36*
G01X572627Y1090273D02*
X572263Y1090491D01*
X572410Y1091226D01*
X572830Y1091287D01*
X573026Y1091248D01*
X572823Y1090233D01*
X572627Y1090273D01*
G37*
G36*
G01X573453Y1092361D02*
X573817Y1092143D01*
X573670Y1091408D01*
X573250Y1091346D01*
X573054Y1091385D01*
X573257Y1092400D01*
X573453Y1092361D01*
G37*
G36*
G01X572992Y1090057D02*
X573356Y1089839D01*
X573209Y1089103D01*
X572789Y1089042D01*
X572593Y1089081D01*
X572796Y1090096D01*
X572992Y1090057D01*
G37*
G36*
G01X572531Y1087752D02*
X572895Y1087534D01*
X572748Y1086799D01*
X572328Y1086738D01*
X572132Y1086777D01*
X572335Y1087792D01*
X572531Y1087752D01*
G37*
G36*
G01X570892Y1085684D02*
X571256Y1085466D01*
X571109Y1084730D01*
X570688Y1084669D01*
X570492Y1084708D01*
X570695Y1085723D01*
X570892Y1085684D01*
G37*
G36*
G01X570066Y1083595D02*
X569702Y1083813D01*
X569849Y1084549D01*
X570269Y1084610D01*
X570465Y1084571D01*
X570262Y1083556D01*
X570066Y1083595D01*
G37*
G36*
G01X570431Y1083379D02*
X570795Y1083161D01*
X570648Y1082426D01*
X570228Y1082365D01*
X570032Y1082404D01*
X570235Y1083419D01*
X570431Y1083379D01*
G37*
G36*
G01X571352Y1087988D02*
X571717Y1087770D01*
X571570Y1087035D01*
X571149Y1086973D01*
X570953Y1087013D01*
X571156Y1088027D01*
X571352Y1087988D01*
G37*
G36*
G01X571909Y1092813D02*
X571545Y1093031D01*
X571692Y1093766D01*
X572112Y1093828D01*
X572308Y1093788D01*
X572105Y1092773D01*
X571909Y1092813D01*
G37*
G36*
G01X572735Y1094901D02*
X573099Y1094683D01*
X572952Y1093948D01*
X572532Y1093886D01*
X572336Y1093926D01*
X572539Y1094941D01*
X572735Y1094901D01*
G37*
G36*
G01X572370Y1095117D02*
X572006Y1095335D01*
X572153Y1096071D01*
X572573Y1096132D01*
X572769Y1096093D01*
X572566Y1095078D01*
X572370Y1095117D01*
G37*
G36*
G01X572274Y1092597D02*
X572638Y1092379D01*
X572491Y1091643D01*
X572071Y1091582D01*
X571875Y1091621D01*
X572078Y1092636D01*
X572274Y1092597D01*
G37*
G36*
G01X570988Y1088204D02*
X570623Y1088422D01*
X570770Y1089158D01*
X571191Y1089219D01*
X571387Y1089180D01*
X571184Y1088165D01*
X570988Y1088204D01*
G37*
G36*
G01X570527Y1085900D02*
X570162Y1086118D01*
X570309Y1086853D01*
X570730Y1086914D01*
X570926Y1086875D01*
X570723Y1085860D01*
X570527Y1085900D01*
G37*
G36*
G01X571448Y1090508D02*
X571084Y1090726D01*
X571231Y1091462D01*
X571651Y1091523D01*
X571847Y1091484D01*
X571645Y1090469D01*
X571448Y1090508D01*
G37*
G36*
G01X571813Y1090293D02*
X572177Y1090074D01*
X572030Y1089339D01*
X571610Y1089278D01*
X571414Y1089317D01*
X571617Y1090332D01*
X571813Y1090293D01*
G37*
G36*
G01X573248Y1085212D02*
X573612Y1084994D01*
X573465Y1084259D01*
X573045Y1084198D01*
X572849Y1084237D01*
X573052Y1085252D01*
X573248Y1085212D01*
G37*
G36*
G01X572787Y1082908D02*
X573151Y1082690D01*
X573004Y1081954D01*
X572584Y1081893D01*
X572388Y1081932D01*
X572591Y1082947D01*
X572787Y1082908D01*
G37*
G36*
G01X571961Y1080819D02*
X571597Y1081038D01*
X571744Y1081773D01*
X572164Y1081834D01*
X572360Y1081795D01*
X572157Y1080780D01*
X571961Y1080819D01*
G37*
G36*
G01X572422Y1083124D02*
X572058Y1083342D01*
X572205Y1084077D01*
X572625Y1084139D01*
X572821Y1084100D01*
X572618Y1083085D01*
X572422Y1083124D01*
G37*
G36*
G01X575092Y1094430D02*
X575456Y1094212D01*
X575309Y1093476D01*
X574889Y1093415D01*
X574692Y1093454D01*
X574895Y1094469D01*
X575092Y1094430D01*
G37*
G36*
G01X574727Y1094646D02*
X574363Y1094864D01*
X574510Y1095599D01*
X574930Y1095661D01*
X575126Y1095621D01*
X574923Y1094606D01*
X574727Y1094646D01*
G37*
G36*
G01X574266Y1092341D02*
X573902Y1092559D01*
X574049Y1093295D01*
X574469Y1093356D01*
X574665Y1093317D01*
X574462Y1092302D01*
X574266Y1092341D01*
G37*
G36*
G01X574170Y1089821D02*
X574534Y1089603D01*
X574387Y1088868D01*
X573967Y1088806D01*
X573771Y1088846D01*
X573974Y1089860D01*
X574170Y1089821D01*
G37*
G36*
G01X573709Y1087517D02*
X574073Y1087299D01*
X573926Y1086563D01*
X573506Y1086502D01*
X573310Y1086541D01*
X573513Y1087556D01*
X573709Y1087517D01*
G37*
G36*
G01X574631Y1092126D02*
X574995Y1091907D01*
X574848Y1091172D01*
X574428Y1091111D01*
X574232Y1091150D01*
X574435Y1092165D01*
X574631Y1092126D01*
G37*
G36*
G01X573344Y1087733D02*
X572980Y1087951D01*
X573127Y1088686D01*
X573547Y1088747D01*
X573743Y1088708D01*
X573540Y1087693D01*
X573344Y1087733D01*
G37*
G36*
G01X572883Y1085428D02*
X572519Y1085646D01*
X572666Y1086382D01*
X573086Y1086443D01*
X573282Y1086404D01*
X573079Y1085389D01*
X572883Y1085428D01*
G37*
G36*
G01X573805Y1090037D02*
X573441Y1090255D01*
X573588Y1090991D01*
X574008Y1091052D01*
X574204Y1091013D01*
X574001Y1089998D01*
X573805Y1090037D01*
G37*
G36*
G01X575553Y1096734D02*
X575917Y1096516D01*
X575770Y1095781D01*
X575350Y1095719D01*
X575153Y1095759D01*
X575356Y1096773D01*
X575553Y1096734D01*
G37*
G36*
G01X574581Y1082561D02*
X574217Y1082779D01*
X574364Y1083515D01*
X574784Y1083576D01*
X574980Y1083537D01*
X574777Y1082522D01*
X574581Y1082561D01*
G37*
G36*
G01X574120Y1080257D02*
X573756Y1080475D01*
X573903Y1081210D01*
X574323Y1081271D01*
X574519Y1081232D01*
X574316Y1080217D01*
X574120Y1080257D01*
G37*
G36*
G01X574946Y1082345D02*
X575310Y1082127D01*
X575163Y1081392D01*
X574743Y1081330D01*
X574547Y1081370D01*
X574750Y1082384D01*
X574946Y1082345D01*
G37*
G36*
G01X575407Y1084650D02*
X575771Y1084431D01*
X575624Y1083696D01*
X575204Y1083635D01*
X575008Y1083674D01*
X575211Y1084689D01*
X575407Y1084650D01*
G37*
G36*
G01X575503Y1087170D02*
X575139Y1087388D01*
X575286Y1088123D01*
X575706Y1088185D01*
X575902Y1088145D01*
X575699Y1087130D01*
X575503Y1087170D01*
G37*
G36*
G01X575042Y1084865D02*
X574678Y1085083D01*
X574825Y1085819D01*
X575245Y1085880D01*
X575441Y1085841D01*
X575238Y1084826D01*
X575042Y1084865D01*
G37*
G36*
G01X577711Y1096171D02*
X578076Y1095953D01*
X577929Y1095218D01*
X577508Y1095156D01*
X577312Y1095196D01*
X577515Y1096211D01*
X577711Y1096171D01*
G37*
G36*
G01X576886Y1094083D02*
X576521Y1094301D01*
X576669Y1095036D01*
X577089Y1095098D01*
X577285Y1095058D01*
X577082Y1094043D01*
X576886Y1094083D01*
G37*
G36*
G01X577251Y1093867D02*
X577615Y1093649D01*
X577468Y1092913D01*
X577048Y1092852D01*
X576851Y1092891D01*
X577054Y1093906D01*
X577251Y1093867D01*
G37*
G36*
G01X576425Y1091778D02*
X576061Y1091997D01*
X576208Y1092732D01*
X576628Y1092793D01*
X576824Y1092754D01*
X576621Y1091739D01*
X576425Y1091778D01*
G37*
G36*
G01X575964Y1089474D02*
X575600Y1089692D01*
X575747Y1090428D01*
X576167Y1090489D01*
X576363Y1090450D01*
X576160Y1089435D01*
X575964Y1089474D01*
G37*
G36*
G01X576790Y1091563D02*
X577154Y1091344D01*
X577007Y1090609D01*
X576587Y1090548D01*
X576390Y1090587D01*
X576594Y1091602D01*
X576790Y1091563D01*
G37*
G36*
G01X576329Y1089258D02*
X576693Y1089040D01*
X576546Y1088305D01*
X576126Y1088243D01*
X575930Y1088283D01*
X576133Y1089297D01*
X576329Y1089258D01*
G37*
G36*
G01X575868Y1086954D02*
X576232Y1086736D01*
X576085Y1086000D01*
X575665Y1085939D01*
X575469Y1085978D01*
X575672Y1086993D01*
X575868Y1086954D01*
G37*
G36*
G01X577397Y1084394D02*
X577033Y1084612D01*
X577180Y1085348D01*
X577600Y1085409D01*
X577797Y1085370D01*
X577593Y1084355D01*
X577397Y1084394D01*
G37*
G36*
G01X577301Y1081874D02*
X577665Y1081656D01*
X577518Y1080920D01*
X577098Y1080859D01*
X576902Y1080898D01*
X577105Y1081913D01*
X577301Y1081874D01*
G37*
G36*
G01X576936Y1082090D02*
X576572Y1082308D01*
X576719Y1083044D01*
X577139Y1083105D01*
X577335Y1083066D01*
X577132Y1082051D01*
X576936Y1082090D01*
G37*
G36*
G01X576475Y1079786D02*
X576111Y1080004D01*
X576258Y1080739D01*
X576678Y1080800D01*
X576874Y1080761D01*
X576671Y1079746D01*
X576475Y1079786D01*
G37*
G36*
G01X577762Y1084178D02*
X578126Y1083960D01*
X577979Y1083225D01*
X577559Y1083164D01*
X577363Y1083203D01*
X577566Y1084218D01*
X577762Y1084178D01*
G37*
G36*
G01X577859Y1086698D02*
X577494Y1086917D01*
X577641Y1087652D01*
X578062Y1087713D01*
X578258Y1087674D01*
X578055Y1086659D01*
X577859Y1086698D01*
G37*
G36*
G01X579146Y1091091D02*
X579510Y1090873D01*
X579363Y1090138D01*
X578942Y1090076D01*
X578746Y1090116D01*
X578949Y1091131D01*
X579146Y1091091D01*
G37*
G36*
G01X578684Y1088787D02*
X579049Y1088569D01*
X578902Y1087833D01*
X578481Y1087772D01*
X578285Y1087811D01*
X578488Y1088826D01*
X578684Y1088787D01*
G37*
G36*
G01X578223Y1086483D02*
X578587Y1086265D01*
X578440Y1085529D01*
X578020Y1085468D01*
X577824Y1085507D01*
X578027Y1086522D01*
X578223Y1086483D01*
G37*
G36*
G01X578781Y1091307D02*
X578417Y1091525D01*
X578564Y1092261D01*
X578984Y1092322D01*
X579180Y1092283D01*
X578977Y1091268D01*
X578781Y1091307D01*
G37*
G36*
G01X578320Y1089003D02*
X577955Y1089221D01*
X578103Y1089956D01*
X578523Y1090018D01*
X578719Y1089978D01*
X578516Y1088964D01*
X578320Y1089003D01*
G37*
G36*
G01X580068Y1095700D02*
X580432Y1095482D01*
X580285Y1094746D01*
X579865Y1094685D01*
X579669Y1094724D01*
X579872Y1095739D01*
X580068Y1095700D01*
G37*
G36*
G01X579242Y1093611D02*
X578878Y1093830D01*
X579025Y1094565D01*
X579445Y1094626D01*
X579641Y1094587D01*
X579438Y1093572D01*
X579242Y1093611D01*
G37*
G36*
G01X579607Y1093396D02*
X579971Y1093177D01*
X579824Y1092442D01*
X579404Y1092381D01*
X579208Y1092420D01*
X579411Y1093435D01*
X579607Y1093396D01*
G37*
G36*
G01X575298Y1080021D02*
X574933Y1080239D01*
X575080Y1080975D01*
X575501Y1081036D01*
X575697Y1080997D01*
X575494Y1079982D01*
X575298Y1080021D01*
G37*
G36*
G01X576219Y1084630D02*
X575855Y1084848D01*
X576002Y1085583D01*
X576422Y1085645D01*
X576619Y1085605D01*
X576416Y1084591D01*
X576219Y1084630D01*
G37*
G36*
G01X576123Y1082110D02*
X576488Y1081891D01*
X576340Y1081156D01*
X575920Y1081095D01*
X575724Y1081134D01*
X575927Y1082149D01*
X576123Y1082110D01*
G37*
G36*
G01X575758Y1082325D02*
X575394Y1082544D01*
X575541Y1083279D01*
X575961Y1083340D01*
X576158Y1083301D01*
X575955Y1082286D01*
X575758Y1082325D01*
G37*
G36*
G01X576584Y1084414D02*
X576948Y1084196D01*
X576801Y1083460D01*
X576381Y1083399D01*
X576185Y1083438D01*
X576388Y1084453D01*
X576584Y1084414D01*
G37*
G36*
G01X577967Y1091327D02*
X578331Y1091109D01*
X578184Y1090373D01*
X577764Y1090312D01*
X577568Y1090351D01*
X577771Y1091366D01*
X577967Y1091327D01*
G37*
G36*
G01X577506Y1089023D02*
X577870Y1088804D01*
X577723Y1088069D01*
X577303Y1088008D01*
X577107Y1088047D01*
X577310Y1089062D01*
X577506Y1089023D01*
G37*
G36*
G01X577045Y1086718D02*
X577409Y1086500D01*
X577262Y1085765D01*
X576842Y1085703D01*
X576646Y1085743D01*
X576849Y1086758D01*
X577045Y1086718D01*
G37*
G36*
G01X577602Y1091543D02*
X577238Y1091761D01*
X577385Y1092496D01*
X577805Y1092558D01*
X578001Y1092518D01*
X577798Y1091504D01*
X577602Y1091543D01*
G37*
G36*
G01X577141Y1089238D02*
X576777Y1089457D01*
X576924Y1090192D01*
X577344Y1090253D01*
X577540Y1090214D01*
X577337Y1089199D01*
X577141Y1089238D01*
G37*
G36*
G01X576680Y1086934D02*
X576316Y1087152D01*
X576463Y1087888D01*
X576883Y1087949D01*
X577079Y1087910D01*
X576876Y1086895D01*
X576680Y1086934D01*
G37*
G36*
G01X578889Y1095936D02*
X579253Y1095718D01*
X579106Y1094982D01*
X578686Y1094921D01*
X578490Y1094960D01*
X578693Y1095975D01*
X578889Y1095936D01*
G37*
G36*
G01X578428Y1093631D02*
X578792Y1093413D01*
X578645Y1092678D01*
X578225Y1092617D01*
X578029Y1092656D01*
X578232Y1093671D01*
X578428Y1093631D01*
G37*
G36*
G01X578063Y1093847D02*
X577699Y1094065D01*
X577846Y1094801D01*
X578266Y1094862D01*
X578462Y1094823D01*
X578259Y1093808D01*
X578063Y1093847D01*
G37*
G36*
G01X578576Y1084158D02*
X578212Y1084377D01*
X578359Y1085112D01*
X578779Y1085173D01*
X578975Y1085134D01*
X578772Y1084119D01*
X578576Y1084158D01*
G37*
G36*
G01X577654Y1079550D02*
X577290Y1079768D01*
X577437Y1080503D01*
X577857Y1080565D01*
X578053Y1080525D01*
X577850Y1079511D01*
X577654Y1079550D01*
G37*
G36*
G01X578480Y1081638D02*
X578844Y1081420D01*
X578697Y1080685D01*
X578277Y1080623D01*
X578080Y1080663D01*
X578283Y1081678D01*
X578480Y1081638D01*
G37*
G36*
G01X578115Y1081854D02*
X577751Y1082072D01*
X577898Y1082808D01*
X578318Y1082869D01*
X578514Y1082830D01*
X578311Y1081815D01*
X578115Y1081854D01*
G37*
G36*
G01X578941Y1083943D02*
X579305Y1083725D01*
X579158Y1082989D01*
X578738Y1082928D01*
X578541Y1082967D01*
X578744Y1083982D01*
X578941Y1083943D01*
G37*
G36*
G01X580881Y1095680D02*
X580517Y1095898D01*
X580664Y1096634D01*
X581084Y1096695D01*
X581280Y1096656D01*
X581077Y1095641D01*
X580881Y1095680D01*
G37*
G36*
G01X581246Y1095464D02*
X581610Y1095246D01*
X581463Y1094511D01*
X581043Y1094449D01*
X580846Y1094489D01*
X581050Y1095504D01*
X581246Y1095464D01*
G37*
G36*
G01X580420Y1093376D02*
X580056Y1093594D01*
X580203Y1094329D01*
X580623Y1094391D01*
X580819Y1094351D01*
X580616Y1093337D01*
X580420Y1093376D01*
G37*
G36*
G01X580785Y1093160D02*
X581149Y1092942D01*
X581002Y1092206D01*
X580582Y1092145D01*
X580385Y1092184D01*
X580589Y1093199D01*
X580785Y1093160D01*
G37*
G36*
G01X580324Y1090856D02*
X580688Y1090638D01*
X580541Y1089902D01*
X580121Y1089841D01*
X579924Y1089880D01*
X580127Y1090895D01*
X580324Y1090856D01*
G37*
G36*
G01X579863Y1088551D02*
X580227Y1088333D01*
X580080Y1087598D01*
X579660Y1087536D01*
X579463Y1087576D01*
X579666Y1088591D01*
X579863Y1088551D01*
G37*
G36*
G01X579402Y1086247D02*
X579766Y1086029D01*
X579619Y1085293D01*
X579199Y1085232D01*
X579002Y1085271D01*
X579205Y1086286D01*
X579402Y1086247D01*
G37*
G36*
G01X579959Y1091071D02*
X579595Y1091290D01*
X579742Y1092025D01*
X580162Y1092086D01*
X580358Y1092047D01*
X580155Y1091032D01*
X579959Y1091071D01*
G37*
G36*
G01X579498Y1088767D02*
X579134Y1088985D01*
X579281Y1089721D01*
X579701Y1089782D01*
X579897Y1089743D01*
X579694Y1088728D01*
X579498Y1088767D01*
G37*
G36*
G01X579037Y1086463D02*
X578673Y1086681D01*
X578820Y1087416D01*
X579240Y1087478D01*
X579436Y1087438D01*
X579233Y1086424D01*
X579037Y1086463D01*
G37*
G36*
G01X565925Y1108080D02*
X566325Y1107937D01*
Y1107187D01*
X565925Y1107045D01*
X565725D01*
Y1108080D01*
X565925D01*
G37*
G36*
G01Y1110430D02*
X566325Y1110287D01*
Y1109537D01*
X565925Y1109395D01*
X565725D01*
Y1110430D01*
X565925D01*
G37*
G36*
G01Y1112780D02*
X566325Y1112637D01*
Y1111887D01*
X565925Y1111745D01*
X565725D01*
Y1112780D01*
X565925D01*
G37*
G36*
G01X566436Y1100482D02*
X566801Y1100264D01*
X566654Y1099529D01*
X566234Y1099468D01*
X566038Y1099507D01*
X566240Y1100522D01*
X566436Y1100482D01*
G37*
G36*
G01X566072Y1100698D02*
X565707Y1100916D01*
X565854Y1101652D01*
X566274Y1101713D01*
X566470Y1101674D01*
X566268Y1100659D01*
X566072Y1100698D01*
G37*
G36*
G01X566725Y1108219D02*
X566325Y1108362D01*
Y1109112D01*
X566725Y1109255D01*
X566925D01*
Y1108219D01*
X566725D01*
G37*
G36*
G01X567125Y1108080D02*
X567525Y1107937D01*
Y1107187D01*
X567125Y1107045D01*
X566925D01*
Y1108080D01*
X567125D01*
G37*
G36*
G01X566725Y1105869D02*
X566325Y1106012D01*
Y1106762D01*
X566725Y1106905D01*
X566925D01*
Y1105869D01*
X566725D01*
G37*
G36*
G01X566897Y1102787D02*
X567261Y1102569D01*
X567114Y1101833D01*
X566694Y1101772D01*
X566498Y1101811D01*
X566701Y1102826D01*
X566897Y1102787D01*
G37*
G36*
G01X566725Y1110569D02*
X566325Y1110712D01*
Y1111462D01*
X566725Y1111605D01*
X566925D01*
Y1110569D01*
X566725D01*
G37*
G36*
G01X567125Y1110430D02*
X567525Y1110287D01*
Y1109537D01*
X567125Y1109395D01*
X566925D01*
Y1110430D01*
X567125D01*
G37*
G36*
G01Y1112780D02*
X567525Y1112637D01*
Y1111887D01*
X567125Y1111745D01*
X566925D01*
Y1112780D01*
X567125D01*
G37*
G36*
G01X571651Y1097657D02*
X571287Y1097876D01*
X571434Y1098611D01*
X571854Y1098672D01*
X572050Y1098633D01*
X571847Y1097618D01*
X571651Y1097657D01*
G37*
G36*
G01X572016Y1097442D02*
X572380Y1097223D01*
X572233Y1096488D01*
X571813Y1096427D01*
X571617Y1096466D01*
X571820Y1097481D01*
X572016Y1097442D01*
G37*
G36*
G01X572112Y1099962D02*
X571747Y1100180D01*
X571894Y1100915D01*
X572315Y1100977D01*
X572511Y1100937D01*
X572308Y1099923D01*
X572112Y1099962D01*
G37*
G36*
G01X572477Y1099746D02*
X572841Y1099528D01*
X572694Y1098792D01*
X572274Y1098731D01*
X572078Y1098770D01*
X572280Y1099785D01*
X572477Y1099746D01*
G37*
G36*
G01X572937Y1102050D02*
X573301Y1101832D01*
X573154Y1101097D01*
X572734Y1101036D01*
X572538Y1101075D01*
X572741Y1102090D01*
X572937Y1102050D01*
G37*
G36*
G01X573140Y1108373D02*
X573540Y1108230D01*
Y1107480D01*
X573140Y1107337D01*
X572940D01*
Y1108373D01*
X573140D01*
G37*
G36*
G01X572740Y1108512D02*
X572340Y1108655D01*
Y1109405D01*
X572740Y1109547D01*
X572940D01*
Y1108512D01*
X572740D01*
G37*
G36*
G01Y1106162D02*
X572340Y1106305D01*
Y1107055D01*
X572740Y1107197D01*
X572940D01*
Y1106162D01*
X572740D01*
G37*
G36*
G01X573140Y1106023D02*
X573540Y1105880D01*
Y1105130D01*
X573140Y1104987D01*
X572940D01*
Y1106023D01*
X573140D01*
G37*
G36*
G01X572740Y1110862D02*
X572340Y1111005D01*
Y1111755D01*
X572740Y1111897D01*
X572940D01*
Y1110862D01*
X572740D01*
G37*
G36*
G01X573140Y1110723D02*
X573540Y1110580D01*
Y1109830D01*
X573140Y1109687D01*
X572940D01*
Y1110723D01*
X573140D01*
G37*
G36*
G01X574010Y1097186D02*
X573646Y1097404D01*
X573793Y1098139D01*
X574213Y1098200D01*
X574409Y1098161D01*
X574206Y1097146D01*
X574010Y1097186D01*
G37*
G36*
G01X574375Y1096970D02*
X574739Y1096752D01*
X574592Y1096016D01*
X574172Y1095955D01*
X573976Y1095994D01*
X574179Y1097009D01*
X574375Y1096970D01*
G37*
G36*
G01X574471Y1099490D02*
X574107Y1099708D01*
X574254Y1100443D01*
X574674Y1100505D01*
X574870Y1100466D01*
X574667Y1099451D01*
X574471Y1099490D01*
G37*
G36*
G01X574836Y1099274D02*
X575200Y1099056D01*
X575053Y1098321D01*
X574633Y1098259D01*
X574437Y1098298D01*
X574640Y1099313D01*
X574836Y1099274D01*
G37*
G36*
G01X575297Y1101578D02*
X575661Y1101360D01*
X575514Y1100625D01*
X575094Y1100564D01*
X574898Y1100603D01*
X575101Y1101618D01*
X575297Y1101578D01*
G37*
G36*
G01X575140Y1103812D02*
X574740Y1103955D01*
Y1104705D01*
X575140Y1104847D01*
X575340D01*
Y1103812D01*
X575140D01*
G37*
G36*
G01Y1110862D02*
X574740Y1111005D01*
Y1111755D01*
X575140Y1111897D01*
X575340D01*
Y1110862D01*
X575140D01*
G37*
G36*
G01Y1108512D02*
X574740Y1108655D01*
Y1109405D01*
X575140Y1109547D01*
X575340D01*
Y1108512D01*
X575140D01*
G37*
G36*
G01Y1106162D02*
X574740Y1106305D01*
Y1107055D01*
X575140Y1107197D01*
X575340D01*
Y1106162D01*
X575140D01*
G37*
G36*
G01X575540Y1108373D02*
X575940Y1108230D01*
Y1107480D01*
X575540Y1107337D01*
X575340D01*
Y1108373D01*
X575540D01*
G37*
G36*
G01Y1110723D02*
X575940Y1110580D01*
Y1109830D01*
X575540Y1109687D01*
X575340D01*
Y1110723D01*
X575540D01*
G37*
G36*
G01Y1106023D02*
X575940Y1105880D01*
Y1105130D01*
X575540Y1104987D01*
X575340D01*
Y1106023D01*
X575540D01*
G37*
G36*
G01X574117Y1101814D02*
X574482Y1101596D01*
X574335Y1100861D01*
X573914Y1100799D01*
X573718Y1100839D01*
X573921Y1101854D01*
X574117Y1101814D01*
G37*
G36*
G01X572831Y1097421D02*
X572467Y1097640D01*
X572614Y1098375D01*
X573034Y1098436D01*
X573230Y1098397D01*
X573027Y1097382D01*
X572831Y1097421D01*
G37*
G36*
G01X573196Y1097206D02*
X573560Y1096987D01*
X573413Y1096252D01*
X572993Y1096191D01*
X572797Y1096230D01*
X573000Y1097245D01*
X573196Y1097206D01*
G37*
G36*
G01X573292Y1099726D02*
X572928Y1099944D01*
X573075Y1100679D01*
X573495Y1100741D01*
X573691Y1100701D01*
X573488Y1099687D01*
X573292Y1099726D01*
G37*
G36*
G01X573657Y1099510D02*
X574021Y1099292D01*
X573874Y1098556D01*
X573454Y1098495D01*
X573257Y1098534D01*
X573461Y1099549D01*
X573657Y1099510D01*
G37*
G36*
G01X573940Y1106162D02*
X573540Y1106305D01*
Y1107055D01*
X573940Y1107197D01*
X574140D01*
Y1106162D01*
X573940D01*
G37*
G36*
G01X574340Y1108373D02*
X574740Y1108230D01*
Y1107480D01*
X574340Y1107337D01*
X574140D01*
Y1108373D01*
X574340D01*
G37*
G36*
G01X573940Y1110862D02*
X573540Y1111005D01*
Y1111755D01*
X573940Y1111897D01*
X574140D01*
Y1110862D01*
X573940D01*
G37*
G36*
G01X574340Y1110723D02*
X574740Y1110580D01*
Y1109830D01*
X574340Y1109687D01*
X574140D01*
Y1110723D01*
X574340D01*
G37*
G36*
G01Y1106023D02*
X574740Y1105880D01*
Y1105130D01*
X574340Y1104987D01*
X574140D01*
Y1106023D01*
X574340D01*
G37*
G36*
G01X573940Y1108512D02*
X573540Y1108655D01*
Y1109405D01*
X573940Y1109547D01*
X574140D01*
Y1108512D01*
X573940D01*
G37*
G36*
G01X575188Y1096950D02*
X574823Y1097168D01*
X574971Y1097904D01*
X575391Y1097965D01*
X575587Y1097926D01*
X575384Y1096911D01*
X575188Y1096950D01*
G37*
G36*
G01X576013Y1099039D02*
X576378Y1098820D01*
X576231Y1098085D01*
X575810Y1098024D01*
X575614Y1098063D01*
X575817Y1099078D01*
X576013Y1099039D01*
G37*
G36*
G01X576474Y1101343D02*
X576839Y1101125D01*
X576692Y1100389D01*
X576271Y1100328D01*
X576075Y1100367D01*
X576278Y1101382D01*
X576474Y1101343D01*
G37*
G36*
G01X575649Y1099254D02*
X575284Y1099473D01*
X575431Y1100208D01*
X575852Y1100269D01*
X576048Y1100230D01*
X575845Y1099215D01*
X575649Y1099254D01*
G37*
G36*
G01X576340Y1103812D02*
X575940Y1103955D01*
Y1104705D01*
X576340Y1104847D01*
X576540D01*
Y1103812D01*
X576340D01*
G37*
G36*
G01X576740Y1108373D02*
X577140Y1108230D01*
Y1107480D01*
X576740Y1107337D01*
X576540D01*
Y1108373D01*
X576740D01*
G37*
G36*
G01Y1110723D02*
X577140Y1110580D01*
Y1109830D01*
X576740Y1109687D01*
X576540D01*
Y1110723D01*
X576740D01*
G37*
G36*
G01X576340Y1108512D02*
X575940Y1108655D01*
Y1109405D01*
X576340Y1109547D01*
X576540D01*
Y1108512D01*
X576340D01*
G37*
G36*
G01Y1110862D02*
X575940Y1111005D01*
Y1111755D01*
X576340Y1111897D01*
X576540D01*
Y1110862D01*
X576340D01*
G37*
G36*
G01Y1106162D02*
X575940Y1106305D01*
Y1107055D01*
X576340Y1107197D01*
X576540D01*
Y1106162D01*
X576340D01*
G37*
G36*
G01X576740Y1106023D02*
X577140Y1105880D01*
Y1105130D01*
X576740Y1104987D01*
X576540D01*
Y1106023D01*
X576740D01*
G37*
G36*
G01X577347Y1096387D02*
X576982Y1096605D01*
X577130Y1097341D01*
X577550Y1097402D01*
X577746Y1097363D01*
X577543Y1096348D01*
X577347Y1096387D01*
G37*
G36*
G01X578172Y1098476D02*
X578537Y1098257D01*
X578390Y1097522D01*
X577969Y1097461D01*
X577773Y1097500D01*
X577976Y1098515D01*
X578172Y1098476D01*
G37*
G36*
G01X577808Y1098691D02*
X577443Y1098910D01*
X577590Y1099645D01*
X578011Y1099706D01*
X578207Y1099667D01*
X578004Y1098652D01*
X577808Y1098691D01*
G37*
G36*
G01X578633Y1100780D02*
X578998Y1100562D01*
X578851Y1099826D01*
X578430Y1099765D01*
X578234Y1099804D01*
X578437Y1100819D01*
X578633Y1100780D01*
G37*
G36*
G01X578269Y1100996D02*
X577904Y1101214D01*
X578051Y1101949D01*
X578472Y1102011D01*
X578668Y1101971D01*
X578465Y1100957D01*
X578269Y1100996D01*
G37*
G36*
G01X578729Y1103300D02*
X578365Y1103518D01*
X578512Y1104254D01*
X578933Y1104315D01*
X579129Y1104276D01*
X578926Y1103261D01*
X578729Y1103300D01*
G37*
G36*
G01X579094Y1103084D02*
X579459Y1102866D01*
X579311Y1102131D01*
X578891Y1102069D01*
X578695Y1102109D01*
X578898Y1103124D01*
X579094Y1103084D01*
G37*
G36*
G01X580016Y1107693D02*
X580380Y1107475D01*
X580233Y1106739D01*
X579813Y1106678D01*
X579617Y1106717D01*
X579820Y1107732D01*
X580016Y1107693D01*
G37*
G36*
G01X579190Y1105604D02*
X578826Y1105823D01*
X578973Y1106558D01*
X579393Y1106619D01*
X579590Y1106580D01*
X579387Y1105565D01*
X579190Y1105604D01*
G37*
G36*
G01X579555Y1105389D02*
X579919Y1105171D01*
X579772Y1104435D01*
X579352Y1104374D01*
X579156Y1104413D01*
X579359Y1105428D01*
X579555Y1105389D01*
G37*
G36*
G01X580990Y1100309D02*
X581354Y1100090D01*
X581207Y1099355D01*
X580787Y1099294D01*
X580591Y1099333D01*
X580794Y1100348D01*
X580990Y1100309D01*
G37*
G36*
G01X580164Y1098220D02*
X579800Y1098438D01*
X579947Y1099174D01*
X580367Y1099235D01*
X580563Y1099196D01*
X580360Y1098181D01*
X580164Y1098220D01*
G37*
G36*
G01X580625Y1100524D02*
X580261Y1100743D01*
X580408Y1101478D01*
X580829Y1101539D01*
X581025Y1101500D01*
X580822Y1100485D01*
X580625Y1100524D01*
G37*
G36*
G01X580529Y1098004D02*
X580893Y1097786D01*
X580746Y1097051D01*
X580326Y1096989D01*
X580130Y1097029D01*
X580333Y1098044D01*
X580529Y1098004D01*
G37*
G36*
G01X579703Y1095916D02*
X579339Y1096134D01*
X579486Y1096869D01*
X579906Y1096931D01*
X580102Y1096891D01*
X579899Y1095876D01*
X579703Y1095916D01*
G37*
G36*
G01X581087Y1102829D02*
X580722Y1103047D01*
X580869Y1103782D01*
X581290Y1103844D01*
X581486Y1103804D01*
X581283Y1102789D01*
X581087Y1102829D01*
G37*
G36*
G01X581451Y1102613D02*
X581816Y1102395D01*
X581668Y1101659D01*
X581248Y1101598D01*
X581052Y1101637D01*
X581255Y1102652D01*
X581451Y1102613D01*
G37*
G36*
G01X579350Y1098240D02*
X579714Y1098022D01*
X579567Y1097286D01*
X579147Y1097225D01*
X578951Y1097264D01*
X579154Y1098279D01*
X579350Y1098240D01*
G37*
G36*
G01X578524Y1096152D02*
X578160Y1096370D01*
X578307Y1097105D01*
X578727Y1097166D01*
X578923Y1097127D01*
X578720Y1096112D01*
X578524Y1096152D01*
G37*
G36*
G01X579811Y1100544D02*
X580175Y1100326D01*
X580028Y1099591D01*
X579608Y1099530D01*
X579412Y1099569D01*
X579615Y1100584D01*
X579811Y1100544D01*
G37*
G36*
G01X578985Y1098456D02*
X578621Y1098674D01*
X578768Y1099410D01*
X579188Y1099471D01*
X579384Y1099432D01*
X579181Y1098417D01*
X578985Y1098456D01*
G37*
G36*
G01X579446Y1100760D02*
X579082Y1100978D01*
X579229Y1101714D01*
X579649Y1101775D01*
X579845Y1101736D01*
X579642Y1100721D01*
X579446Y1100760D01*
G37*
G36*
G01X579907Y1103065D02*
X579543Y1103283D01*
X579690Y1104018D01*
X580110Y1104079D01*
X580306Y1104040D01*
X580103Y1103025D01*
X579907Y1103065D01*
G37*
G36*
G01X580272Y1102849D02*
X580636Y1102631D01*
X580489Y1101895D01*
X580069Y1101834D01*
X579873Y1101873D01*
X580076Y1102888D01*
X580272Y1102849D01*
G37*
G36*
G01X580733Y1105153D02*
X581097Y1104935D01*
X580950Y1104200D01*
X580530Y1104138D01*
X580333Y1104178D01*
X580537Y1105192D01*
X580733Y1105153D01*
G37*
G36*
G01X581707Y1097769D02*
X582071Y1097551D01*
X581924Y1096815D01*
X581504Y1096754D01*
X581308Y1096793D01*
X581511Y1097808D01*
X581707Y1097769D01*
G37*
G36*
G01X582168Y1100073D02*
X582532Y1099855D01*
X582385Y1099119D01*
X581965Y1099058D01*
X581769Y1099097D01*
X581972Y1100112D01*
X582168Y1100073D01*
G37*
G36*
G01X581342Y1097984D02*
X580978Y1098203D01*
X581125Y1098938D01*
X581545Y1098999D01*
X581741Y1098960D01*
X581538Y1097945D01*
X581342Y1097984D01*
G37*
G36*
G01X581803Y1100289D02*
X581439Y1100507D01*
X581586Y1101242D01*
X582006Y1101304D01*
X582202Y1101264D01*
X581999Y1100250D01*
X581803Y1100289D01*
G37*
G36*
G01X582264Y1102593D02*
X581900Y1102811D01*
X582047Y1103547D01*
X582467Y1103608D01*
X582663Y1103569D01*
X582460Y1102554D01*
X582264Y1102593D01*
G37*
G36*
G01X565925Y1115130D02*
X566325Y1114987D01*
Y1114237D01*
X565925Y1114095D01*
X565725D01*
Y1115130D01*
X565925D01*
G37*
G36*
G01Y1117480D02*
X566325Y1117337D01*
Y1116587D01*
X565925Y1116445D01*
X565725D01*
Y1117480D01*
X565925D01*
G37*
G36*
G01Y1124530D02*
X566325Y1124387D01*
Y1123637D01*
X565925Y1123495D01*
X565725D01*
Y1124530D01*
X565925D01*
G37*
G36*
G01Y1122180D02*
X566325Y1122037D01*
Y1121287D01*
X565925Y1121145D01*
X565725D01*
Y1122180D01*
X565925D01*
G37*
G36*
G01Y1119830D02*
X566325Y1119687D01*
Y1118937D01*
X565925Y1118795D01*
X565725D01*
Y1119830D01*
X565925D01*
G37*
G36*
G01Y1126880D02*
X566325Y1126737D01*
Y1125987D01*
X565925Y1125845D01*
X565725D01*
Y1126880D01*
X565925D01*
G37*
G36*
G01Y1129230D02*
X566325Y1129087D01*
Y1128337D01*
X565925Y1128195D01*
X565725D01*
Y1129230D01*
X565925D01*
G37*
G36*
G01X566725Y1112919D02*
X566325Y1113062D01*
Y1113812D01*
X566725Y1113955D01*
X566925D01*
Y1112919D01*
X566725D01*
G37*
G36*
G01Y1115269D02*
X566325Y1115412D01*
Y1116162D01*
X566725Y1116305D01*
X566925D01*
Y1115269D01*
X566725D01*
G37*
G36*
G01Y1117619D02*
X566325Y1117762D01*
Y1118512D01*
X566725Y1118655D01*
X566925D01*
Y1117619D01*
X566725D01*
G37*
G36*
G01X567125Y1117480D02*
X567525Y1117337D01*
Y1116587D01*
X567125Y1116445D01*
X566925D01*
Y1117480D01*
X567125D01*
G37*
G36*
G01Y1115130D02*
X567525Y1114987D01*
Y1114237D01*
X567125Y1114095D01*
X566925D01*
Y1115130D01*
X567125D01*
G37*
G36*
G01X566725Y1119969D02*
X566325Y1120112D01*
Y1120862D01*
X566725Y1121005D01*
X566925D01*
Y1119969D01*
X566725D01*
G37*
G36*
G01Y1122319D02*
X566325Y1122462D01*
Y1123212D01*
X566725Y1123355D01*
X566925D01*
Y1122319D01*
X566725D01*
G37*
G36*
G01Y1124669D02*
X566325Y1124812D01*
Y1125562D01*
X566725Y1125705D01*
X566925D01*
Y1124669D01*
X566725D01*
G37*
G36*
G01Y1127019D02*
X566325Y1127162D01*
Y1127912D01*
X566725Y1128055D01*
X566925D01*
Y1127019D01*
X566725D01*
G37*
G36*
G01X567125Y1122180D02*
X567525Y1122037D01*
Y1121287D01*
X567125Y1121145D01*
X566925D01*
Y1122180D01*
X567125D01*
G37*
G36*
G01Y1119830D02*
X567525Y1119687D01*
Y1118937D01*
X567125Y1118795D01*
X566925D01*
Y1119830D01*
X567125D01*
G37*
G36*
G01Y1124530D02*
X567525Y1124387D01*
Y1123637D01*
X567125Y1123495D01*
X566925D01*
Y1124530D01*
X567125D01*
G37*
G36*
G01Y1126880D02*
X567525Y1126737D01*
Y1125987D01*
X567125Y1125845D01*
X566925D01*
Y1126880D01*
X567125D01*
G37*
G36*
G01Y1129230D02*
X567525Y1129087D01*
Y1128337D01*
X567125Y1128195D01*
X566925D01*
Y1129230D01*
X567125D01*
G37*
G36*
G01X572740Y1113212D02*
X572340Y1113355D01*
Y1114105D01*
X572740Y1114247D01*
X572940D01*
Y1113212D01*
X572740D01*
G37*
G36*
G01Y1115562D02*
X572340Y1115705D01*
Y1116455D01*
X572740Y1116597D01*
X572940D01*
Y1115562D01*
X572740D01*
G37*
G36*
G01X573140Y1115423D02*
X573540Y1115280D01*
Y1114530D01*
X573140Y1114387D01*
X572940D01*
Y1115423D01*
X573140D01*
G37*
G36*
G01Y1113073D02*
X573540Y1112930D01*
Y1112180D01*
X573140Y1112037D01*
X572940D01*
Y1113073D01*
X573140D01*
G37*
G36*
G01Y1117773D02*
X573540Y1117630D01*
Y1116880D01*
X573140Y1116737D01*
X572940D01*
Y1117773D01*
X573140D01*
G37*
G36*
G01X572740Y1117912D02*
X572340Y1118055D01*
Y1118805D01*
X572740Y1118947D01*
X572940D01*
Y1117912D01*
X572740D01*
G37*
G36*
G01Y1120262D02*
X572340Y1120405D01*
Y1121155D01*
X572740Y1121297D01*
X572940D01*
Y1120262D01*
X572740D01*
G37*
G36*
G01Y1122612D02*
X572340Y1122755D01*
Y1123505D01*
X572740Y1123647D01*
X572940D01*
Y1122612D01*
X572740D01*
G37*
G36*
G01X573140Y1120123D02*
X573540Y1119980D01*
Y1119230D01*
X573140Y1119087D01*
X572940D01*
Y1120123D01*
X573140D01*
G37*
G36*
G01Y1122473D02*
X573540Y1122330D01*
Y1121580D01*
X573140Y1121437D01*
X572940D01*
Y1122473D01*
X573140D01*
G37*
G36*
G01X575140Y1113212D02*
X574740Y1113355D01*
Y1114105D01*
X575140Y1114247D01*
X575340D01*
Y1113212D01*
X575140D01*
G37*
G36*
G01Y1115562D02*
X574740Y1115705D01*
Y1116455D01*
X575140Y1116597D01*
X575340D01*
Y1115562D01*
X575140D01*
G37*
G36*
G01Y1117912D02*
X574740Y1118055D01*
Y1118805D01*
X575140Y1118947D01*
X575340D01*
Y1117912D01*
X575140D01*
G37*
G36*
G01X575540Y1115423D02*
X575940Y1115280D01*
Y1114530D01*
X575540Y1114387D01*
X575340D01*
Y1115423D01*
X575540D01*
G37*
G36*
G01Y1117773D02*
X575940Y1117630D01*
Y1116880D01*
X575540Y1116737D01*
X575340D01*
Y1117773D01*
X575540D01*
G37*
G36*
G01Y1113073D02*
X575940Y1112930D01*
Y1112180D01*
X575540Y1112037D01*
X575340D01*
Y1113073D01*
X575540D01*
G37*
G36*
G01Y1120123D02*
X575940Y1119980D01*
Y1119230D01*
X575540Y1119087D01*
X575340D01*
Y1120123D01*
X575540D01*
G37*
G36*
G01X573940Y1113212D02*
X573540Y1113355D01*
Y1114105D01*
X573940Y1114247D01*
X574140D01*
Y1113212D01*
X573940D01*
G37*
G36*
G01Y1115562D02*
X573540Y1115705D01*
Y1116455D01*
X573940Y1116597D01*
X574140D01*
Y1115562D01*
X573940D01*
G37*
G36*
G01X574340Y1113073D02*
X574740Y1112930D01*
Y1112180D01*
X574340Y1112037D01*
X574140D01*
Y1113073D01*
X574340D01*
G37*
G36*
G01Y1115423D02*
X574740Y1115280D01*
Y1114530D01*
X574340Y1114387D01*
X574140D01*
Y1115423D01*
X574340D01*
G37*
G36*
G01Y1117773D02*
X574740Y1117630D01*
Y1116880D01*
X574340Y1116737D01*
X574140D01*
Y1117773D01*
X574340D01*
G37*
G36*
G01X573940Y1117912D02*
X573540Y1118055D01*
Y1118805D01*
X573940Y1118947D01*
X574140D01*
Y1117912D01*
X573940D01*
G37*
G36*
G01X574340Y1122473D02*
X574740Y1122330D01*
Y1121580D01*
X574340Y1121437D01*
X574140D01*
Y1122473D01*
X574340D01*
G37*
G36*
G01X573940Y1120262D02*
X573540Y1120405D01*
Y1121155D01*
X573940Y1121297D01*
X574140D01*
Y1120262D01*
X573940D01*
G37*
G36*
G01Y1122612D02*
X573540Y1122755D01*
Y1123505D01*
X573940Y1123647D01*
X574140D01*
Y1122612D01*
X573940D01*
G37*
G36*
G01X574340Y1120123D02*
X574740Y1119980D01*
Y1119230D01*
X574340Y1119087D01*
X574140D01*
Y1120123D01*
X574340D01*
G37*
G36*
G01X576740Y1113073D02*
X577140Y1112930D01*
Y1112180D01*
X576740Y1112037D01*
X576540D01*
Y1113073D01*
X576740D01*
G37*
G36*
G01Y1115423D02*
X577140Y1115280D01*
Y1114530D01*
X576740Y1114387D01*
X576540D01*
Y1115423D01*
X576740D01*
G37*
G36*
G01Y1117773D02*
X577140Y1117630D01*
Y1116880D01*
X576740Y1116737D01*
X576540D01*
Y1117773D01*
X576740D01*
G37*
G36*
G01X576340Y1113212D02*
X575940Y1113355D01*
Y1114105D01*
X576340Y1114247D01*
X576540D01*
Y1113212D01*
X576340D01*
G37*
G36*
G01Y1115562D02*
X575940Y1115705D01*
Y1116455D01*
X576340Y1116597D01*
X576540D01*
Y1115562D01*
X576340D01*
G37*
G36*
G01Y1117912D02*
X575940Y1118055D01*
Y1118805D01*
X576340Y1118947D01*
X576540D01*
Y1117912D01*
X576340D01*
G37*
G36*
G01X565925Y1131580D02*
X566325Y1131437D01*
Y1130687D01*
X565925Y1130545D01*
X565725D01*
Y1131580D01*
X565925D01*
G37*
G36*
G01Y1133930D02*
X566325Y1133787D01*
Y1133037D01*
X565925Y1132895D01*
X565725D01*
Y1133930D01*
X565925D01*
G37*
G36*
G01Y1136280D02*
X566325Y1136137D01*
Y1135387D01*
X565925Y1135245D01*
X565725D01*
Y1136280D01*
X565925D01*
G37*
G36*
G01Y1138630D02*
X566325Y1138487D01*
Y1137737D01*
X565925Y1137595D01*
X565725D01*
Y1138630D01*
X565925D01*
G37*
G36*
G01X566725Y1129369D02*
X566325Y1129512D01*
Y1130262D01*
X566725Y1130405D01*
X566925D01*
Y1129369D01*
X566725D01*
G37*
G36*
G01Y1131719D02*
X566325Y1131862D01*
Y1132612D01*
X566725Y1132755D01*
X566925D01*
Y1131719D01*
X566725D01*
G37*
G36*
G01Y1134069D02*
X566325Y1134212D01*
Y1134962D01*
X566725Y1135105D01*
X566925D01*
Y1134069D01*
X566725D01*
G37*
G36*
G01X567125Y1131580D02*
X567525Y1131437D01*
Y1130687D01*
X567125Y1130545D01*
X566925D01*
Y1131580D01*
X567125D01*
G37*
G36*
G01Y1133930D02*
X567525Y1133787D01*
Y1133037D01*
X567125Y1132895D01*
X566925D01*
Y1133930D01*
X567125D01*
G37*
G36*
G01X566725Y1136419D02*
X566325Y1136562D01*
Y1137312D01*
X566725Y1137455D01*
X566925D01*
Y1136419D01*
X566725D01*
G37*
G36*
G01X567125Y1136280D02*
X567525Y1136137D01*
Y1135387D01*
X567125Y1135245D01*
X566925D01*
Y1136280D01*
X567125D01*
G37*
G36*
G01Y1138630D02*
X567525Y1138487D01*
Y1137737D01*
X567125Y1137595D01*
X566925D01*
Y1138630D01*
X567125D01*
G37*
G36*
G01X581533Y1575686D02*
G03I-720J0D01*
G37*
G36*
G01Y1580678D02*
G03I-720J0D01*
G37*
G36*
G01X574429D02*
G03I-720J0D01*
G37*
G36*
G01X569473D02*
G03I-720J0D01*
G37*
G36*
G01Y1575686D02*
G03I-720J0D01*
G37*
G36*
G01X574429D02*
G03I-720J0D01*
G37*
G36*
G01X579729Y1599884D02*
G03I-720J0D01*
G37*
G36*
G01X574773D02*
G03I-720J0D01*
G37*
G36*
G01X567669D02*
G03I-720J0D01*
G37*
G36*
G01X581533Y1587598D02*
G03I-720J0D01*
G37*
G36*
G01Y1592590D02*
G03I-720J0D01*
G37*
G36*
G01X574429D02*
G03I-720J0D01*
G37*
G36*
G01X569473D02*
G03I-720J0D01*
G37*
G36*
G01X574429Y1587598D02*
G03I-720J0D01*
G37*
G36*
G01X569473D02*
G03I-720J0D01*
G37*
G36*
G01X574773Y1616788D02*
G03I-720J0D01*
G37*
G36*
G01X579729D02*
G03I-720J0D01*
G37*
G36*
G01Y1611796D02*
G03I-720J0D01*
G37*
G36*
G01X574773D02*
G03I-720J0D01*
G37*
G36*
G01X579729Y1604876D02*
G03I-720J0D01*
G37*
G36*
G01X574773D02*
G03I-720J0D01*
G37*
G36*
G01X567669Y1616788D02*
G03I-720J0D01*
G37*
G36*
G01Y1604876D02*
G03I-720J0D01*
G37*
G36*
G01Y1611796D02*
G03I-720J0D01*
G37*
G36*
G01X597560Y45152D02*
G03I-720J0D01*
G37*
G36*
G01X597301Y184849D02*
G03I-720J0D01*
G37*
G36*
G01X591057Y177604D02*
G03I-720J0D01*
G37*
G36*
G01X591070Y294402D02*
G03I-720J0D01*
G37*
G36*
G01X587540Y314662D02*
G03I-720J0D01*
G37*
G36*
G01X598540Y317062D02*
G03I-720J0D01*
G37*
G36*
G01X593640Y326362D02*
G03I-720J0D01*
G37*
G36*
G01X584628Y900522D02*
X585028Y900379D01*
Y899629D01*
X584628Y899487D01*
X584428D01*
Y900522D01*
X584628D01*
G37*
G36*
G01Y898172D02*
X585028Y898029D01*
Y897279D01*
X584628Y897137D01*
X584428D01*
Y898172D01*
X584628D01*
G37*
G36*
G01Y895822D02*
X585028Y895679D01*
Y894929D01*
X584628Y894787D01*
X584428D01*
Y895822D01*
X584628D01*
G37*
G36*
G01X584228Y895962D02*
X583828Y896105D01*
Y896855D01*
X584228Y896997D01*
X584428D01*
Y895962D01*
X584228D01*
G37*
G36*
G01Y893612D02*
X583828Y893755D01*
Y894505D01*
X584228Y894647D01*
X584428D01*
Y893612D01*
X584228D01*
G37*
G36*
G01Y898312D02*
X583828Y898455D01*
Y899205D01*
X584228Y899347D01*
X584428D01*
Y898312D01*
X584228D01*
G37*
G36*
G01X582228Y895822D02*
X582628Y895679D01*
Y894929D01*
X582228Y894787D01*
X582028D01*
Y895822D01*
X582228D01*
G37*
G36*
G01Y898172D02*
X582628Y898029D01*
Y897279D01*
X582228Y897137D01*
X582028D01*
Y898172D01*
X582228D01*
G37*
G36*
G01Y893472D02*
X582628Y893329D01*
Y892579D01*
X582228Y892437D01*
X582028D01*
Y893472D01*
X582228D01*
G37*
G36*
G01Y900522D02*
X582628Y900379D01*
Y899629D01*
X582228Y899487D01*
X582028D01*
Y900522D01*
X582228D01*
G37*
G36*
G01X583428D02*
X583828Y900379D01*
Y899629D01*
X583428Y899487D01*
X583228D01*
Y900522D01*
X583428D01*
G37*
G36*
G01X583028Y895962D02*
X582628Y896105D01*
Y896855D01*
X583028Y896997D01*
X583228D01*
Y895962D01*
X583028D01*
G37*
G36*
G01Y898312D02*
X582628Y898455D01*
Y899205D01*
X583028Y899347D01*
X583228D01*
Y898312D01*
X583028D01*
G37*
G36*
G01X583428Y895822D02*
X583828Y895679D01*
Y894929D01*
X583428Y894787D01*
X583228D01*
Y895822D01*
X583428D01*
G37*
G36*
G01Y898172D02*
X583828Y898029D01*
Y897279D01*
X583428Y897137D01*
X583228D01*
Y898172D01*
X583428D01*
G37*
G36*
G01X590014Y910237D02*
X589630Y910055D01*
X589100Y910586D01*
X589282Y910969D01*
X589423Y911111D01*
X590155Y910379D01*
X590014Y910237D01*
G37*
G36*
G01X587072Y913745D02*
X587456Y913927D01*
X587986Y913396D01*
X587804Y913013D01*
X587663Y912871D01*
X586931Y913603D01*
X587072Y913745D01*
G37*
G36*
G01X585410Y915406D02*
X585794Y915588D01*
X586324Y915058D01*
X586142Y914674D01*
X586001Y914533D01*
X585269Y915265D01*
X585410Y915406D01*
G37*
G36*
G01X586690Y913561D02*
X586307Y913379D01*
X585776Y913909D01*
X585959Y914293D01*
X586100Y914434D01*
X586832Y913702D01*
X586690Y913561D01*
G37*
G36*
G01X588352Y911899D02*
X587968Y911717D01*
X587438Y912247D01*
X587620Y912631D01*
X587762Y912772D01*
X588493Y912041D01*
X588352Y911899D01*
G37*
G36*
G01X583367Y916884D02*
X582983Y916702D01*
X582453Y917232D01*
X582635Y917616D01*
X582777Y917757D01*
X583508Y917026D01*
X583367Y916884D01*
G37*
G36*
G01X583749Y917068D02*
X584132Y917250D01*
X584663Y916720D01*
X584481Y916336D01*
X584339Y916195D01*
X583607Y916927D01*
X583749Y917068D01*
G37*
G36*
G01X585029Y915222D02*
X584645Y915040D01*
X584115Y915571D01*
X584297Y915954D01*
X584438Y916096D01*
X585170Y915364D01*
X585029Y915222D01*
G37*
G36*
G01X586651Y910198D02*
X586268Y910016D01*
X585737Y910546D01*
X585919Y910930D01*
X586061Y911071D01*
X586793Y910340D01*
X586651Y910198D01*
G37*
G36*
G01X588313Y908536D02*
X587929Y908354D01*
X587399Y908885D01*
X587581Y909268D01*
X587722Y909410D01*
X588454Y908678D01*
X588313Y908536D01*
G37*
G36*
G01X587033Y910382D02*
X587416Y910564D01*
X587947Y910034D01*
X587765Y909650D01*
X587623Y909509D01*
X586891Y910240D01*
X587033Y910382D01*
G37*
G36*
G01X588695Y908720D02*
X589078Y908902D01*
X589609Y908372D01*
X589426Y907988D01*
X589285Y907847D01*
X588553Y908579D01*
X588695Y908720D01*
G37*
G36*
G01X585371Y912044D02*
X585755Y912226D01*
X586285Y911695D01*
X586103Y911312D01*
X585962Y911170D01*
X585230Y911902D01*
X585371Y912044D01*
G37*
G36*
G01X583328Y913522D02*
X582944Y913339D01*
X582414Y913870D01*
X582596Y914253D01*
X582737Y914395D01*
X583469Y913663D01*
X583328Y913522D01*
G37*
G36*
G01X584989Y911860D02*
X584606Y911678D01*
X584075Y912208D01*
X584257Y912592D01*
X584399Y912733D01*
X585131Y912001D01*
X584989Y911860D01*
G37*
G36*
G01X583709Y913705D02*
X584093Y913887D01*
X584623Y913357D01*
X584441Y912974D01*
X584300Y912832D01*
X583568Y913564D01*
X583709Y913705D01*
G37*
G36*
G01X584228Y900662D02*
X583828Y900805D01*
Y901555D01*
X584228Y901697D01*
X584428D01*
Y900662D01*
X584228D01*
G37*
G36*
G01X582799Y906126D02*
X583183Y906308D01*
X583713Y905778D01*
X583531Y905394D01*
X583389Y905253D01*
X582657Y905985D01*
X582799Y906126D01*
G37*
G36*
G01X584628Y902872D02*
X585028Y902729D01*
Y901979D01*
X584628Y901837D01*
X584428D01*
Y902872D01*
X584628D01*
G37*
G36*
G01X583028Y900662D02*
X582628Y900805D01*
Y901555D01*
X583028Y901697D01*
X583228D01*
Y900662D01*
X583028D01*
G37*
G36*
G01X583428Y902872D02*
X583828Y902729D01*
Y901979D01*
X583428Y901837D01*
X583228D01*
Y902872D01*
X583428D01*
G37*
G36*
G01X587922Y914594D02*
X588305Y914776D01*
X588836Y914246D01*
X588654Y913862D01*
X588512Y913721D01*
X587780Y914453D01*
X587922Y914594D01*
G37*
G36*
G01X587540Y914410D02*
X587156Y914228D01*
X586626Y914759D01*
X586808Y915142D01*
X586949Y915284D01*
X587681Y914552D01*
X587540Y914410D01*
G37*
G36*
G01X586260Y916256D02*
X586644Y916438D01*
X587174Y915908D01*
X586992Y915524D01*
X586850Y915383D01*
X586119Y916114D01*
X586260Y916256D01*
G37*
G36*
G01X585878Y916072D02*
X585495Y915890D01*
X584964Y916420D01*
X585146Y916804D01*
X585288Y916945D01*
X586020Y916213D01*
X585878Y916072D01*
G37*
G36*
G01X587884Y911233D02*
X588268Y911415D01*
X588798Y910885D01*
X588616Y910501D01*
X588475Y910360D01*
X587743Y911092D01*
X587884Y911233D01*
G37*
G36*
G01X589546Y909572D02*
X589930Y909754D01*
X590460Y909223D01*
X590278Y908840D01*
X590136Y908698D01*
X589405Y909430D01*
X589546Y909572D01*
G37*
G36*
G01X585840Y912711D02*
X585457Y912529D01*
X584926Y913059D01*
X585108Y913443D01*
X585250Y913584D01*
X585982Y912852D01*
X585840Y912711D01*
G37*
G36*
G01X587502Y911049D02*
X587119Y910867D01*
X586588Y911397D01*
X586770Y911781D01*
X586912Y911922D01*
X587644Y911191D01*
X587502Y911049D01*
G37*
G36*
G01X589164Y909388D02*
X588780Y909206D01*
X588250Y909736D01*
X588432Y910119D01*
X588574Y910261D01*
X589305Y909529D01*
X589164Y909388D01*
G37*
G36*
G01X590826Y907726D02*
X590442Y907544D01*
X589912Y908074D01*
X590094Y908458D01*
X590235Y908599D01*
X590967Y907868D01*
X590826Y907726D01*
G37*
G36*
G01X586222Y912895D02*
X586606Y913077D01*
X587136Y912546D01*
X586954Y912163D01*
X586813Y912021D01*
X586081Y912753D01*
X586222Y912895D01*
G37*
G36*
G01X584179Y914372D02*
X583795Y914190D01*
X583265Y914721D01*
X583447Y915104D01*
X583588Y915246D01*
X584320Y914514D01*
X584179Y914372D01*
G37*
G36*
G01X584560Y914556D02*
X584944Y914738D01*
X585474Y914208D01*
X585292Y913824D01*
X585151Y913683D01*
X584419Y914415D01*
X584560Y914556D01*
G37*
G36*
G01X582899Y916218D02*
X583282Y916400D01*
X583813Y915870D01*
X583630Y915486D01*
X583489Y915345D01*
X582757Y916076D01*
X582899Y916218D01*
G37*
G36*
G01X582087Y918730D02*
X582471Y918912D01*
X583001Y918381D01*
X582819Y917998D01*
X582678Y917856D01*
X581946Y918588D01*
X582087Y918730D01*
G37*
G36*
G01X584598Y917918D02*
X584982Y918100D01*
X585512Y917569D01*
X585330Y917186D01*
X585189Y917044D01*
X584457Y917776D01*
X584598Y917918D01*
G37*
G36*
G01X584216Y917734D02*
X583833Y917552D01*
X583303Y918082D01*
X583485Y918466D01*
X583626Y918607D01*
X584358Y917875D01*
X584216Y917734D01*
G37*
G36*
G01X582937Y919579D02*
X583320Y919761D01*
X583851Y919231D01*
X583668Y918847D01*
X583527Y918706D01*
X582795Y919438D01*
X582937Y919579D01*
G37*
G36*
G01X583144Y1046940D02*
X583326Y1046556D01*
X582796Y1046026D01*
X582412Y1046208D01*
X582270Y1046349D01*
X583002Y1047081D01*
X583144Y1046940D01*
G37*
G36*
G01X583731Y1062812D02*
X583913Y1062428D01*
X583383Y1061898D01*
X582999Y1062080D01*
X582858Y1062222D01*
X583589Y1062953D01*
X583731Y1062812D01*
G37*
G36*
G01X583547Y1063194D02*
X583365Y1063578D01*
X583895Y1064108D01*
X584279Y1063926D01*
X584420Y1063784D01*
X583688Y1063052D01*
X583547Y1063194D01*
G37*
G36*
G01X582882Y1063661D02*
X583064Y1063277D01*
X582534Y1062747D01*
X582150Y1062929D01*
X582009Y1063071D01*
X582740Y1063802D01*
X582882Y1063661D01*
G37*
G36*
G01X584580Y1061963D02*
X584762Y1061579D01*
X584232Y1061049D01*
X583848Y1061231D01*
X583707Y1061373D01*
X584438Y1062104D01*
X584580Y1061963D01*
G37*
G36*
G01X584396Y1062345D02*
X584214Y1062729D01*
X584744Y1063259D01*
X585128Y1063077D01*
X585269Y1062935D01*
X584537Y1062203D01*
X584396Y1062345D01*
G37*
G36*
G01X582918Y1060301D02*
X583100Y1059918D01*
X582570Y1059387D01*
X582186Y1059570D01*
X582045Y1059711D01*
X582777Y1060443D01*
X582918Y1060301D01*
G37*
G36*
G01X582734Y1060683D02*
X582552Y1061067D01*
X583083Y1061597D01*
X583466Y1061415D01*
X583608Y1061274D01*
X582876Y1060542D01*
X582734Y1060683D01*
G37*
G36*
G01X586242Y1063625D02*
X586424Y1063241D01*
X585893Y1062711D01*
X585510Y1062893D01*
X585368Y1063034D01*
X586100Y1063766D01*
X586242Y1063625D01*
G37*
G36*
G01X583736Y1053192D02*
X583554Y1053576D01*
X584085Y1054106D01*
X584468Y1053924D01*
X584610Y1053783D01*
X583878Y1053051D01*
X583736Y1053192D01*
G37*
G36*
G01X585582Y1054472D02*
X585764Y1054088D01*
X585234Y1053558D01*
X584850Y1053740D01*
X584709Y1053882D01*
X585440Y1054613D01*
X585582Y1054472D01*
G37*
G36*
G01X583920Y1052810D02*
X584102Y1052427D01*
X583572Y1051896D01*
X583188Y1052078D01*
X583047Y1052220D01*
X583779Y1052952D01*
X583920Y1052810D01*
G37*
G36*
G01X587060Y1056516D02*
X586878Y1056899D01*
X587408Y1057429D01*
X587792Y1057247D01*
X587933Y1057106D01*
X587201Y1056374D01*
X587060Y1056516D01*
G37*
G36*
G01X587244Y1056134D02*
X587426Y1055750D01*
X586895Y1055220D01*
X586512Y1055402D01*
X586370Y1055543D01*
X587102Y1056275D01*
X587244Y1056134D01*
G37*
G36*
G01X585398Y1054854D02*
X585216Y1055237D01*
X585746Y1055768D01*
X586130Y1055586D01*
X586271Y1055444D01*
X585539Y1054712D01*
X585398Y1054854D01*
G37*
G36*
G01X585618Y1051112D02*
X585800Y1050729D01*
X585270Y1050198D01*
X584886Y1050380D01*
X584745Y1050522D01*
X585477Y1051254D01*
X585618Y1051112D01*
G37*
G36*
G01X583773Y1049832D02*
X583591Y1050216D01*
X584121Y1050746D01*
X584504Y1050564D01*
X584646Y1050423D01*
X583914Y1049691D01*
X583773Y1049832D01*
G37*
G36*
G01X585434Y1051494D02*
X585252Y1051878D01*
X585783Y1052408D01*
X586166Y1052226D01*
X586308Y1052085D01*
X585576Y1051353D01*
X585434Y1051494D01*
G37*
G36*
G01X587096Y1053156D02*
X586914Y1053539D01*
X587444Y1054070D01*
X587828Y1053888D01*
X587969Y1053746D01*
X587237Y1053014D01*
X587096Y1053156D01*
G37*
G36*
G01X588758Y1054818D02*
X588576Y1055201D01*
X589106Y1055731D01*
X589490Y1055549D01*
X589631Y1055408D01*
X588899Y1054676D01*
X588758Y1054818D01*
G37*
G36*
G01X588942Y1054436D02*
X589124Y1054052D01*
X588593Y1053522D01*
X588210Y1053704D01*
X588068Y1053845D01*
X588800Y1054577D01*
X588942Y1054436D01*
G37*
G36*
G01X587280Y1052774D02*
X587462Y1052390D01*
X586932Y1051860D01*
X586548Y1052042D01*
X586407Y1052184D01*
X587138Y1052915D01*
X587280Y1052774D01*
G37*
G36*
G01X582111Y1048171D02*
X581929Y1048554D01*
X582459Y1049085D01*
X582843Y1048903D01*
X582984Y1048761D01*
X582252Y1048029D01*
X582111Y1048171D01*
G37*
G36*
G01X583956Y1049451D02*
X584139Y1049067D01*
X583608Y1048537D01*
X583225Y1048719D01*
X583083Y1048860D01*
X583815Y1049592D01*
X583956Y1049451D01*
G37*
G36*
G01X582924Y1050681D02*
X582742Y1051065D01*
X583272Y1051595D01*
X583655Y1051413D01*
X583797Y1051272D01*
X583065Y1050540D01*
X582924Y1050681D01*
G37*
G36*
G01X584769Y1051961D02*
X584951Y1051578D01*
X584421Y1051047D01*
X584037Y1051229D01*
X583896Y1051371D01*
X584628Y1052103D01*
X584769Y1051961D01*
G37*
G36*
G01X583107Y1050300D02*
X583290Y1049916D01*
X582759Y1049386D01*
X582376Y1049568D01*
X582234Y1049709D01*
X582966Y1050441D01*
X583107Y1050300D01*
G37*
G36*
G01X584585Y1052343D02*
X584403Y1052727D01*
X584934Y1053257D01*
X585317Y1053075D01*
X585459Y1052934D01*
X584727Y1052202D01*
X584585Y1052343D01*
G37*
G36*
G01X586247Y1054005D02*
X586065Y1054388D01*
X586595Y1054919D01*
X586979Y1054737D01*
X587120Y1054595D01*
X586388Y1053863D01*
X586247Y1054005D01*
G37*
G36*
G01X587909Y1055667D02*
X587727Y1056050D01*
X588257Y1056580D01*
X588641Y1056398D01*
X588782Y1056257D01*
X588050Y1055525D01*
X587909Y1055667D01*
G37*
G36*
G01X586431Y1053623D02*
X586613Y1053239D01*
X586083Y1052709D01*
X585699Y1052891D01*
X585558Y1053033D01*
X586289Y1053764D01*
X586431Y1053623D01*
G37*
G36*
G01X588093Y1055285D02*
X588275Y1054901D01*
X587744Y1054371D01*
X587361Y1054553D01*
X587219Y1054694D01*
X587951Y1055426D01*
X588093Y1055285D01*
G37*
G36*
G01X584622Y1048983D02*
X584440Y1049367D01*
X584970Y1049897D01*
X585353Y1049715D01*
X585495Y1049574D01*
X584763Y1048842D01*
X584622Y1048983D01*
G37*
G36*
G01X586283Y1050645D02*
X586101Y1051029D01*
X586632Y1051559D01*
X587015Y1051377D01*
X587157Y1051236D01*
X586425Y1050504D01*
X586283Y1050645D01*
G37*
G36*
G01X586467Y1050263D02*
X586649Y1049880D01*
X586119Y1049349D01*
X585735Y1049531D01*
X585594Y1049673D01*
X586326Y1050405D01*
X586467Y1050263D01*
G37*
G36*
G01X588129Y1051925D02*
X588311Y1051541D01*
X587781Y1051011D01*
X587397Y1051193D01*
X587256Y1051335D01*
X587987Y1052066D01*
X588129Y1051925D01*
G37*
G36*
G01X587945Y1052307D02*
X587763Y1052690D01*
X588293Y1053221D01*
X588677Y1053039D01*
X588818Y1052897D01*
X588086Y1052165D01*
X587945Y1052307D01*
G37*
G36*
G01X582960Y1047322D02*
X582778Y1047705D01*
X583308Y1048236D01*
X583692Y1048054D01*
X583833Y1047912D01*
X583101Y1047180D01*
X582960Y1047322D01*
G37*
G36*
G01X584805Y1048602D02*
X584988Y1048218D01*
X584457Y1047688D01*
X584074Y1047870D01*
X583932Y1048011D01*
X584664Y1048743D01*
X584805Y1048602D01*
G37*
G36*
G01X583695Y1066172D02*
X583877Y1065788D01*
X583346Y1065258D01*
X582963Y1065440D01*
X582821Y1065581D01*
X583553Y1066313D01*
X583695Y1066172D01*
G37*
G36*
G01X585356Y1067833D02*
X585538Y1067450D01*
X585008Y1066920D01*
X584624Y1067102D01*
X584483Y1067243D01*
X585215Y1067975D01*
X585356Y1067833D01*
G37*
G36*
G01X583511Y1066554D02*
X583329Y1066937D01*
X583859Y1067468D01*
X584243Y1067285D01*
X584384Y1067144D01*
X583652Y1066412D01*
X583511Y1066554D01*
G37*
G36*
G01X585172Y1068215D02*
X584990Y1068599D01*
X585521Y1069129D01*
X585904Y1068947D01*
X586046Y1068806D01*
X585314Y1068074D01*
X585172Y1068215D01*
G37*
G36*
G01X585393Y1064474D02*
X585575Y1064090D01*
X585044Y1063560D01*
X584661Y1063742D01*
X584519Y1063883D01*
X585251Y1064615D01*
X585393Y1064474D01*
G37*
G36*
G01X585209Y1064856D02*
X585027Y1065239D01*
X585557Y1065770D01*
X585941Y1065587D01*
X586082Y1065446D01*
X585350Y1064714D01*
X585209Y1064856D01*
G37*
G36*
G01X584544Y1065323D02*
X584726Y1064939D01*
X584195Y1064409D01*
X583812Y1064591D01*
X583670Y1064732D01*
X584402Y1065464D01*
X584544Y1065323D01*
G37*
G36*
G01X584360Y1065705D02*
X584178Y1066088D01*
X584708Y1066619D01*
X585092Y1066436D01*
X585233Y1066295D01*
X584501Y1065563D01*
X584360Y1065705D01*
G37*
G36*
G01X582698Y1064043D02*
X582516Y1064427D01*
X583046Y1064957D01*
X583430Y1064775D01*
X583571Y1064633D01*
X582839Y1063901D01*
X582698Y1064043D01*
G37*
G36*
G01X586058Y1064007D02*
X585876Y1064390D01*
X586406Y1064921D01*
X586790Y1064738D01*
X586931Y1064597D01*
X586199Y1063865D01*
X586058Y1064007D01*
G37*
G36*
G01X584270Y1079703D02*
X584634Y1079485D01*
X584487Y1078749D01*
X584067Y1078688D01*
X583870Y1078727D01*
X584073Y1079742D01*
X584270Y1079703D01*
G37*
G36*
G01X583444Y1077614D02*
X583079Y1077832D01*
X583227Y1078568D01*
X583647Y1078629D01*
X583843Y1078590D01*
X583640Y1077575D01*
X583444Y1077614D01*
G37*
G36*
G01X582983Y1075310D02*
X582618Y1075528D01*
X582765Y1076264D01*
X583186Y1076325D01*
X583382Y1076286D01*
X583179Y1075271D01*
X582983Y1075310D01*
G37*
G36*
G01X583808Y1077398D02*
X584173Y1077180D01*
X584026Y1076445D01*
X583605Y1076384D01*
X583409Y1076423D01*
X583612Y1077438D01*
X583808Y1077398D01*
G37*
G36*
G01X584676Y1071838D02*
X584858Y1071454D01*
X584327Y1070924D01*
X583944Y1071106D01*
X583802Y1071247D01*
X584534Y1071979D01*
X584676Y1071838D01*
G37*
G36*
G01X583014Y1070176D02*
X583196Y1069792D01*
X582666Y1069262D01*
X582282Y1069444D01*
X582141Y1069586D01*
X582872Y1070317D01*
X583014Y1070176D01*
G37*
G36*
G01X582830Y1070558D02*
X582648Y1070941D01*
X583178Y1071472D01*
X583562Y1071290D01*
X583703Y1071148D01*
X582971Y1070416D01*
X582830Y1070558D01*
G37*
G36*
G01X586625Y1079232D02*
X586989Y1079013D01*
X586842Y1078278D01*
X586422Y1078217D01*
X586226Y1078256D01*
X586429Y1079271D01*
X586625Y1079232D01*
G37*
G36*
G01X586260Y1079447D02*
X585896Y1079665D01*
X586043Y1080401D01*
X586463Y1080462D01*
X586659Y1080423D01*
X586456Y1079408D01*
X586260Y1079447D01*
G37*
G36*
G01X585799Y1077143D02*
X585435Y1077361D01*
X585582Y1078097D01*
X586002Y1078158D01*
X586198Y1078119D01*
X585995Y1077104D01*
X585799Y1077143D01*
G37*
G36*
G01X586164Y1076927D02*
X586528Y1076709D01*
X586381Y1075974D01*
X585961Y1075912D01*
X585765Y1075951D01*
X585968Y1076966D01*
X586164Y1076927D01*
G37*
G36*
G01X585703Y1074623D02*
X586067Y1074405D01*
X585920Y1073669D01*
X585500Y1073608D01*
X585304Y1073647D01*
X585507Y1074662D01*
X585703Y1074623D01*
G37*
G36*
G01X585338Y1074839D02*
X584974Y1075057D01*
X585121Y1075792D01*
X585541Y1075853D01*
X585737Y1075814D01*
X585534Y1074799D01*
X585338Y1074839D01*
G37*
G36*
G01X584525Y1074858D02*
X584890Y1074640D01*
X584743Y1073905D01*
X584322Y1073844D01*
X584126Y1073883D01*
X584329Y1074898D01*
X584525Y1074858D01*
G37*
G36*
G01X584161Y1075074D02*
X583796Y1075292D01*
X583944Y1076028D01*
X584364Y1076089D01*
X584560Y1076050D01*
X584357Y1075035D01*
X584161Y1075074D01*
G37*
G36*
G01X584986Y1077163D02*
X585351Y1076945D01*
X585204Y1076209D01*
X584783Y1076148D01*
X584587Y1076187D01*
X584790Y1077202D01*
X584986Y1077163D01*
G37*
G36*
G01X584622Y1077379D02*
X584257Y1077597D01*
X584405Y1078332D01*
X584825Y1078393D01*
X585021Y1078354D01*
X584818Y1077339D01*
X584622Y1077379D01*
G37*
G36*
G01X585447Y1079467D02*
X585812Y1079249D01*
X585665Y1078513D01*
X585244Y1078452D01*
X585048Y1078491D01*
X585251Y1079506D01*
X585447Y1079467D01*
G37*
G36*
G01X585525Y1070988D02*
X585707Y1070605D01*
X585177Y1070074D01*
X584793Y1070256D01*
X584652Y1070398D01*
X585384Y1071130D01*
X585525Y1070988D01*
G37*
G36*
G01X583679Y1069708D02*
X583497Y1070092D01*
X584028Y1070622D01*
X584411Y1070440D01*
X584553Y1070299D01*
X583821Y1069567D01*
X583679Y1069708D01*
G37*
G36*
G01X583863Y1069326D02*
X584045Y1068943D01*
X583515Y1068413D01*
X583131Y1068595D01*
X582990Y1068736D01*
X583722Y1069468D01*
X583863Y1069326D01*
G37*
G36*
G01X587803Y1078996D02*
X588167Y1078778D01*
X588020Y1078042D01*
X587600Y1077981D01*
X587403Y1078020D01*
X587607Y1079035D01*
X587803Y1078996D01*
G37*
G36*
G01X586977Y1076907D02*
X586613Y1077125D01*
X586760Y1077861D01*
X587180Y1077922D01*
X587376Y1077883D01*
X587173Y1076868D01*
X586977Y1076907D01*
G37*
G36*
G01X587438Y1079212D02*
X587074Y1079430D01*
X587221Y1080165D01*
X587641Y1080226D01*
X587837Y1080187D01*
X587634Y1079172D01*
X587438Y1079212D01*
G37*
G36*
G01X587342Y1076691D02*
X587706Y1076473D01*
X587559Y1075738D01*
X587139Y1075677D01*
X586943Y1075716D01*
X587146Y1076731D01*
X587342Y1076691D01*
G37*
G36*
G01X586881Y1074387D02*
X587245Y1074169D01*
X587098Y1073433D01*
X586678Y1073372D01*
X586482Y1073411D01*
X586685Y1074426D01*
X586881Y1074387D01*
G37*
G36*
G01X586516Y1074603D02*
X586152Y1074821D01*
X586299Y1075556D01*
X586719Y1075618D01*
X586915Y1075578D01*
X586712Y1074564D01*
X586516Y1074603D01*
G37*
G36*
G01X583905Y1079919D02*
X583541Y1080137D01*
X583688Y1080872D01*
X584108Y1080933D01*
X584304Y1080894D01*
X584101Y1079879D01*
X583905Y1079919D01*
G37*
G36*
G01X584366Y1082223D02*
X584002Y1082441D01*
X584149Y1083176D01*
X584569Y1083238D01*
X584765Y1083198D01*
X584562Y1082184D01*
X584366Y1082223D01*
G37*
G36*
G01X584827Y1084527D02*
X584463Y1084745D01*
X584610Y1085481D01*
X585030Y1085542D01*
X585226Y1085503D01*
X585023Y1084488D01*
X584827Y1084527D01*
G37*
G36*
G01X585192Y1084311D02*
X585556Y1084093D01*
X585409Y1083358D01*
X584989Y1083297D01*
X584793Y1083336D01*
X584996Y1084351D01*
X585192Y1084311D01*
G37*
G36*
G01X584731Y1082007D02*
X585095Y1081789D01*
X584948Y1081053D01*
X584528Y1080992D01*
X584332Y1081031D01*
X584535Y1082046D01*
X584731Y1082007D01*
G37*
G36*
G01X585288Y1086831D02*
X584924Y1087050D01*
X585071Y1087785D01*
X585491Y1087846D01*
X585687Y1087807D01*
X585484Y1086792D01*
X585288Y1086831D01*
G37*
G36*
G01X585653Y1086616D02*
X586017Y1086398D01*
X585870Y1085662D01*
X585450Y1085601D01*
X585254Y1085640D01*
X585457Y1086655D01*
X585653Y1086616D01*
G37*
G36*
G01X585749Y1089136D02*
X585385Y1089354D01*
X585532Y1090089D01*
X585952Y1090151D01*
X586149Y1090111D01*
X585946Y1089097D01*
X585749Y1089136D01*
G37*
G36*
G01X586575Y1091224D02*
X586940Y1091006D01*
X586792Y1090271D01*
X586372Y1090209D01*
X586176Y1090249D01*
X586379Y1091264D01*
X586575Y1091224D01*
G37*
G36*
G01X586114Y1088920D02*
X586478Y1088702D01*
X586331Y1087966D01*
X585911Y1087905D01*
X585715Y1087944D01*
X585918Y1088959D01*
X586114Y1088920D01*
G37*
G36*
G01X586211Y1091440D02*
X585846Y1091658D01*
X585993Y1092394D01*
X586414Y1092455D01*
X586610Y1092416D01*
X586407Y1091401D01*
X586211Y1091440D01*
G37*
G36*
G01X587086Y1081536D02*
X587450Y1081318D01*
X587303Y1080582D01*
X586883Y1080521D01*
X586687Y1080560D01*
X586890Y1081575D01*
X587086Y1081536D01*
G37*
G36*
G01X586721Y1081752D02*
X586357Y1081970D01*
X586504Y1082705D01*
X586924Y1082766D01*
X587120Y1082727D01*
X586917Y1081712D01*
X586721Y1081752D01*
G37*
G36*
G01X587547Y1083840D02*
X587911Y1083622D01*
X587764Y1082887D01*
X587344Y1082825D01*
X587148Y1082865D01*
X587351Y1083879D01*
X587547Y1083840D01*
G37*
G36*
G01X587182Y1084056D02*
X586818Y1084274D01*
X586965Y1085010D01*
X587385Y1085071D01*
X587581Y1085032D01*
X587378Y1084017D01*
X587182Y1084056D01*
G37*
G36*
G01X588008Y1086145D02*
X588372Y1085926D01*
X588225Y1085191D01*
X587805Y1085130D01*
X587609Y1085169D01*
X587812Y1086184D01*
X588008Y1086145D01*
G37*
G36*
G01X588469Y1088449D02*
X588833Y1088231D01*
X588686Y1087495D01*
X588266Y1087434D01*
X588070Y1087473D01*
X588273Y1088488D01*
X588469Y1088449D01*
G37*
G36*
G01X587643Y1086360D02*
X587279Y1086578D01*
X587426Y1087314D01*
X587846Y1087375D01*
X588042Y1087336D01*
X587839Y1086321D01*
X587643Y1086360D01*
G37*
G36*
G01X588104Y1088665D02*
X587740Y1088883D01*
X587887Y1089618D01*
X588307Y1089679D01*
X588503Y1089640D01*
X588300Y1088625D01*
X588104Y1088665D01*
G37*
G36*
G01X585083Y1079683D02*
X584718Y1079901D01*
X584866Y1080636D01*
X585286Y1080698D01*
X585482Y1080658D01*
X585279Y1079644D01*
X585083Y1079683D01*
G37*
G36*
G01X585909Y1081771D02*
X586273Y1081553D01*
X586126Y1080818D01*
X585705Y1080757D01*
X585509Y1080796D01*
X585712Y1081811D01*
X585909Y1081771D01*
G37*
G36*
G01X586370Y1084076D02*
X586734Y1083858D01*
X586587Y1083122D01*
X586167Y1083061D01*
X585970Y1083100D01*
X586173Y1084115D01*
X586370Y1084076D01*
G37*
G36*
G01X586005Y1084291D02*
X585641Y1084510D01*
X585788Y1085245D01*
X586208Y1085306D01*
X586404Y1085267D01*
X586201Y1084252D01*
X586005Y1084291D01*
G37*
G36*
G01X585544Y1081987D02*
X585180Y1082205D01*
X585327Y1082941D01*
X585747Y1083002D01*
X585943Y1082963D01*
X585740Y1081948D01*
X585544Y1081987D01*
G37*
G36*
G01X587292Y1088684D02*
X587656Y1088466D01*
X587509Y1087731D01*
X587089Y1087670D01*
X586893Y1087709D01*
X587096Y1088724D01*
X587292Y1088684D01*
G37*
G36*
G01X587753Y1090989D02*
X588117Y1090771D01*
X587970Y1090035D01*
X587550Y1089974D01*
X587354Y1090013D01*
X587557Y1091028D01*
X587753Y1090989D01*
G37*
G36*
G01X586831Y1086380D02*
X587195Y1086162D01*
X587048Y1085426D01*
X586628Y1085365D01*
X586431Y1085404D01*
X586635Y1086419D01*
X586831Y1086380D01*
G37*
G36*
G01X586466Y1086596D02*
X586102Y1086814D01*
X586249Y1087549D01*
X586669Y1087611D01*
X586865Y1087571D01*
X586662Y1086557D01*
X586466Y1086596D01*
G37*
G36*
G01X586927Y1088900D02*
X586563Y1089118D01*
X586710Y1089854D01*
X587130Y1089915D01*
X587326Y1089876D01*
X587123Y1088861D01*
X586927Y1088900D01*
G37*
G36*
G01X588724Y1083605D02*
X589089Y1083386D01*
X588941Y1082651D01*
X588521Y1082590D01*
X588325Y1082629D01*
X588528Y1083644D01*
X588724Y1083605D01*
G37*
G36*
G01X588263Y1081300D02*
X588628Y1081082D01*
X588481Y1080347D01*
X588060Y1080285D01*
X587864Y1080324D01*
X588067Y1081339D01*
X588263Y1081300D01*
G37*
G36*
G01X587899Y1081516D02*
X587534Y1081734D01*
X587681Y1082470D01*
X588102Y1082531D01*
X588298Y1082492D01*
X588095Y1081477D01*
X587899Y1081516D01*
G37*
G36*
G01X588359Y1083820D02*
X587995Y1084038D01*
X588142Y1084774D01*
X588562Y1084835D01*
X588759Y1084796D01*
X588556Y1083781D01*
X588359Y1083820D01*
G37*
G36*
G01X589185Y1085909D02*
X589549Y1085691D01*
X589402Y1084955D01*
X588982Y1084894D01*
X588786Y1084933D01*
X588989Y1085948D01*
X589185Y1085909D01*
G37*
G36*
G01X589646Y1088213D02*
X590010Y1087995D01*
X589863Y1087260D01*
X589443Y1087198D01*
X589247Y1087238D01*
X589450Y1088252D01*
X589646Y1088213D01*
G37*
G36*
G01X588820Y1086125D02*
X588456Y1086343D01*
X588603Y1087078D01*
X589023Y1087140D01*
X589219Y1087100D01*
X589016Y1086085D01*
X588820Y1086125D01*
G37*
G36*
G01X589281Y1088429D02*
X588917Y1088647D01*
X589064Y1089383D01*
X589484Y1089444D01*
X589680Y1089405D01*
X589477Y1088390D01*
X589281Y1088429D01*
G37*
G36*
G01X582629Y1102377D02*
X582993Y1102159D01*
X582846Y1101424D01*
X582426Y1101362D01*
X582230Y1101402D01*
X582433Y1102417D01*
X582629Y1102377D01*
G37*
G36*
G01X583090Y1104682D02*
X583454Y1104464D01*
X583307Y1103728D01*
X582887Y1103667D01*
X582691Y1103706D01*
X582894Y1104721D01*
X583090Y1104682D01*
G37*
G36*
G01X598549Y1580678D02*
G03I-720J0D01*
G37*
G36*
G01X593593D02*
G03I-720J0D01*
G37*
G36*
G01X598549Y1575686D02*
G03I-720J0D01*
G37*
G36*
G01X593593D02*
G03I-720J0D01*
G37*
G36*
G01X586489D02*
G03I-720J0D01*
G37*
G36*
G01Y1580678D02*
G03I-720J0D01*
G37*
G36*
G01X598893Y1599884D02*
G03I-720J0D01*
G37*
G36*
G01X586833D02*
G03I-720J0D01*
G37*
G36*
G01X591789D02*
G03I-720J0D01*
G37*
G36*
G01X598549Y1592590D02*
G03I-720J0D01*
G37*
G36*
G01X593593D02*
G03I-720J0D01*
G37*
G36*
G01X598549Y1587598D02*
G03I-720J0D01*
G37*
G36*
G01X593593D02*
G03I-720J0D01*
G37*
G36*
G01X586489D02*
G03I-720J0D01*
G37*
G36*
G01Y1592590D02*
G03I-720J0D01*
G37*
G36*
G01X598893Y1616788D02*
G03I-720J0D01*
G37*
G36*
G01Y1611796D02*
G03I-720J0D01*
G37*
G36*
G01Y1604876D02*
G03I-720J0D01*
G37*
G36*
G01X586833D02*
G03I-720J0D01*
G37*
G36*
G01X591789D02*
G03I-720J0D01*
G37*
G36*
G01X586833Y1611796D02*
G03I-720J0D01*
G37*
G36*
G01X591789D02*
G03I-720J0D01*
G37*
G36*
G01Y1616788D02*
G03I-720J0D01*
G37*
G36*
G01X586833D02*
G03I-720J0D01*
G37*
G36*
G01X608610Y34389D02*
G03I-720J0D01*
G37*
G36*
G01X605780Y42402D02*
G03I-720J0D01*
G37*
G36*
G01X601770Y100008D02*
G03I-720J0D01*
G37*
G36*
G01X611750Y188372D02*
G03I-720J0D01*
G37*
G36*
G01X612030Y266272D02*
G03I-720J0D01*
G37*
G36*
G01X610564Y330407D02*
G03I-720J0D01*
G37*
G36*
G01X609550Y374302D02*
G03I-720J0D01*
G37*
G36*
G01X614741Y452862D02*
G03I-521J0D01*
G37*
G36*
G01X608310Y497620D02*
X644460D01*
X645300Y496780D01*
Y487280D01*
X644430Y486410D01*
X631055D01*
G02X630669Y486915I0J400D01*
G03X630722Y487310I-1449J395D01*
G03X627718I-1502J0D01*
G03X627771Y486915I1502J0D01*
G02X627385Y486410I-386J-105D01*
G01X625530D01*
X625356Y486236D01*
X625090D01*
G03X624272Y485898I-1J-1156D01*
G01X622214Y483840D01*
X607730D01*
X607330Y484240D01*
Y496640D01*
X608310Y497620D01*
G37*
G36*
G01X634898Y508970D02*
X638540D01*
X639440Y508070D01*
Y500660D01*
X638460Y499680D01*
X608240D01*
X607220Y500700D01*
Y507920D01*
X608270Y508970D01*
X627970D01*
X627980Y508781D01*
G03X630980I1500J81D01*
G01X630990Y508970D01*
X631499D01*
Y508762D01*
G03X631498Y508700I1501J-55D01*
G03X633000Y507198I1502J0D01*
G03X634498Y508597I0J1502D01*
G02X634898Y508970I399J-27D01*
G37*
G36*
G01X603932Y738415D02*
G03I-615J0D01*
G37*
G36*
G01X615275Y739553D02*
G03I-615J0D01*
G37*
G36*
G01X602642Y761445D02*
G03I-615J0D01*
G37*
G36*
G01X611960Y1311012D02*
X817820D01*
X833230Y1295602D01*
Y1285425D01*
X836816Y1281838D01*
X850844D01*
X853153Y1279529D01*
Y1261639D01*
X852577Y1261064D01*
X838746D01*
X836586Y1263224D01*
X836571Y1263266D01*
G03X836267Y1263570I-472J-168D01*
G01X836225Y1263585D01*
X835446Y1264364D01*
X827746D01*
X826857Y1263475D01*
X826772Y1263476D01*
X826750D01*
G03X825348Y1262074I0J-1402D01*
G01Y1262052D01*
X825349Y1261967D01*
X824446Y1261064D01*
X810346D01*
X807046Y1264364D01*
X797346D01*
X796358Y1263376D01*
X796323Y1263360D01*
G03X795594Y1262631I557J-1286D01*
G01X795578Y1262596D01*
X794046Y1261064D01*
X781046D01*
X777746Y1264364D01*
X767546D01*
X766558Y1263376D01*
X766523Y1263360D01*
G03X765794Y1262631I557J-1286D01*
G01X765778Y1262596D01*
X764246Y1261064D01*
X755065D01*
X754329Y1261800D01*
X754314Y1261841D01*
G03X753000Y1262754I-1314J-489D01*
G03X751601Y1261439I0J-1402D01*
G02X751202Y1261064I-399J25D01*
G01X750846D01*
X747546Y1264364D01*
X740946D01*
X740346Y1263764D01*
X738346D01*
X737999Y1263417D01*
X737891Y1263441D01*
G03X737580Y1263476I-311J-1367D01*
G03X736178Y1262074I0J-1402D01*
G03X736213Y1261763I1402J0D01*
G01X736237Y1261655D01*
X735646Y1261064D01*
X721346D01*
X718046Y1264364D01*
X711446D01*
X710646Y1263564D01*
X708346D01*
X708252Y1263470D01*
X708163Y1263474D01*
G03X708090Y1263476I-75J-1400D01*
G03X706688Y1262074I0J-1402D01*
G03X706690Y1262001I1402J2D01*
G01X706694Y1261912D01*
X705846Y1261064D01*
X697946D01*
X697246Y1260364D01*
X697075D01*
X695429Y1262010D01*
X695414Y1262051D01*
G03X694100Y1262964I-1314J-489D01*
G03X692698Y1261562I0J-1402D01*
G03X693003Y1260689I1402J0D01*
G02X692847Y1260364I-156J-125D01*
G01X692446D01*
X688446Y1264364D01*
X679346D01*
X678399Y1263417D01*
X678291Y1263441D01*
G03X677980Y1263476I-311J-1367D01*
G03X676578Y1262074I0J-1402D01*
G03X676613Y1261763I1402J0D01*
G01X676637Y1261655D01*
X676046Y1261064D01*
X666446D01*
X663046Y1264464D01*
X662438D01*
G03X660362I-1038J-941D01*
G01X650546D01*
X648204Y1262122D01*
X648090Y1262156D01*
G03X647690Y1262214I-399J-1344D01*
G03X646376Y1261301I0J-1402D01*
G01X646361Y1261260D01*
X645965Y1260864D01*
X633690D01*
G02X633332Y1261444I-1J400D01*
G03X633482Y1262074I-1252J631D01*
G03X632080Y1263476I-1402J0D01*
G03X631496Y1263349I-1J-1402D01*
G01X631457Y1263330D01*
X630480D01*
X629446Y1264364D01*
X611388D01*
X610237Y1265515D01*
Y1309289D01*
X611960Y1311012D01*
G37*
G36*
G01X610609Y1575686D02*
G03I-720J0D01*
G37*
G36*
G01X605653D02*
G03I-720J0D01*
G37*
G36*
G01X610609Y1580678D02*
G03I-720J0D01*
G37*
G36*
G01X605653D02*
G03I-720J0D01*
G37*
G36*
G01X610953Y1599884D02*
G03I-720J0D01*
G37*
G36*
G01X603849D02*
G03I-720J0D01*
G37*
G36*
G01X610609Y1587598D02*
G03I-720J0D01*
G37*
G36*
G01X605653D02*
G03I-720J0D01*
G37*
G36*
G01X610609Y1592590D02*
G03I-720J0D01*
G37*
G36*
G01X605653D02*
G03I-720J0D01*
G37*
G36*
G01X610953Y1604876D02*
G03I-720J0D01*
G37*
G36*
G01Y1611796D02*
G03I-720J0D01*
G37*
G36*
G01Y1616788D02*
G03I-720J0D01*
G37*
G36*
G01X603849D02*
G03I-720J0D01*
G37*
G36*
G01Y1611796D02*
G03I-720J0D01*
G37*
G36*
G01Y1604876D02*
G03I-720J0D01*
G37*
G36*
G01X616140Y42342D02*
G03I-720J0D01*
G37*
G36*
G01X616292Y173942D02*
G03I-720J0D01*
G37*
G36*
G01X616293Y181984D02*
G03I-720J0D01*
G37*
G36*
G01X628915Y178414D02*
G03I-720J0D01*
G37*
G36*
G01X628914Y170372D02*
G03I-720J0D01*
G37*
G36*
G01X631538Y191248D02*
G03I-720J0D01*
G37*
G36*
G01X626582D02*
G03I-720J0D01*
G37*
G36*
G01X620750Y188782D02*
G03I-720J0D01*
G37*
G36*
G01X650620Y222362D02*
X669820D01*
X670520Y221662D01*
Y218562D01*
X670120Y218162D01*
X663920D01*
X663020Y217262D01*
Y216053D01*
G02X662607Y215653I-400J0D01*
G03X662560Y215654I-55J-1501D01*
G03X661058Y214152I0J-1502D01*
G03X662201Y212694I1501J0D01*
G01X662255Y212680D01*
X663029Y211907D01*
G03X663436Y211634I890J887D01*
G01X663473Y211619D01*
X663720Y211372D01*
X670240D01*
X670710Y210902D01*
Y204692D01*
X670350Y204332D01*
X664320D01*
X662920Y202932D01*
Y196402D01*
X660884Y194366D01*
X652030D01*
G03X651142Y193998I0J-1255D01*
G01X650855Y193712D01*
X633830D01*
X632810Y194732D01*
G03X631780Y195158I-1029J-1030D01*
G01X627710D01*
Y209222D01*
X627960Y209472D01*
X631800D01*
X633560Y207712D01*
X646220D01*
Y207762D01*
X650220Y211762D01*
Y221962D01*
X650620Y222362D01*
G37*
G36*
G01X627450Y211262D02*
Y215822D01*
X626090Y217182D01*
Y225082D01*
X626520Y225512D01*
X646480D01*
X647990Y224002D01*
Y213812D01*
X645050Y210872D01*
X627840D01*
X627450Y211262D01*
G37*
G36*
G01X622460Y265952D02*
G03I-720J0D01*
G37*
G36*
G01X629014Y317007D02*
G03I-720J0D01*
G37*
G36*
G01X624300Y336429D02*
G03I-720J0D01*
G37*
G36*
G01X738351Y1420295D02*
X750416D01*
X750475Y1420237D01*
X753242Y1417470D01*
X753300Y1417411D01*
Y1374125D01*
G03X753359Y1373983I200J0D01*
G01X756020Y1371322D01*
G03X756162Y1371263I142J141D01*
G01X764968D01*
X765027Y1371205D01*
X766562Y1369670D01*
X766620Y1369611D01*
Y1314882D01*
X766561Y1314823D01*
X764649Y1312911D01*
X764590Y1312852D01*
X616570D01*
X616511Y1312911D01*
X615119Y1314303D01*
X615060Y1314362D01*
Y1388761D01*
X615118Y1388820D01*
X616116Y1389818D01*
X616175Y1389876D01*
X658337D01*
G03X658479Y1389935I0J200D01*
G01X659172Y1390628D01*
X659231Y1390686D01*
X665585D01*
X665644Y1390628D01*
X667219Y1389053D01*
G03X667361Y1388994I142J141D01*
G01X673279D01*
G03X673421Y1389053I0J200D01*
G01X673491Y1389123D01*
G03X673550Y1389265I-141J142D01*
G01Y1392719D01*
G03X673491Y1392861I-200J0D01*
G01X673459Y1392893D01*
G03X673317Y1392952I-142J-141D01*
G01X669603D01*
X669544Y1393011D01*
X669242Y1393313D01*
G03X669100Y1393372I-142J-141D01*
G01X667710D01*
Y1394262D01*
X669463D01*
G03X669605Y1394321I0J200D01*
G01X669888Y1394604D01*
X670090Y1394807D01*
G03X670133Y1394871I-141J141D01*
G01X670162Y1394940D01*
G03X670177Y1395016I-185J76D01*
G01Y1395017D01*
Y1398255D01*
Y1398256D01*
G03X670162Y1398332I-200J0D01*
G01X670133Y1398400D01*
Y1398401D01*
G03X670090Y1398465I-184J-77D01*
G01X670064Y1398491D01*
G03X670000Y1398534I-141J-141D01*
G01X669999D01*
X669931Y1398563D01*
G03X669855Y1398578I-76J-185D01*
G01X669854D01*
X666900D01*
X666858D01*
X666677Y1398656D01*
Y1399471D01*
Y1399513D01*
X666755Y1399694D01*
X669854D01*
X669855D01*
G03X669931Y1399709I0J200D01*
G01X669999Y1399738D01*
X670000D01*
G03X670064Y1399781I-77J184D01*
G01X670090Y1399807D01*
G03X670133Y1399871I-141J141D01*
G01Y1399872D01*
X670162Y1399940D01*
G03X670177Y1400016I-185J76D01*
G01Y1400017D01*
Y1400671D01*
Y1400712D01*
X670237Y1400854D01*
X670317Y1400934D01*
X670459Y1400994D01*
X670500D01*
X677054D01*
X677095D01*
X677237Y1400934D01*
X677402Y1400769D01*
X677460Y1400710D01*
Y1392272D01*
G03X677519Y1392130I200J0D01*
G01X677868Y1391781D01*
G03X678010Y1391722I142J141D01*
G01X687047D01*
G03X687159Y1391757I-1J200D01*
G01X687210Y1391791D01*
X691774D01*
X691785Y1391781D01*
X691792Y1391788D01*
X696727D01*
G03X696869Y1391847I0J200D01*
G01X697472Y1392450D01*
G03X697531Y1392592I-141J142D01*
G01Y1401568D01*
G03X697472Y1401710I-200J0D01*
G01X695496Y1403686D01*
X695437Y1403745D01*
Y1412512D01*
X695495Y1412571D01*
X697796Y1414872D01*
X697855Y1414930D01*
X700087D01*
X700146Y1414872D01*
X700267Y1414751D01*
X700325Y1414692D01*
Y1405324D01*
X700266Y1405265D01*
X699780Y1404779D01*
G03X699721Y1404637I141J-142D01*
G01Y1391442D01*
G03X699780Y1391300I200J0D01*
G01X700272Y1390808D01*
G03X700414Y1390749I142J141D01*
G01X703652D01*
X703711Y1390691D01*
X705349Y1389053D01*
G03X705491Y1388994I142J141D01*
G01X711422D01*
G03X711564Y1389053I0J200D01*
G01X711661Y1389150D01*
G03X711720Y1389292I-141J142D01*
G01Y1392659D01*
G03X711661Y1392801I-200J0D01*
G01X711569Y1392893D01*
G03X711427Y1392952I-142J-141D01*
G01X707746D01*
X707687Y1393011D01*
X707607Y1393091D01*
G03X707543Y1393134I-141J-141D01*
G01X707542D01*
X707474Y1393163D01*
G03X707398Y1393178I-76J-185D01*
G01X707397D01*
X704843D01*
X704801D01*
X704620Y1393256D01*
Y1394171D01*
Y1394212D01*
X704680Y1394354D01*
X704819Y1394493D01*
X707136D01*
G03X707168Y1394494I-6J698D01*
G01X707172D01*
X707797D01*
X707798D01*
G03X707874Y1394509I0J200D01*
G01X707942Y1394538D01*
X707943D01*
G03X708007Y1394581I-77J184D01*
G01X708233Y1394807D01*
G03X708276Y1394871I-141J141D01*
G01Y1394872D01*
X708305Y1394940D01*
G03X708320Y1395016I-185J76D01*
G01Y1395017D01*
Y1398255D01*
Y1398256D01*
G03X708305Y1398332I-200J0D01*
G01X708276Y1398400D01*
Y1398401D01*
G03X708233Y1398465I-184J-77D01*
G01X708207Y1398491D01*
G03X708143Y1398534I-141J-141D01*
G01X708142D01*
X708074Y1398563D01*
G03X707998Y1398578I-76J-185D01*
G01X707997D01*
X705043D01*
X705001D01*
X704820Y1398656D01*
Y1399471D01*
Y1399513D01*
X704898Y1399694D01*
X707997D01*
X707998D01*
G03X708074Y1399709I0J200D01*
G01X708142Y1399738D01*
X708143D01*
G03X708207Y1399781I-77J184D01*
G01X708233Y1399807D01*
G03X708276Y1399871I-141J141D01*
G01Y1399872D01*
X708305Y1399940D01*
G03X708320Y1400016I-185J76D01*
G01Y1400017D01*
Y1400671D01*
Y1400712D01*
X708380Y1400854D01*
X708460Y1400934D01*
X708602Y1400994D01*
X708643D01*
X715197D01*
X715238D01*
X715380Y1400934D01*
X715545Y1400769D01*
X715603Y1400710D01*
Y1392272D01*
G03X715662Y1392130I200J0D01*
G01X716001Y1391791D01*
G03X716143Y1391732I142J141D01*
G01X725147D01*
G03X725252Y1391762I0J200D01*
G01X725300Y1391791D01*
X729917D01*
X729928Y1391781D01*
X729935Y1391788D01*
X735780D01*
G03X735922Y1391847I0J200D01*
G01X736891Y1392816D01*
G03X736950Y1392958I-141J142D01*
G01Y1418894D01*
X737008Y1418953D01*
X738292Y1420237D01*
X738351Y1420295D01*
G37*
G36*
G01X629773Y1575686D02*
G03I-720J0D01*
G37*
G36*
G01Y1580678D02*
G03I-720J0D01*
G37*
G36*
G01X622669D02*
G03I-720J0D01*
G37*
G36*
G01X617713D02*
G03I-720J0D01*
G37*
G36*
G01X622669Y1575686D02*
G03I-720J0D01*
G37*
G36*
G01X617713D02*
G03I-720J0D01*
G37*
G36*
G01X615909Y1599884D02*
G03I-720J0D01*
G37*
G36*
G01X623013D02*
G03I-720J0D01*
G37*
G36*
G01X627969D02*
G03I-720J0D01*
G37*
G36*
G01X629773Y1587598D02*
G03I-720J0D01*
G37*
G36*
G01Y1592590D02*
G03I-720J0D01*
G37*
G36*
G01X622669D02*
G03I-720J0D01*
G37*
G36*
G01X617713D02*
G03I-720J0D01*
G37*
G36*
G01X622669Y1587598D02*
G03I-720J0D01*
G37*
G36*
G01X617713D02*
G03I-720J0D01*
G37*
G36*
G01X615909Y1604876D02*
G03I-720J0D01*
G37*
G36*
G01Y1611796D02*
G03I-720J0D01*
G37*
G36*
G01Y1616788D02*
G03I-720J0D01*
G37*
G36*
G01X627969D02*
G03I-720J0D01*
G37*
G36*
G01X623013D02*
G03I-720J0D01*
G37*
G36*
G01Y1611796D02*
G03I-720J0D01*
G37*
G36*
G01X627969D02*
G03I-720J0D01*
G37*
G36*
G01X623013Y1604876D02*
G03I-720J0D01*
G37*
G36*
G01X627969D02*
G03I-720J0D01*
G37*
G36*
G01X647160Y43632D02*
G03I-720J0D01*
G37*
G36*
G01X633183Y43302D02*
G03I-720J0D01*
G37*
G36*
G01X646070Y60612D02*
G03I-720J0D01*
G37*
G36*
G01X632266Y85024D02*
G03I-720J0D01*
G37*
G36*
G01X633360Y107532D02*
G03I-720J0D01*
G37*
G36*
G01X638220Y110362D02*
G03I-720J0D01*
G37*
G36*
G01X646596Y296231D02*
G03I-720J0D01*
G37*
G36*
G01X633858Y296766D02*
G03I-720J0D01*
G37*
G36*
G01X646248Y308623D02*
G03I-720J0D01*
G37*
G36*
G01X646527Y304291D02*
G03I-720J0D01*
G37*
G36*
G01X647920Y354300D02*
G03I-720J0D01*
G37*
G36*
G01X644257Y457214D02*
G03I-521J0D01*
G37*
G36*
G01X646789Y1580678D02*
G03I-720J0D01*
G37*
G36*
G01X641833D02*
G03I-720J0D01*
G37*
G36*
G01X646789Y1575592D02*
G03I-720J0D01*
G37*
G36*
G01X641833D02*
G03I-720J0D01*
G37*
G36*
G01X634729Y1575686D02*
G03I-720J0D01*
G37*
G36*
G01Y1580678D02*
G03I-720J0D01*
G37*
G36*
G01X647133Y1599790D02*
G03I-720J0D01*
G37*
G36*
G01X640029Y1599884D02*
G03I-720J0D01*
G37*
G36*
G01X635073D02*
G03I-720J0D01*
G37*
G36*
G01X646789Y1592590D02*
G03I-720J0D01*
G37*
G36*
G01X641833D02*
G03I-720J0D01*
G37*
G36*
G01X646789Y1587598D02*
G03I-720J0D01*
G37*
G36*
G01X641833D02*
G03I-720J0D01*
G37*
G36*
G01X634729D02*
G03I-720J0D01*
G37*
G36*
G01Y1592590D02*
G03I-720J0D01*
G37*
G36*
G01X647133Y1616788D02*
G03I-720J0D01*
G37*
G36*
G01Y1611796D02*
G03I-720J0D01*
G37*
G36*
G01Y1604876D02*
G03I-720J0D01*
G37*
G36*
G01X640029D02*
G03I-720J0D01*
G37*
G36*
G01X635073D02*
G03I-720J0D01*
G37*
G36*
G01X640029Y1611796D02*
G03I-720J0D01*
G37*
G36*
G01X635073D02*
G03I-720J0D01*
G37*
G36*
G01Y1616788D02*
G03I-720J0D01*
G37*
G36*
G01X640029D02*
G03I-720J0D01*
G37*
G36*
G01X641548Y1648659D02*
G03I-491J0D01*
G37*
G36*
G01X645898Y1660425D02*
G03I-491J0D01*
G37*
G36*
G01X655184Y45133D02*
G03I-720J0D01*
G37*
G36*
G01X661215Y154332D02*
X670380D01*
X670780Y153932D01*
Y145732D01*
X668990Y143942D01*
X662140D01*
X660520Y145562D01*
Y153637D01*
X661215Y154332D01*
G37*
G36*
G01X655326Y1431203D02*
G03I-720J0D01*
G37*
G36*
G01X653893Y1575686D02*
G03I-720J0D01*
G37*
G36*
G01X658849D02*
G03I-720J0D01*
G37*
G36*
G01X653893Y1580678D02*
G03I-720J0D01*
G37*
G36*
G01X658849D02*
G03I-720J0D01*
G37*
G36*
G01X664149Y1599884D02*
G03I-720J0D01*
G37*
G36*
G01X659193D02*
G03I-720J0D01*
G37*
G36*
G01X652089Y1599790D02*
G03I-720J0D01*
G37*
G36*
G01X653893Y1587598D02*
G03I-720J0D01*
G37*
G36*
G01X658849D02*
G03I-720J0D01*
G37*
G36*
G01X653893Y1592590D02*
G03I-720J0D01*
G37*
G36*
G01X658849D02*
G03I-720J0D01*
G37*
G36*
G01X664149Y1604876D02*
G03I-720J0D01*
G37*
G36*
G01X659193D02*
G03I-720J0D01*
G37*
G36*
G01X664149Y1611796D02*
G03I-720J0D01*
G37*
G36*
G01X659193D02*
G03I-720J0D01*
G37*
G36*
G01Y1616788D02*
G03I-720J0D01*
G37*
G36*
G01X664149D02*
G03I-720J0D01*
G37*
G36*
G01X652089D02*
G03I-720J0D01*
G37*
G36*
G01Y1611796D02*
G03I-720J0D01*
G37*
G36*
G01Y1604876D02*
G03I-720J0D01*
G37*
G36*
G01X655798Y1647436D02*
G03I-491J0D01*
G37*
G36*
G01X653203Y1686275D02*
G03I-491J0D01*
G37*
G36*
G01X657464Y1698727D02*
G03I-491J0D01*
G37*
G36*
G01X672725Y44119D02*
G03I-720J0D01*
G37*
G36*
G01X675945Y58108D02*
G03I-720J0D01*
G37*
G36*
G01X674470Y77692D02*
G03I-720J0D01*
G37*
G36*
G01X691520Y75362D02*
X691040Y74882D01*
X688820D01*
X688130Y75572D01*
X685020D01*
X680940Y79652D01*
X679720D01*
X677950Y81422D01*
Y86622D01*
X678230D01*
X678500Y86892D01*
X687230D01*
X688230Y85892D01*
Y81022D01*
X691520Y77732D01*
Y75362D01*
G37*
G36*
G01X679453Y109768D02*
X681953D01*
X682053Y109668D01*
Y99068D01*
X682853Y98268D01*
X686253D01*
X686553Y97968D01*
Y94968D01*
X686053Y94468D01*
X681153D01*
X679253Y96368D01*
Y104539D01*
X679258Y104560D01*
G03X679292Y104880I-1468J318D01*
G03X679258Y105200I-1502J2D01*
G01X679253Y105221D01*
Y109568D01*
X679453Y109768D01*
G37*
G36*
G01X677253Y121268D02*
X680953D01*
X681353Y120868D01*
Y114568D01*
X681253Y114468D01*
X677253D01*
X676553Y115168D01*
Y115993D01*
G03X677062Y117120I-993J1127D01*
G03X676816Y117943I-1502J-1D01*
G01Y120832D01*
X677253Y121268D01*
G37*
G36*
G01X694146Y1443425D02*
X721510D01*
X735894Y1429041D01*
Y1392802D01*
X717025D01*
X716758Y1393068D01*
Y1401111D01*
X716848Y1401201D01*
X722196D01*
X722856Y1401861D01*
Y1404472D01*
X724330Y1405946D01*
Y1413650D01*
X721880Y1416100D01*
X697495D01*
X694481Y1413086D01*
Y1403165D01*
X696450Y1401196D01*
Y1393002D01*
X696250Y1392802D01*
X678710D01*
X678616Y1392897D01*
Y1400666D01*
G03X678809Y1401116I-5649J2689D01*
G01X678887Y1401194D01*
X684233D01*
X684751Y1401712D01*
Y1404544D01*
G03X684743Y1404652I-799J-5D01*
G01X684729Y1404751D01*
X686264Y1406287D01*
Y1418335D01*
X689197Y1421268D01*
Y1438475D01*
X690618Y1439897D01*
X694146Y1443425D01*
G37*
G36*
G01X668417Y1547018D02*
G03I-491J0D01*
G37*
G36*
G01X679683Y1564252D02*
G03I-491J0D01*
G37*
G36*
G01X679006Y1573910D02*
G03I-491J0D01*
G37*
G36*
G01X693100Y43532D02*
G03I-720J0D01*
G37*
G36*
G01X683610Y72642D02*
G03I-720J0D01*
G37*
G36*
G01X693480Y110122D02*
X711480D01*
X711490Y110112D01*
X722483D01*
X723933Y108662D01*
Y87888D01*
X726733Y85088D01*
X728011D01*
X728018Y84895D01*
G03X728573Y83619I1900J68D01*
G01X729475Y82717D01*
G03X730820Y82160I1345J1345D01*
G03X732722Y84062I0J1902D01*
G03X732650Y84579I-1902J-1D01*
G02X733035Y85088I385J109D01*
G01X740433D01*
X746503Y91158D01*
Y94314D01*
X746507Y94333D01*
G03X746537Y94632I-1472J299D01*
G03X746507Y94931I-1502J0D01*
G01X746503Y94950D01*
Y104148D01*
X746743Y104388D01*
X747213D01*
X747463Y104138D01*
Y96838D01*
X748183Y96118D01*
X749753D01*
X750453Y96818D01*
Y102188D01*
X750673Y102408D01*
X751243D01*
X751433Y102218D01*
Y97478D01*
X752533Y96378D01*
Y75075D01*
X751620Y74162D01*
X729905D01*
G02X729523Y74682I0J400D01*
G03X729592Y75132I-1433J450D01*
G03X726588I-1502J0D01*
G03X726657Y74682I1502J0D01*
G02X726275Y74162I-382J-120D01*
G01X701927D01*
Y74392D01*
X701936Y74421D01*
G03X701958Y74503I-1439J430D01*
G01X701972Y74557D01*
X702445Y75030D01*
X702915D01*
X702961Y75004D01*
G03X703411Y74885I445J771D01*
G01Y74886D01*
X704589D01*
Y74885D01*
G03X705486Y75775I7J890D01*
G01Y76828D01*
X705250D01*
Y78210D01*
X705650Y78610D01*
X708345D01*
G02X708734Y78117I0J-400D01*
G03X708684Y77695I1752J-422D01*
G03X712288I1802J0D01*
G01Y77714D01*
G02X712653Y78117I400J5D01*
G03X714252Y79862I-153J1745D01*
G03X713738Y81100I-1751J-1D01*
G01X713238Y81600D01*
G03X712000Y82114I-1239J-1237D01*
G01X704925D01*
G03X703687Y81600I1J-1751D01*
G01X702762Y80675D01*
G03X702248Y79437I1237J-1239D01*
G03X702699Y78264I1751J0D01*
G01X702750Y78207D01*
Y77544D01*
X701925D01*
G03X701037Y77175I1J-1256D01*
G01X700195Y76334D01*
X700141Y76320D01*
G03X698998Y74862I358J-1458D01*
G03X699017Y74625I1502J1D01*
G02X698622Y74162I-395J-63D01*
G01X694120D01*
X692763Y75519D01*
Y78022D01*
X690620Y80165D01*
Y86269D01*
X692763Y88412D01*
Y103848D01*
X693098Y104184D01*
Y109740D01*
X693480Y110122D01*
G37*
G36*
G01X683553Y109768D02*
X685058D01*
X685870Y108957D01*
G03X686495Y108616I890J887D01*
G01X686653Y108582D01*
Y100468D01*
X686153Y99968D01*
X683253D01*
X683054Y100166D01*
Y109270D01*
X683553Y109768D01*
G37*
G36*
G01X690813Y110018D02*
X692096D01*
Y104598D01*
X691762Y104262D01*
Y90518D01*
X689313D01*
X688713Y91118D01*
Y103685D01*
X690513Y105485D01*
Y109718D01*
X690813Y110018D01*
G37*
G36*
G01X740110Y136528D02*
X744163D01*
X749493Y131198D01*
Y107536D01*
G03Y105748I1207J-894D01*
G01Y102644D01*
X749452Y102603D01*
Y97786D01*
X749213Y97548D01*
X748763D01*
X748553Y97758D01*
Y104268D01*
X748464Y104356D01*
Y104553D01*
X747628Y105390D01*
X746328D01*
X746267Y105328D01*
X746253D01*
X745503Y104578D01*
Y104564D01*
X745502Y104563D01*
Y99716D01*
X745313Y99528D01*
X744693D01*
X744563Y99658D01*
Y108998D01*
X742710Y110852D01*
Y111841D01*
G03X742708Y111894I-890J-7D01*
G01Y114784D01*
X742717Y114813D01*
G03X742756Y115072I-851J261D01*
G01Y116126D01*
X742708D01*
Y117064D01*
X741820Y117952D01*
X727790D01*
X720970Y111132D01*
X693150D01*
X692520Y111762D01*
Y115992D01*
X693150Y116622D01*
X699790D01*
X699850Y116562D01*
X708900D01*
X715382Y123044D01*
Y135350D01*
X716559Y136528D01*
X737090D01*
X737117Y136360D01*
G03X740083I1483J240D01*
G01X740110Y136528D01*
G37*
G36*
G01X691946Y121066D02*
X692190Y120822D01*
Y118102D01*
X691940Y117852D01*
X682990D01*
X682500Y118342D01*
Y121032D01*
Y125010D01*
X682840Y125350D01*
X684930D01*
X686820D01*
X691084Y121086D01*
X691926D01*
X691946Y121066D01*
G37*
G36*
G01X703953Y129868D02*
X703553Y130268D01*
X682433D01*
X682093Y130608D01*
Y138808D01*
X682653Y139368D01*
X705724D01*
X706750Y138342D01*
Y130582D01*
X706036Y129868D01*
X703953D01*
G37*
G36*
G01X683030Y152482D02*
X684010Y153462D01*
X701370D01*
X702990Y151842D01*
Y144122D01*
X701000Y142132D01*
X685090D01*
X683030Y144192D01*
Y152482D01*
G37*
G36*
G01X684972Y742345D02*
G03I-615J0D01*
G37*
G36*
G01X690366Y1577913D02*
G03I-491J0D01*
G37*
G36*
G01X697558Y45112D02*
G03I-720J0D01*
G37*
G36*
G01X702558D02*
G03I-720J0D01*
G37*
G36*
G01X701330Y57782D02*
G03I-720J0D01*
G37*
G36*
G01X702532Y742865D02*
G03I-615J0D01*
G37*
G36*
G01X709602Y1618842D02*
G03I-491J0D01*
G37*
G36*
G01X704924Y1657964D02*
G03I-491J0D01*
G37*
G36*
G01X726094Y-23978D02*
G03I-557J0D01*
G37*
G36*
G01Y-19022D02*
G03I-557J0D01*
G37*
G36*
G01Y-13978D02*
G03I-557J0D01*
G37*
G36*
G01Y-9022D02*
G03I-557J0D01*
G37*
G36*
G01X729700Y39872D02*
G03I-720J0D01*
G37*
G36*
G01X735870Y116812D02*
X738410D01*
X739133Y116089D01*
Y110188D01*
X738933Y109988D01*
X729733D01*
X729598Y109853D01*
X729546Y109839D01*
G03X728431Y108388I387J-1451D01*
G03X729417Y106977I1503J0D01*
G01X729459Y106962D01*
X729533Y106888D01*
X729860D01*
G03X729933Y106886I78J1500D01*
G03X730006Y106888I-5J1502D01*
G01X731493D01*
X731923Y106458D01*
Y100958D01*
X731994Y100888D01*
Y100718D01*
X732162D01*
X732433Y100448D01*
X735836D01*
G03X737604I884J1213D01*
G01X742173D01*
X742603Y100878D01*
Y102138D01*
X742893Y102428D01*
X743223D01*
X743523Y102128D01*
Y99688D01*
X743363Y99528D01*
X740523D01*
X737853Y96858D01*
X731765D01*
X731223Y96316D01*
Y93858D01*
X731023Y93658D01*
X725463D01*
X725133Y93988D01*
Y112645D01*
X725920Y113432D01*
X733860D01*
X734740Y114312D01*
Y115682D01*
X735870Y116812D01*
G37*
G36*
G01X719914Y172909D02*
G03I-720J0D01*
G37*
G36*
G01X714922D02*
G03I-720J0D01*
G37*
G36*
G01X719914Y177865D02*
G03I-720J0D01*
G37*
G36*
G01X714922D02*
G03I-720J0D01*
G37*
G36*
G01X719914Y184909D02*
G03I-720J0D01*
G37*
G36*
G01X714922D02*
G03I-720J0D01*
G37*
G36*
G01X719914Y189865D02*
G03I-720J0D01*
G37*
G36*
G01X714922D02*
G03I-720J0D01*
G37*
G36*
G01X719914Y196409D02*
G03I-720J0D01*
G37*
G36*
G01X714922D02*
G03I-720J0D01*
G37*
G36*
G01X719914Y201365D02*
G03I-720J0D01*
G37*
G36*
G01X714922D02*
G03I-720J0D01*
G37*
G36*
G01X719914Y208243D02*
G03I-720J0D01*
G37*
G36*
G01X714922D02*
G03I-720J0D01*
G37*
G36*
G01X719914Y213199D02*
G03I-720J0D01*
G37*
G36*
G01X714922D02*
G03I-720J0D01*
G37*
G36*
G01X721670Y1583410D02*
X727360D01*
X727630Y1583140D01*
Y1579120D01*
X727340Y1578830D01*
X721530D01*
X721290Y1579070D01*
Y1583030D01*
X721670Y1583410D01*
G37*
G36*
G01X718721Y1600372D02*
G03I-491J0D01*
G37*
G36*
G01X725063Y1588950D02*
G03X725120Y1588554I1402J0D01*
G01Y1584412D01*
X721255D01*
X720787Y1583943D01*
X719927D01*
G03X719199Y1584166I-729J-1079D01*
G03X718580Y1584009I1J-1302D01*
G01X718535Y1583984D01*
X717482D01*
G03X717178Y1583949I-4J-1301D01*
G01X717155Y1583943D01*
X715952D01*
X715612Y1584283D01*
Y1584560D01*
X716344Y1585292D01*
X717475D01*
G03X718480Y1584906I1005J1115D01*
G01X719200D01*
G03X720492Y1585643I0J1501D01*
G01X720922D01*
X721172Y1585893D01*
Y1592283D01*
X721312Y1592423D01*
X725120D01*
Y1589346D01*
G03X725063Y1588950I1345J-396D01*
G37*
G36*
G01X714282Y1629816D02*
G03I-491J0D01*
G37*
G36*
G01X743560Y39832D02*
G03I-720J0D01*
G37*
G36*
G01X737510D02*
G03I-720J0D01*
G37*
G36*
G01X732050Y60712D02*
G03I-720J0D01*
G37*
G36*
G01X729920Y588952D02*
G03I-720J0D01*
G37*
G36*
G01X739926Y608020D02*
G03I-720J0D01*
G37*
G36*
G01Y603064D02*
G03I-720J0D01*
G37*
G36*
G01X1369231Y1467093D02*
X1359287Y1457149D01*
Y1398215D01*
X1359140Y1398068D01*
X1319020D01*
G02X1318835Y1398208I6J200D01*
G03X1298642Y1413007I-20193J-6377D01*
G03X1290761Y1411485I2J-21176D01*
G02X1290686Y1411471I-74J186D01*
G01X1219891D01*
X1217630Y1413732D01*
Y1447785D01*
X1212099Y1453316D01*
X1211957Y1453375D01*
X1201588Y1463744D01*
Y1476834D01*
X1195002Y1483420D01*
X1145160D01*
X1142740Y1481000D01*
Y1478860D01*
X1142900Y1478700D01*
Y1459600D01*
X1141700Y1458400D01*
X786220D01*
X729340Y1515280D01*
Y1562610D01*
X732020Y1565290D01*
Y1570800D01*
X730630Y1572190D01*
Y1575070D01*
X729710Y1575990D01*
Y1577400D01*
X729770Y1577460D01*
X743440D01*
X743900Y1577920D01*
Y1581510D01*
X743930Y1581540D01*
X745740D01*
X746280Y1581000D01*
Y1579010D01*
X748580Y1576710D01*
X757010D01*
X765200Y1568520D01*
X774300D01*
X779750Y1573970D01*
Y1576720D01*
X780520Y1577490D01*
X795470D01*
X796130Y1578150D01*
Y1581100D01*
X796140Y1581110D01*
X798070D01*
X798500Y1580680D01*
Y1576820D01*
X804600Y1570720D01*
X816140D01*
X822900Y1577480D01*
X837650D01*
X838130Y1577960D01*
Y1581100D01*
X838150Y1581120D01*
X839930D01*
X840430Y1580620D01*
Y1576570D01*
X846700Y1570300D01*
X858110D01*
X864570Y1576760D01*
Y1577310D01*
X864730Y1577470D01*
X879900D01*
X880120Y1577690D01*
Y1581080D01*
X880160Y1581120D01*
X882040D01*
X882460Y1580700D01*
Y1576870D01*
X888320Y1571010D01*
X900550D01*
X907020Y1577480D01*
X921580D01*
X922120Y1578020D01*
Y1581080D01*
X922150Y1581110D01*
X924010D01*
X924470Y1580650D01*
Y1578860D01*
X926905Y1576425D01*
X940385D01*
X941250Y1575560D01*
Y1562080D01*
X942730Y1560600D01*
X957750D01*
X958100Y1560250D01*
Y1549520D01*
X958880Y1548740D01*
X967370D01*
X968120Y1549490D01*
Y1560310D01*
X968510Y1560700D01*
X981060D01*
X981400Y1560360D01*
Y1549430D01*
X982060Y1548770D01*
X990970D01*
X991510Y1549310D01*
Y1560240D01*
X991870Y1560600D01*
X1001234D01*
Y1560590D01*
X1004530D01*
X1004800Y1560320D01*
Y1549300D01*
X1005360Y1548740D01*
X1014310D01*
X1015100Y1549530D01*
Y1560290D01*
X1015410Y1560600D01*
X1027830D01*
X1028200Y1560230D01*
Y1549430D01*
X1029150Y1548480D01*
X1037160D01*
X1038300Y1549620D01*
Y1559990D01*
X1038910Y1560600D01*
X1051160D01*
X1051600Y1560160D01*
Y1549160D01*
X1052540Y1548220D01*
X1060360D01*
X1061570Y1549430D01*
Y1560250D01*
X1061920Y1560600D01*
X1074430D01*
X1074800Y1560230D01*
Y1549340D01*
X1075960Y1548180D01*
X1083880D01*
X1084890Y1549190D01*
Y1560080D01*
X1085410Y1560600D01*
X1089698D01*
Y1560590D01*
X1089708Y1560600D01*
X1094698D01*
Y1560550D01*
X1097670D01*
X1098200Y1560020D01*
Y1519050D01*
X1104025Y1513225D01*
X1628800D01*
X1644087Y1497938D01*
Y1456842D01*
X1643390Y1456145D01*
X1528057D01*
X1517168Y1467034D01*
G03X1517026Y1467093I-142J-141D01*
G01X1369231D01*
G37*
G36*
G01X817460Y1718640D02*
X900700D01*
X907010Y1712330D01*
X907011Y1702710D01*
X907130Y1702591D01*
Y1666600D01*
X907135Y1666595D01*
Y1663777D01*
X914842Y1656070D01*
X914850D01*
X915427Y1655493D01*
X915566Y1655354D01*
X921048D01*
X922265D01*
X922981Y1656070D01*
X925552D01*
X1064370D01*
X1084840Y1635600D01*
X1101560D01*
X1103140Y1634020D01*
Y1607480D01*
X1102240Y1606580D01*
X1095437D01*
Y1615196D01*
X1095236Y1615397D01*
Y1616774D01*
G03X1094736Y1617274I-500J0D01*
G01X1093136D01*
G03X1092636Y1616774I0J-500D01*
G01Y1615397D01*
X1092435Y1615196D01*
Y1606580D01*
X1059900D01*
Y1607558D01*
G03X1059899Y1607575I-501J-21D01*
G01Y1607680D01*
X1059882Y1607697D01*
X1059867Y1607737D01*
G03X1059576Y1608027I-469J-179D01*
G01X1059536Y1608043D01*
X1059020Y1608559D01*
X1057776D01*
X1057260Y1608043D01*
X1057220Y1608027D01*
G03X1056930Y1607737I179J-469D01*
G01X1056915Y1607698D01*
X1056897Y1607680D01*
Y1607575D01*
G03X1056896Y1607558I500J-38D01*
G01Y1606580D01*
X1028300D01*
Y1607558D01*
G03X1028299Y1607580I-502J-12D01*
G01Y1607680D01*
X1028283Y1607696D01*
X1028267Y1607736D01*
Y1607737D01*
G03X1027976Y1608027I-469J-179D01*
G01X1027936Y1608043D01*
X1027420Y1608559D01*
X1026176D01*
X1025660Y1608043D01*
X1025620Y1608027D01*
G03X1025314Y1607688I179J-469D01*
G01X1025310Y1607675D01*
X1025297Y1607643D01*
Y1607580D01*
G03X1025296Y1607558I501J-34D01*
G01Y1606580D01*
X996700D01*
Y1607559D01*
G03X996699Y1607585I-502J-6D01*
G01Y1607680D01*
X996683Y1607696D01*
X996667Y1607736D01*
G03X996376Y1608027I-469J-178D01*
G01X996336Y1608043D01*
X995820Y1608559D01*
X994576D01*
X994060Y1608043D01*
X994020Y1608027D01*
G03X993730Y1607737I179J-469D01*
G01X993714Y1607697D01*
X993697Y1607680D01*
Y1607585D01*
G03X993696Y1607559I501J-32D01*
G01Y1606580D01*
X965088D01*
Y1607542D01*
G03X965087Y1607574I-502J0D01*
G01Y1607664D01*
X965068Y1607683D01*
G03X964727Y1608024I-482J-141D01*
G01X964208Y1608543D01*
X962964D01*
X962445Y1608024D01*
G03X962099Y1607662I141J-482D01*
G01X962085Y1607627D01*
Y1607574D01*
G03X962084Y1607542I501J-32D01*
G01Y1606580D01*
X943180D01*
X935490Y1598890D01*
X926730D01*
X920790Y1592950D01*
Y1578870D01*
X920730Y1578810D01*
X907390D01*
X907330Y1578870D01*
Y1592932D01*
X906522Y1593740D01*
Y1604418D01*
X897900Y1613040D01*
X888092D01*
X879522Y1604470D01*
Y1593670D01*
X878810Y1592958D01*
Y1578920D01*
X878710Y1578820D01*
X865410D01*
X865340Y1578890D01*
Y1593002D01*
X864622Y1593720D01*
Y1603900D01*
X855922Y1612600D01*
X845130D01*
X837480Y1604950D01*
Y1593680D01*
X836780Y1592980D01*
Y1578840D01*
X836760Y1578820D01*
X823390D01*
X823370Y1578840D01*
Y1592852D01*
X822622Y1593600D01*
Y1604078D01*
X813690Y1613010D01*
X803262D01*
X795522Y1605270D01*
Y1593622D01*
X794790Y1592890D01*
Y1578870D01*
X794740Y1578820D01*
X781390D01*
X781370Y1578840D01*
Y1592990D01*
X775990Y1598370D01*
X750940D01*
X745522Y1592951D01*
Y1591843D01*
X744930Y1591251D01*
X744152D01*
X744052Y1591151D01*
X744022D01*
X743723Y1590852D01*
G03X743489Y1590618I218J-452D01*
G01X742590Y1589719D01*
Y1578820D01*
X742522Y1578751D01*
X729122D01*
Y1593148D01*
X729188Y1593207D01*
G03X729313Y1593381I-336J373D01*
G01X729328Y1593416D01*
X729703Y1593791D01*
Y1600932D01*
X730422Y1601651D01*
Y1601857D01*
X730438Y1601935D01*
Y1601936D01*
X730439Y1601939D01*
X730446Y1601957D01*
G03X730505Y1602131I-1391J569D01*
G01X730613Y1602239D01*
Y1605213D01*
X730422Y1605404D01*
Y1607951D01*
X729622Y1608751D01*
Y1626201D01*
X759336Y1655914D01*
X777714D01*
X812960Y1691160D01*
Y1714140D01*
X817460Y1718640D01*
G37*
G36*
G01X1439442Y1738108D02*
G02X1439628Y1737984I1J-200D01*
G01X1439791Y1737584D01*
X1439766Y1737466D01*
X1439723Y1737423D01*
G03X1438522Y1736176I22078J-22466D01*
G02X1438374Y1736110I-149J134D01*
G01X1353614D01*
X1353583Y1736121D01*
G03X1352953Y1736222I-629J-1909D01*
G03X1352323Y1736121I-1J-2010D01*
G01X1352292Y1736110D01*
X1337866D01*
X1337835Y1736121D01*
G03X1337205Y1736222I-629J-1909D01*
G03X1336575Y1736121I-1J-2010D01*
G01X1336544Y1736110D01*
X1322118D01*
X1322087Y1736121D01*
G03X1321457Y1736222I-629J-1909D01*
G03X1320827Y1736121I-1J-2010D01*
G01X1320796Y1736110D01*
X1307567D01*
X1307514Y1736126D01*
X1307489Y1736142D01*
G03X1307218Y1736222I-272J-421D01*
G01X1304200D01*
G03X1303929Y1736142I1J-501D01*
G01X1303904Y1736126D01*
X1303851Y1736110D01*
X1286685D01*
X1286654Y1736121D01*
G03X1286024Y1736222I-629J-1909D01*
G03X1285394Y1736121I-1J-2010D01*
G01X1285363Y1736110D01*
X1270937D01*
X1270906Y1736121D01*
G03X1270276Y1736222I-629J-1909D01*
G03X1269646Y1736121I-1J-2010D01*
G01X1269615Y1736110D01*
X1255189D01*
X1255158Y1736121D01*
G03X1254528Y1736222I-629J-1909D01*
G03X1253898Y1736121I-1J-2010D01*
G01X1253867Y1736110D01*
X1240638D01*
X1240585Y1736126D01*
X1240560Y1736142D01*
G03X1240289Y1736222I-272J-421D01*
G01X1237271D01*
G03X1237000Y1736142I1J-501D01*
G01X1236975Y1736126D01*
X1236922Y1736110D01*
X1093780D01*
G02X1087854Y1730914I-5926J781D01*
G01X769705D01*
G02X763779Y1736110I0J5977D01*
G01X731108D01*
G02X730960Y1736176I1J200D01*
G03X729759Y1737423I-23279J-21219D01*
G01X729716Y1737466D01*
X729691Y1737584D01*
X729854Y1737984D01*
G02X730040Y1738108I185J-76D01*
G01X765526D01*
G02X765726Y1737908I0J-200D01*
G01Y1736890D01*
G03X769705Y1732911I3979J0D01*
G01X1087854D01*
G03X1091833Y1736890I0J3979D01*
G01Y1737908D01*
G02X1092033Y1738108I200J0D01*
G01X1133345D01*
X1133347D01*
X1439442D01*
G37*
G36*
G01X750480Y71312D02*
X760100D01*
X761690Y69722D01*
Y52262D01*
X758281Y48853D01*
X758186Y48862D01*
G03X757040Y48804I-383J-3783D01*
G01X757020Y48800D01*
X749960D01*
X749190Y49570D01*
Y53544D01*
G03X749127Y54000I-1702J-3D01*
G01X749120Y54026D01*
Y56072D01*
X749476Y56428D01*
X749553Y56432D01*
G03X750826Y57272I-76J1500D01*
G01X753810D01*
X754530Y57992D01*
Y59510D01*
X754252Y59788D01*
X754238Y59814D01*
G03X753532Y60520I-1518J-812D01*
G01X753506Y60534D01*
X752770Y61270D01*
X750242D01*
X749140Y62372D01*
Y69972D01*
X750480Y71312D01*
G37*
G36*
G01X753440Y59002D02*
G03I-720J0D01*
G37*
G36*
G01X751767Y132822D02*
X769940D01*
X771533Y131229D01*
Y73220D01*
X771329Y73016D01*
X754813D01*
X754433Y73396D01*
Y74313D01*
X754581Y74353D01*
G03Y77061I-361J1354D01*
G01X754433Y77101D01*
Y82088D01*
X757026Y84680D01*
X761519D01*
G03X762934Y85267I-1J2002D01*
G01X765701Y88034D01*
G03X766288Y89449I-1415J1416D01*
G01Y93942D01*
X766533Y94188D01*
Y102211D01*
X768445Y104124D01*
G03X769032Y105539I-1415J1416D01*
G01Y117362D01*
G03X768445Y118777I-2002J-1D01*
G01X767151Y120071D01*
G03X765787Y120657I-1416J-1415D01*
G01X765708Y120659D01*
X765201Y121165D01*
G03X763786Y121752I-1416J-1415D01*
G01X755288D01*
G03X754302Y121492I1J-2002D01*
G01X752280D01*
X750733Y123039D01*
Y131788D01*
X751767Y132822D01*
G37*
G36*
G01X753173Y101438D02*
X752673D01*
X752443Y101668D01*
Y104858D01*
Y108598D01*
X753410Y109565D01*
Y112382D01*
X753816Y112788D01*
X755133D01*
X755633Y112288D01*
Y108048D01*
Y103898D01*
X753173Y101438D01*
G37*
G36*
G01X766720Y274742D02*
Y281762D01*
X766120Y282362D01*
X763820D01*
X763120Y281662D01*
X760420D01*
X759820Y282262D01*
Y284962D01*
X759220Y285562D01*
X756120D01*
X755620Y285062D01*
Y279062D01*
X756420Y278262D01*
X761520D01*
X763420Y276362D01*
Y274322D01*
X763680Y274062D01*
X766040D01*
X766720Y274742D01*
G37*
G36*
G01X755920Y296062D02*
G03I-720J0D01*
G37*
G36*
G01X758243Y1390645D02*
G03I-464J0D01*
G37*
G36*
G01X758006Y1420684D02*
G03I-464J0D01*
G37*
G36*
G01X767781Y99959D02*
G03I-720J0D01*
G37*
G36*
G01X767765Y95960D02*
G03I-720J0D01*
G37*
G36*
G01X777450Y117479D02*
G03I-720J0D01*
G37*
G36*
G01X774663Y114633D02*
G03I-720J0D01*
G37*
G36*
G01X771851Y111788D02*
G03I-720J0D01*
G37*
G36*
G01X872869Y282330D02*
X873548D01*
X873717Y282161D01*
Y275037D01*
X874098Y274656D01*
X875964D01*
X876855Y275547D01*
Y280253D01*
X877109Y280507D01*
X877364D01*
X877752Y280120D01*
Y279312D01*
X877872Y279192D01*
Y262342D01*
X878879Y261335D01*
X893017D01*
X896615Y257737D01*
Y237183D01*
X890526Y231094D01*
X886239Y226808D01*
X867839D01*
X867239Y227408D01*
Y229708D01*
X865339Y231608D01*
X861339D01*
X859739Y233208D01*
Y244977D01*
X859726Y244990D01*
Y245121D01*
X858508Y246339D01*
Y246392D01*
X779860D01*
X768440Y257812D01*
Y265582D01*
X769420Y266562D01*
X772050D01*
X776600Y262012D01*
X869747D01*
X872087Y264352D01*
X872106D01*
X872615Y264861D01*
Y282076D01*
X872869Y282330D01*
G37*
G36*
G01X763720Y272562D02*
X766320D01*
X766620Y272262D01*
Y269362D01*
X769420Y266562D01*
Y263062D01*
Y258792D01*
X768440Y257812D01*
X762190D01*
X761320Y258682D01*
Y262162D01*
Y266062D01*
X763720Y268462D01*
Y272562D01*
G37*
G36*
G01X773940Y296262D02*
G03I-720J0D01*
G37*
G36*
G01X778320Y134862D02*
X778920Y135462D01*
X796520D01*
X799120Y132862D01*
Y121562D01*
X795820Y118262D01*
X780420D01*
X778320Y120362D01*
Y134862D01*
G37*
G36*
G01X777420Y149662D02*
X781420Y153662D01*
X798020D01*
X799420Y152262D01*
Y142162D01*
X798220Y140962D01*
X778320D01*
X777420Y141862D01*
Y149662D01*
G37*
G36*
G01X825375Y204724D02*
G02I-19685J0D01*
G37*
G36*
G01X779840Y306162D02*
G03I-720J0D01*
G37*
G36*
G01X788689Y1388683D02*
G03I-464J0D01*
G37*
G36*
G01X807020Y279662D02*
G03I-720J0D01*
G37*
G36*
G01X810420Y273562D02*
G03I-720J0D01*
G37*
G36*
G01X795910Y298572D02*
G03I-720J0D01*
G37*
G36*
G01X807308Y351097D02*
G03I-720J0D01*
G37*
G36*
G01X799935Y431217D02*
G03I-477J0D01*
G37*
G36*
G01X817140Y287062D02*
G03I-720J0D01*
G37*
G36*
G01X814575Y354008D02*
G03I-720J0D01*
G37*
G36*
G01X821656Y356956D02*
G03I-720J0D01*
G37*
G36*
G01X821884Y372312D02*
G03I-720J0D01*
G37*
G36*
G01X811501Y372615D02*
G03I-720J0D01*
G37*
G36*
G01X814698Y1340465D02*
G03I-464J0D01*
G37*
G36*
G01X857040Y1420330D02*
G02I-15800J0D01*
G37*
G36*
G01X843054Y6022D02*
G03I-557J0D01*
G37*
G36*
G01Y16022D02*
G03I-557J0D01*
G37*
G36*
G01Y20978D02*
G03I-557J0D01*
G37*
G36*
G01Y10978D02*
G03I-557J0D01*
G37*
G36*
G01X837035Y161553D02*
G03I-533J0D01*
G37*
G36*
G01X838508Y210064D02*
G03I-533J0D01*
G37*
G36*
G01X830440Y277562D02*
G03I-720J0D01*
G37*
G36*
G01X830520Y271562D02*
G03I-720J0D01*
G37*
G36*
G01X835120Y283862D02*
G03I-720J0D01*
G37*
G36*
G01X835620Y293462D02*
G03I-720J0D01*
G37*
G36*
G01X828942Y359960D02*
G03I-720J0D01*
G37*
G36*
G01X836191Y363003D02*
G03I-720J0D01*
G37*
G36*
G01X829263Y1336870D02*
G03I-464J0D01*
G37*
G36*
G01X829374Y1331756D02*
G03I-464J0D01*
G37*
G36*
G01Y1341725D02*
G03I-464J0D01*
G37*
G36*
G01X851000Y113852D02*
G03I-720J0D01*
G37*
G36*
G01X857309Y129268D02*
G03I-533J0D01*
G37*
G36*
G01X847379Y127064D02*
G03I-533J0D01*
G37*
G36*
G01X844470Y217542D02*
X849930D01*
X850650Y216822D01*
Y214322D01*
X851150Y213822D01*
X853940D01*
X854150Y213612D01*
Y213222D01*
X853790Y212862D01*
X851330D01*
X850720Y212252D01*
Y211502D01*
X850220Y211002D01*
X844940D01*
X844220Y211722D01*
Y217292D01*
X844470Y217542D01*
G37*
G36*
G01X851506Y242478D02*
X858106D01*
X858738Y241846D01*
Y232793D01*
X859006Y232525D01*
Y230378D01*
X857706Y229078D01*
X851506D01*
X850706Y229878D01*
Y241678D01*
X851506Y242478D01*
G37*
G36*
G01X852420Y294562D02*
X852520Y294662D01*
X864720D01*
X865443Y293939D01*
Y288247D01*
X865243Y288047D01*
X856043D01*
X855908Y287912D01*
X855856Y287898D01*
G03X854741Y286447I387J-1451D01*
G03X855727Y285036I1503J0D01*
G01X855769Y285021D01*
X855843Y284947D01*
X856170D01*
G03X856243Y284945I78J1500D01*
G03X856316Y284947I-5J1502D01*
G01X857803D01*
X858233Y284517D01*
Y279017D01*
X858304Y278946D01*
Y278778D01*
X858472D01*
X858743Y278507D01*
X868483D01*
X868913Y278937D01*
Y280197D01*
X869203Y280487D01*
X869533D01*
X869833Y280187D01*
Y277747D01*
X869673Y277587D01*
X866833D01*
X864232Y274986D01*
X862688D01*
G03X861865Y275232I-824J-1256D01*
G03X861042Y274986I1J-1502D01*
G01X859921D01*
G03X859537Y274927I-3J-1257D01*
G01X859508Y274917D01*
X858075D01*
X857533Y274375D01*
Y271917D01*
X857333Y271717D01*
X851773D01*
X851443Y272047D01*
Y285501D01*
G03X851850Y286625I-1350J1124D01*
G01Y293908D01*
X852420Y294478D01*
Y294562D01*
G37*
G36*
G01X853920Y297462D02*
G03I-720J0D01*
G37*
G36*
G01X857420Y304862D02*
G03I-720J0D01*
G37*
G36*
G01X843853Y366158D02*
G03I-720J0D01*
G37*
G36*
G01X852116Y369614D02*
G03I-720J0D01*
G37*
G36*
G01X853815Y751062D02*
G03I-615J0D01*
G37*
G36*
G01X862070Y61672D02*
G03I-720J0D01*
G37*
G36*
G01X868907Y72006D02*
G03I-720J0D01*
G37*
G36*
G01X861657Y71877D02*
G03I-720J0D01*
G37*
G36*
G01X867539Y207008D02*
Y224608D01*
X867739Y224808D01*
X888939D01*
X888998Y224750D01*
X897022D01*
X899460Y222312D01*
Y207432D01*
X897736Y205708D01*
X868839D01*
X867539Y207008D01*
G37*
G36*
G01X864608Y307279D02*
X874341D01*
X875803Y305817D01*
Y275911D01*
X875549Y275658D01*
X875022D01*
X874863Y275817D01*
Y282327D01*
X874718Y282472D01*
Y282576D01*
X873963Y283332D01*
X873858D01*
X873803Y283387D01*
X872563D01*
X872508Y283332D01*
X872454D01*
X871614Y282491D01*
Y277587D01*
X871003D01*
X870873Y277717D01*
Y287057D01*
X869020Y288910D01*
Y289900D01*
G03X869018Y289953I-890J-7D01*
G01Y293038D01*
X869025Y293064D01*
G03X869056Y293298I-859J233D01*
G01Y294352D01*
X869018D01*
Y295164D01*
X868820Y295362D01*
Y295394D01*
X868788D01*
X868720Y295462D01*
X865336D01*
X865135Y295664D01*
X861718D01*
X861320Y296062D01*
Y298962D01*
X861651Y299293D01*
Y304322D01*
X864608Y307279D01*
G37*
G36*
G01X860454Y373032D02*
G03I-720J0D01*
G37*
G36*
G01X868642Y376450D02*
G03I-720J0D01*
G37*
G36*
G01X886813Y174085D02*
G03I-533J0D01*
G37*
G36*
G01X879483Y279497D02*
X878983D01*
X878753Y279727D01*
Y282917D01*
Y286657D01*
X879443Y287347D01*
Y290347D01*
X879943Y290847D01*
X881443D01*
X881943Y290347D01*
Y286107D01*
Y281957D01*
X879483Y279497D01*
G37*
G36*
G01X881193Y329370D02*
G03I-720J0D01*
G37*
G36*
G01X876642Y379793D02*
G03I-720J0D01*
G37*
G36*
G01X888589Y386618D02*
G03I-720J0D01*
G37*
G36*
G01X884192Y382910D02*
G03I-720J0D01*
G37*
G36*
G01X888391Y487831D02*
G03I-720J0D01*
G37*
G36*
G01Y494767D02*
G03I-720J0D01*
G37*
G36*
G01X879438Y509051D02*
G03I-507J0D01*
G37*
G36*
G01Y503833D02*
G03I-507J0D01*
G37*
G36*
G01X887082Y534380D02*
G03I-720J0D01*
G37*
G36*
G01X887115Y739162D02*
G03I-615J0D01*
G37*
G36*
G01X889903Y1437938D02*
G03I-464J0D01*
G37*
G36*
G01X904586Y202885D02*
G03I-656J0D01*
G37*
G36*
G01X904636Y210355D02*
G03I-656J0D01*
G37*
G36*
G01X904586Y217059D02*
G03I-656J0D01*
G37*
G36*
G01X904636Y224529D02*
G03I-656J0D01*
G37*
G36*
G01X906657Y259849D02*
X920310D01*
X920995Y259164D01*
Y250099D01*
X920402Y249506D01*
X917263D01*
X915143Y247386D01*
Y241705D01*
X916627Y240221D01*
Y234751D01*
X915694Y233818D01*
X903398D01*
X900388Y236828D01*
Y259197D01*
X901040Y259849D01*
X905583D01*
X905615Y259837D01*
G03X906120Y259750I504J1415D01*
G03X906625Y259837I1J1502D01*
G01X906657Y259849D01*
G37*
G36*
G01X894220Y339062D02*
G03I-720J0D01*
G37*
G36*
G01X900345Y473856D02*
G03I-720J0D01*
G37*
G36*
G01X893818Y480313D02*
G03I-507J0D01*
G37*
G36*
G01Y485531D02*
G03I-507J0D01*
G37*
G36*
G01X894292Y503050D02*
G03I-720J0D01*
G37*
G36*
G01Y496114D02*
G03I-720J0D01*
G37*
G36*
G01X900781Y510962D02*
G03I-720J0D01*
G37*
G36*
G01Y517898D02*
G03I-720J0D01*
G37*
G36*
G01X894018Y534380D02*
G03I-720J0D01*
G37*
G36*
G01X900182Y533380D02*
G03I-720J0D01*
G37*
G36*
G01X907118D02*
G03I-720J0D01*
G37*
G36*
G01X895082Y913692D02*
G03I-707J0D01*
G37*
G36*
G01X898782Y976652D02*
G03I-720J0D01*
G37*
G36*
G01Y969716D02*
G03I-720J0D01*
G37*
G36*
G01X918380Y165289D02*
X910240D01*
X909620Y165909D01*
Y180059D01*
X909860Y180299D01*
X918370D01*
X918940Y179729D01*
Y165849D01*
X918380Y165289D01*
G37*
G36*
G01X920779Y184138D02*
G03I-533J0D01*
G37*
G36*
G01X948424Y321653D02*
G02I-19685J0D01*
G37*
G36*
G01X909182Y455386D02*
G03I-507J0D01*
G37*
G36*
G01X914400D02*
G03I-507J0D01*
G37*
G36*
G01X919999Y461244D02*
G03I-720J0D01*
G37*
G36*
G01X912346Y523430D02*
G03I-720J0D01*
G37*
G36*
G01X919282D02*
G03I-720J0D01*
G37*
G36*
G01X922230Y991522D02*
X924960D01*
X925390Y991952D01*
Y994992D01*
X925550Y995152D01*
X926030D01*
X926280Y994902D01*
Y992042D01*
X926740Y991582D01*
X931940D01*
X932490Y992132D01*
X935100D01*
X935260Y991972D01*
Y991342D01*
X935070Y991152D01*
X933120D01*
X932900Y990932D01*
Y990402D01*
X933080Y990222D01*
X934960D01*
X935210Y989972D01*
Y989352D01*
X935060Y989202D01*
X932030D01*
X931460Y988632D01*
Y982152D01*
X932220Y981392D01*
Y978532D01*
X932060Y978372D01*
X931460D01*
X931150Y978682D01*
Y980592D01*
X930760Y980982D01*
X926710D01*
X926300Y980572D01*
Y978442D01*
X926140Y978282D01*
X925600D01*
X925280Y978602D01*
Y980822D01*
X924210Y981892D01*
X922300D01*
X922000Y982192D01*
Y986652D01*
X921410Y987242D01*
X918610D01*
X918340Y987512D01*
Y988092D01*
X918480Y988232D01*
X921220D01*
X922000Y989012D01*
Y991292D01*
X922230Y991522D01*
G37*
G36*
G01X966409Y207834D02*
X974938D01*
X975668Y207104D01*
Y205109D01*
X991620D01*
X992040Y204689D01*
X995230D01*
X995470Y204449D01*
Y190199D01*
X995160Y189889D01*
X986580D01*
X983288Y186596D01*
X983114D01*
Y186424D01*
X978900Y182209D01*
Y174793D01*
X978268D01*
X975475Y172000D01*
Y169809D01*
X977043Y168241D01*
X981070D01*
X987022Y162289D01*
X987931D01*
X987939Y162288D01*
G03X988038Y162284I100J1253D01*
G01X992452D01*
G03X992551Y162288I-1J1257D01*
G01X992559Y162289D01*
X993714D01*
X993905Y162098D01*
X998682D01*
X998910Y161869D01*
Y161389D01*
X998580Y161059D01*
X991560D01*
X991000Y160499D01*
Y159029D01*
X991018Y159010D01*
Y158984D01*
X991905Y158098D01*
X996822D01*
X996890Y158029D01*
Y157199D01*
X996826Y157134D01*
X995700D01*
X995535Y156969D01*
X991663D01*
X991618Y156924D01*
X991036D01*
G03X990211Y156614I1J-1256D01*
G01X987192D01*
G03X986369Y156860I-824J-1256D01*
G03X984911Y155717I0J-1501D01*
G01X984897Y155663D01*
X984612Y155377D01*
G03X984514Y155268I884J-893D01*
G01X984507Y155259D01*
X984062Y154814D01*
X976378D01*
X973628Y157564D01*
X966044D01*
X962689Y160919D01*
X957410D01*
X955210Y163119D01*
Y165679D01*
X953890Y166999D01*
X935300D01*
X933960Y165659D01*
X928300D01*
X927830Y166129D01*
Y179629D01*
X928530Y180329D01*
X938720D01*
X938740Y180309D01*
X948630D01*
X951320Y182999D01*
Y196109D01*
X951900Y196689D01*
X962880D01*
X965340Y199149D01*
Y206765D01*
X966409Y207834D01*
G37*
G36*
G01X928840Y191739D02*
X929070Y191969D01*
X935020D01*
X936500Y193449D01*
X939250D01*
X939830Y192869D01*
Y190819D01*
X939460Y190449D01*
X929020D01*
X928840Y190629D01*
Y191739D01*
G37*
G36*
G01X939157Y455454D02*
G03I-720J0D01*
G37*
G36*
G01X933444Y455538D02*
G03I-720J0D01*
G37*
G36*
G01X926935Y461244D02*
G03I-720J0D01*
G37*
G36*
G01X925367Y526808D02*
G03I-720J0D01*
G37*
G36*
G01X939817Y527257D02*
G03I-720J0D01*
G37*
G36*
G01X925367Y533744D02*
G03I-720J0D01*
G37*
G36*
G01X929118Y530479D02*
G03I-887J0D01*
G37*
G36*
G01X937130Y530478D02*
G03I-857J0D01*
G37*
G36*
G01X940002Y534020D02*
G03I-720J0D01*
G37*
G36*
G01X927815Y811462D02*
G03I-615J0D01*
G37*
G36*
G01X925215Y824262D02*
G03I-615J0D01*
G37*
G36*
G01X929836Y1014664D02*
G03I-615J0D01*
G37*
G36*
G01X955820Y159799D02*
X962020D01*
X965320Y156499D01*
X973230D01*
X975688Y154041D01*
X975735D01*
X975963Y153812D01*
X982384D01*
X982468Y153729D01*
Y146933D01*
X981069Y145534D01*
X975585D01*
X975520Y145599D01*
X956320D01*
X955220Y146699D01*
Y159199D01*
X955820Y159799D01*
G37*
G36*
G01X942290Y199051D02*
G03I-656J0D01*
G37*
G36*
G01Y193451D02*
G03I-656J0D01*
G37*
G36*
G01X962620Y217299D02*
X971920D01*
X972454Y216766D01*
Y209688D01*
X971824Y209058D01*
X964979D01*
X962640Y206719D01*
Y198809D01*
X961600Y197769D01*
X949190D01*
X949100Y197679D01*
X948300Y198479D01*
Y200609D01*
X948780Y201089D01*
X955320D01*
X957620Y203389D01*
Y212299D01*
X962620Y217299D01*
G37*
G36*
G01X952010Y203837D02*
G03I-656J0D01*
G37*
G36*
G01Y209437D02*
G03I-656J0D01*
G37*
G36*
G01X945536Y210959D02*
G03I-656J0D01*
G37*
G36*
G01Y216559D02*
G03I-656J0D01*
G37*
G36*
G01Y230697D02*
G03I-656J0D01*
G37*
G36*
G01Y225097D02*
G03I-656J0D01*
G37*
G36*
G01X955530Y232071D02*
G03I-656J0D01*
G37*
G36*
G01X955560Y225741D02*
G03I-656J0D01*
G37*
G36*
G01X943366Y400793D02*
G03I-720J0D01*
G37*
G36*
G01X943547Y422743D02*
G03I-720J0D01*
G37*
G36*
G01Y429679D02*
G03I-720J0D01*
G37*
G36*
G01X946520Y432463D02*
G03I-720J0D01*
G37*
G36*
G01Y439399D02*
G03I-720J0D01*
G37*
G36*
G01X941429Y460438D02*
G03I-720J0D01*
G37*
G36*
G01X947212Y460410D02*
G03I-720J0D01*
G37*
G36*
G01X956908Y495384D02*
G03I-720J0D01*
G37*
G36*
G01Y502320D02*
G03I-720J0D01*
G37*
G36*
G01X949215Y502784D02*
G03I-720J0D01*
G37*
G36*
G01X949413Y509497D02*
G03I-720J0D01*
G37*
G36*
G01X956908Y509484D02*
G03I-720J0D01*
G37*
G36*
G01Y516420D02*
G03I-720J0D01*
G37*
G36*
G01X953342Y529364D02*
G03I-720J0D01*
G37*
G36*
G01X947910Y527330D02*
G03I-720J0D01*
G37*
G36*
G01X942015Y810062D02*
G03I-615J0D01*
G37*
G36*
G01X1059899Y1601500D02*
X1078000D01*
X1080000Y1599500D01*
Y1565500D01*
X1079000Y1564500D01*
X945500D01*
X943500Y1566500D01*
Y1600500D01*
X944500Y1601500D01*
X962084D01*
Y1600426D01*
G03X962085Y1600409I501J21D01*
G01Y1600404D01*
Y1600304D01*
X962102Y1600287D01*
X962117Y1600247D01*
G03X962408Y1599957I469J179D01*
G01X962448Y1599941D01*
X962964Y1599425D01*
X964208D01*
X964724Y1599941D01*
X964764Y1599957D01*
G03X965069Y1600293I-179J469D01*
G01X965070Y1600296D01*
X965074Y1600309D01*
X965087Y1600341D01*
Y1600404D01*
Y1600409D01*
G03X965088Y1600426I-500J38D01*
G01Y1601500D01*
X993696D01*
Y1600442D01*
G03X993697Y1600420I502J12D01*
G01Y1600415D01*
Y1600320D01*
X993713Y1600304D01*
X993729Y1600264D01*
Y1600263D01*
G03X994020Y1599973I469J179D01*
G01X994060Y1599957D01*
X994576Y1599441D01*
X995820D01*
X996336Y1599957D01*
X996376Y1599973D01*
G03X996682Y1600312I-179J469D01*
G01X996686Y1600325D01*
X996699Y1600357D01*
Y1600415D01*
Y1600420D01*
G03X996700Y1600442I-501J34D01*
G01Y1601500D01*
X1025296D01*
Y1600441D01*
G03X1025297Y1600415I502J6D01*
G01Y1600410D01*
Y1600320D01*
X1025313Y1600304D01*
X1025329Y1600264D01*
G03X1025620Y1599973I469J178D01*
G01X1025660Y1599957D01*
X1026176Y1599441D01*
X1027420D01*
X1027936Y1599957D01*
X1027976Y1599973D01*
G03X1028282Y1600311I-178J469D01*
G01X1028285Y1600323D01*
X1028299Y1600357D01*
Y1600410D01*
Y1600415D01*
G03X1028300Y1600441I-501J32D01*
G01Y1601500D01*
X1056897D01*
Y1601474D01*
G03X1056896Y1601442I501J-32D01*
G01Y1600442D01*
G03X1056897Y1600410I502J0D01*
G01Y1600320D01*
X1056916Y1600301D01*
G03X1057257Y1599960I482J141D01*
G01X1057776Y1599441D01*
X1059020D01*
X1059539Y1599960D01*
G03X1059885Y1600322I-141J482D01*
G01X1059899Y1600357D01*
Y1600410D01*
G03X1059900Y1600442I-501J32D01*
G01Y1601442D01*
G03X1059899Y1601474I-502J0D01*
G01Y1601500D01*
G37*
G36*
G01X1099290Y1737610D02*
X1186050D01*
X1188370Y1735290D01*
Y1689680D01*
X1184270Y1685580D01*
X1159670D01*
X1154970Y1680880D01*
Y1644370D01*
X1152800Y1642200D01*
X1142680D01*
X1139410Y1638930D01*
X1122990D01*
X1115540Y1646380D01*
Y1677090D01*
X1106790Y1685840D01*
X1090200D01*
X1066190Y1661830D01*
X968960D01*
X949190Y1681600D01*
Y1721800D01*
X956080Y1728690D01*
X1090370D01*
X1099290Y1737610D01*
G37*
G36*
G01X972127Y242358D02*
G03I-656J0D01*
G37*
G36*
G01X967769Y280100D02*
Y297018D01*
X969469Y298718D01*
X981904D01*
X982371Y298251D01*
Y281353D01*
Y276206D01*
Y274236D01*
X982229Y274094D01*
X968289D01*
X967769Y274614D01*
Y276074D01*
Y280100D01*
G37*
G36*
G01X984380Y381852D02*
X985807D01*
X985845Y381836D01*
G03X985905Y381811I569J1281D01*
G02X986046Y381154I-141J-374D01*
G01X983156Y378264D01*
X981064D01*
G03X979766Y379009I-1298J-758D01*
G03X978264Y377507I0J-1502D01*
G03X978291Y377225I1502J2D01*
G01X978310Y377121D01*
X974353Y373164D01*
G03X974189Y372919I535J-535D01*
G01X972469Y368767D01*
G03X972412Y368477I699J-288D01*
G01Y358146D01*
X971584D01*
Y355646D01*
X972443D01*
X972499Y355540D01*
G03X972633Y355359I668J355D01*
G01X974144Y353849D01*
Y348376D01*
X973328Y347560D01*
X967788D01*
G03X967286Y347059I0J-502D01*
G01Y342259D01*
G03X967788Y341758I501J0D01*
G01X973688D01*
G03X974190Y342259I0J502D01*
G01Y346283D01*
X975435Y347528D01*
G03X975611Y347806I-536J534D01*
G02X976052Y348064I376J-137D01*
G03X976134Y348058I77J495D01*
G01X982034D01*
G03X982536Y348559I0J502D01*
G01Y353359D01*
G03X982050Y353860I-501J0D01*
G02X981856Y354056I6J200D01*
G03X981488Y354917I-1256J-28D01*
G01X979304Y357102D01*
Y358160D01*
X978260D01*
Y358396D01*
X977856D01*
Y360761D01*
G02X978050Y360961I200J0D01*
G03X979048Y361386I-50J1501D01*
G02X979610Y361382I279J-287D01*
G01X980304Y360689D01*
Y360373D01*
G03X981200Y359483I890J0D01*
G01Y359484D01*
X982378D01*
Y359483D01*
G03X983274Y360373I6J890D01*
G01Y361426D01*
X983038D01*
Y363261D01*
X983204Y363290D01*
G03X983608Y363500I-131J745D01*
G01X984305Y364197D01*
G03X984526Y364732I-535J534D01*
G01Y366363D01*
G03X984305Y366898I-756J1D01*
G01X983795Y367408D01*
G03X983260Y367630I-535J-534D01*
G01X979323D01*
X979256Y367696D01*
Y369460D01*
X979323Y369526D01*
X983260D01*
G03X983795Y369748I0J756D01*
G01X984305Y370258D01*
G03X984526Y370793I-535J534D01*
G01Y372664D01*
G03X985272Y373962I-756J1298D01*
G03X985161Y374528I-1502J-1D01*
G01X985111Y374651D01*
X990857Y380398D01*
X991369D01*
G03X991446Y380401I9J756D01*
G01X991456Y380402D01*
X992029D01*
X993010Y379422D01*
X991240Y377652D01*
Y375852D01*
X990360Y374972D01*
X988720D01*
X988614Y374866D01*
X988559Y374853D01*
G03X987447Y373741I349J-1461D01*
G01X987434Y373686D01*
X987200Y373452D01*
Y359042D01*
X986040Y357882D01*
Y343502D01*
X981680Y339142D01*
X967300D01*
X965220Y341222D01*
Y365802D01*
X980554Y381136D01*
X982116D01*
G03X982927Y381432I1J1256D01*
G01X983960D01*
X984380Y381852D01*
G37*
G36*
G01X973706Y393171D02*
G03I-720J0D01*
G37*
G36*
G01X970774Y478773D02*
G03I-720J0D01*
G37*
G36*
G01Y485709D02*
G03I-720J0D01*
G37*
G36*
G01X960278Y529364D02*
G03I-720J0D01*
G37*
G36*
G01X962882Y535130D02*
G03I-720J0D01*
G37*
G36*
G01X969818D02*
G03I-720J0D01*
G37*
G36*
G01X959464Y657078D02*
G03I-709J0D01*
G37*
G36*
G01X964229Y665062D02*
G03I-709J0D01*
G37*
G36*
G01X959575Y662378D02*
G03I-709J0D01*
G37*
G36*
G01X957315Y786862D02*
G03I-615J0D01*
G37*
G36*
G01X959715Y789862D02*
G03I-615J0D01*
G37*
G36*
G01X963482Y1552700D02*
Y1551040D01*
X963722Y1550800D01*
X965972D01*
X967042Y1551870D01*
Y1555170D01*
X966772Y1555440D01*
X965122D01*
X964752Y1555070D01*
Y1553690D01*
Y1553220D01*
X964432Y1552900D01*
X963682D01*
X963482Y1552700D01*
G37*
G36*
G01X959902Y1560400D02*
Y1551480D01*
X960542Y1550840D01*
X962362D01*
X962482Y1550960D01*
Y1553190D01*
X962802Y1553510D01*
Y1560490D01*
X962772Y1560520D01*
X960022D01*
X959902Y1560400D01*
G37*
G36*
G01X978960Y-13978D02*
G03I-557J0D01*
G37*
G36*
G01Y-19022D02*
G03I-557J0D01*
G37*
G36*
G01Y-23978D02*
G03I-557J0D01*
G37*
G36*
G01Y6022D02*
G03I-557J0D01*
G37*
G36*
G01Y-9022D02*
G03I-557J0D01*
G37*
G36*
G01Y10978D02*
G03I-557J0D01*
G37*
G36*
G01Y20978D02*
G03I-557J0D01*
G37*
G36*
G01Y16022D02*
G03I-557J0D01*
G37*
G36*
G01X989720Y182299D02*
X997304D01*
X997305Y182298D01*
X1002922D01*
X1010768Y174450D01*
Y169675D01*
X1010536Y169443D01*
X1004635D01*
X1004435Y169643D01*
Y176084D01*
X1003320Y177199D01*
X1001451D01*
X1000905Y176653D01*
X995405D01*
X995334Y176582D01*
X995166D01*
Y176414D01*
X994895Y176143D01*
Y166403D01*
X995325Y165973D01*
X996585D01*
X996875Y165683D01*
Y165353D01*
X996575Y165053D01*
X994135D01*
X993975Y165213D01*
Y168053D01*
X991372Y170656D01*
Y172216D01*
G03X991617Y173039I-1257J822D01*
G03X991372Y173862I-1502J1D01*
G01Y174968D01*
G03X991314Y175343I-1257J-2D01*
G01X991305Y175373D01*
Y176811D01*
X990763Y177353D01*
X988305D01*
X988105Y177553D01*
Y180684D01*
X989720Y182299D01*
G37*
G36*
G01X994695Y211223D02*
X985995D01*
X985495Y211723D01*
Y214623D01*
X985795Y214923D01*
X994695D01*
X995295Y214323D01*
Y211823D01*
X994695Y211223D01*
G37*
G36*
G01X981895Y218623D02*
X995095D01*
X995295Y218423D01*
Y215924D01*
X985380D01*
X985279Y215823D01*
X984595D01*
X983795Y215023D01*
Y211623D01*
X983495Y211323D01*
X980495D01*
X979995Y211823D01*
Y216723D01*
X981895Y218623D01*
G37*
G36*
G01X976645Y209163D02*
X989212D01*
X991012Y207363D01*
X995245D01*
X995545Y207063D01*
Y205690D01*
X992455D01*
X992035Y206110D01*
X976670D01*
Y207519D01*
X976045Y208143D01*
Y208563D01*
X976645Y209163D01*
G37*
G36*
G01X1065218Y294300D02*
X1071318D01*
X1071731Y293887D01*
Y239793D01*
X1070485Y238547D01*
X1024746D01*
X1024656Y238638D01*
X1018979D01*
X1016532Y241084D01*
G03X1015644Y241452I-888J-887D01*
G01X983359D01*
Y273808D01*
X983372Y273821D01*
Y277298D01*
X983429Y277354D01*
X992783D01*
X992791Y277346D01*
X1035394D01*
X1035433Y277307D01*
Y270668D01*
X1035431Y270667D01*
Y267415D01*
X1034311Y266295D01*
X1030413D01*
X1029518Y265400D01*
Y262600D01*
X1033618Y258500D01*
X1040018D01*
X1041018Y259500D01*
Y271200D01*
X1041818Y272000D01*
X1062318D01*
X1063518Y273200D01*
Y292600D01*
X1065218Y294300D01*
G37*
G36*
G01X1040354Y283564D02*
X1040787Y283997D01*
X1044107D01*
X1044259Y283845D01*
Y281845D01*
X1044178Y281764D01*
X1039278D01*
X1034233D01*
X1030905D01*
X1027707Y278566D01*
X989416D01*
X988459Y279523D01*
Y283238D01*
Y296141D01*
X990843Y298525D01*
X1006733D01*
X1009287D01*
X1010883Y296929D01*
Y294375D01*
Y291919D01*
X1011808Y290994D01*
X1015094Y287708D01*
X1016010Y286792D01*
X1018368Y284435D01*
X1019219Y283584D01*
X1019429Y283374D01*
X1040164D01*
X1040354Y283564D01*
G37*
G36*
G01X988380Y381462D02*
X988816D01*
G02X989099Y380779I0J-400D01*
G01X983786Y375466D01*
X983708Y375463D01*
G03X982268Y373962I62J-1501D01*
G03X983014Y372664I1502J0D01*
G01Y371106D01*
X982947Y371040D01*
X979010D01*
G03X978475Y370818I0J-756D01*
G01X977965Y370308D01*
G03X977744Y369773I535J-534D01*
G01Y367383D01*
G03X977965Y366848I756J-1D01*
G01X978475Y366338D01*
G03X979010Y366116I535J534D01*
G01X982947D01*
X983014Y366050D01*
Y365816D01*
G02X982542Y365422I-400J0D01*
G03X982378Y365437I-163J-875D01*
G01Y365436D01*
X981200D01*
Y365437D01*
G03X980304Y364547I-6J-890D01*
G01Y363494D01*
X980540D01*
Y363075D01*
G02X980198Y362934I-200J0D01*
G01X980135Y362997D01*
G03X979600Y363218I-534J-535D01*
G01X979298D01*
G03X978000Y363964I-1298J-756D01*
G03X976498Y362462I0J-1502D01*
G03X976548Y362079I1502J1D01*
G03X976344Y361562I553J-517D01*
G01Y357720D01*
X976339Y357699D01*
G03X976317Y357499I868J-197D01*
G01X976318D01*
Y356321D01*
X976317D01*
G03X977207Y355424I890J-7D01*
G01X977428D01*
X978309Y354543D01*
G02X978026Y353860I-283J-283D01*
G01X976134D01*
G03X975936Y353820I-2J-501D01*
G01X975898Y353803D01*
X975656D01*
Y354162D01*
G03X975435Y354697I-756J1D01*
G01X974389Y355743D01*
X974461Y355874D01*
G03X974570Y356307I-781J427D01*
G01Y357485D01*
G03X974043Y358304I-890J6D01*
G01X973924Y358357D01*
Y368327D01*
X975529Y372200D01*
X979380Y376051D01*
X979484Y376032D01*
G03X979766Y376005I284J1475D01*
G03X981064Y376750I0J1503D01*
G01X983469D01*
G03X984004Y376972I0J756D01*
G01X987534Y380502D01*
G03X987703Y380761I-536J534D01*
G01X987719Y380800D01*
X988380Y381462D01*
G37*
G36*
G01X995312Y392602D02*
Y391402D01*
X993390D01*
X992985Y391807D01*
X988183D01*
X987556Y391180D01*
X986568D01*
X986298Y391449D01*
Y392435D01*
X986537Y392674D01*
X987656D01*
X988173Y392157D01*
X992969D01*
X993414Y392602D01*
X995312D01*
G37*
G36*
G01X988879Y409068D02*
G03I-720J0D01*
G37*
G36*
G01X986392Y432961D02*
G03I-720J0D01*
G37*
G36*
G01X977003Y534226D02*
G03I-720J0D01*
G37*
G36*
G01X986848Y1552700D02*
Y1551040D01*
X987088Y1550800D01*
X989338D01*
X990408Y1551870D01*
Y1555170D01*
X990138Y1555440D01*
X988488D01*
X988118Y1555070D01*
Y1553690D01*
Y1553220D01*
X987798Y1552900D01*
X987048D01*
X986848Y1552700D01*
G37*
G36*
G01X983268Y1560400D02*
Y1551480D01*
X983908Y1550840D01*
X985728D01*
X985848Y1550960D01*
Y1553190D01*
X986168Y1553510D01*
Y1560490D01*
X986138Y1560520D01*
X983388D01*
X983268Y1560400D01*
G37*
G36*
G01X995885Y155403D02*
Y155903D01*
X996115Y156133D01*
X999305D01*
X1003045D01*
X1003999Y155179D01*
X1006999D01*
X1007235Y154943D01*
Y153443D01*
X1006735Y152943D01*
X1002495D01*
X998345D01*
X995885Y155403D01*
G37*
G36*
G01X996920Y205299D02*
X1001420D01*
X1002220Y204499D01*
Y189199D01*
X1004420Y186999D01*
X1018520D01*
X1020420Y185099D01*
Y183799D01*
X1021420Y182799D01*
X1025120D01*
X1025620Y182299D01*
Y156639D01*
Y155862D01*
X1025157Y155399D01*
X1024380D01*
X1017320D01*
X1016880Y155839D01*
Y158419D01*
X1016200Y159099D01*
X992320D01*
X992020Y159399D01*
Y159799D01*
X992220Y159999D01*
X999720D01*
X1000020Y160299D01*
Y162799D01*
X999720Y163099D01*
X994320D01*
X993920Y163499D01*
Y163799D01*
X994120Y163999D01*
X1007120D01*
X1008420Y165299D01*
X1011420D01*
X1011770Y165649D01*
Y174999D01*
X1003470Y183299D01*
X997720D01*
X996820Y184199D01*
Y204799D01*
X996720Y204899D01*
Y205099D01*
X996920Y205299D01*
G37*
G36*
G01X1000095Y216523D02*
X999995Y216623D01*
Y220623D01*
X1000695Y221323D01*
X1006095D01*
X1006795Y220623D01*
Y216923D01*
X1006395Y216523D01*
X1000095D01*
G37*
G36*
G01X1004620Y215299D02*
X1006420D01*
X1006920Y214799D01*
Y206489D01*
X1006140Y205709D01*
X1003410D01*
X1003320Y205799D01*
Y208399D01*
X1004220Y209299D01*
Y214899D01*
X1004620Y215299D01*
G37*
G36*
G01X1012805Y302415D02*
X999947D01*
X998785Y303577D01*
Y313687D01*
X1000238Y315140D01*
X1011642D01*
X1013313Y313469D01*
Y302923D01*
X1012805Y302415D01*
G37*
G36*
G01X995863Y383562D02*
X993413D01*
X993343Y383632D01*
Y384602D01*
X993403Y384662D01*
X995973D01*
X996293D01*
X996553Y384922D01*
Y401122D01*
X997463Y402032D01*
X1016503D01*
X1016663Y401872D01*
Y382212D01*
X1016403Y381952D01*
X997993D01*
X997373Y381332D01*
Y378882D01*
X997233Y378742D01*
X996303D01*
X996223Y378822D01*
Y380872D01*
X996573Y381222D01*
Y383342D01*
X996353Y383562D01*
X995863D01*
G37*
G36*
G01X1005294Y403302D02*
X1004043D01*
Y405165D01*
X1004477Y405599D01*
Y413733D01*
X1004083Y414127D01*
Y415382D01*
X1004409Y415708D01*
X1005899D01*
X1006139Y415468D01*
Y414228D01*
X1005529Y413618D01*
X1004858D01*
X1004827Y413587D01*
Y405578D01*
X1005294Y405111D01*
Y403302D01*
G37*
G36*
G01X993328Y432961D02*
G03I-720J0D01*
G37*
G36*
G01X991817Y529902D02*
G03I-720J0D01*
G37*
G36*
G01X1003360Y594692D02*
G03I-720J0D01*
G37*
G36*
G01X1004200Y1336862D02*
X1241800D01*
X1242620Y1336042D01*
Y1262552D01*
X1241200Y1261133D01*
X1229237D01*
X1229206Y1261144D01*
G03X1228799Y1261212I-408J-1189D01*
G01X1227389D01*
G03X1226982Y1261144I1J-1257D01*
G01X1226951Y1261133D01*
X1223516D01*
X1220148Y1264501D01*
X1210738D01*
X1210006Y1265232D01*
Y1265923D01*
X1210025Y1265962D01*
G03X1210152Y1266546I-1275J583D01*
G03X1207348I-1402J0D01*
G03X1207475Y1265962I1402J-1D01*
G01X1207494Y1265923D01*
Y1264712D01*
G03X1207862Y1263824I1255J0D01*
G01X1208774Y1262912D01*
X1206959Y1261097D01*
X1197012D01*
X1196726Y1261382D01*
Y1262179D01*
X1196745Y1262218D01*
G03X1196872Y1262802I-1275J583D01*
G03X1195470Y1264204I-1402J0D01*
G03X1195086Y1264150I1J-1402D01*
G02X1194576Y1264535I-110J385D01*
G01Y1266916D01*
G03X1194992Y1267912I-986J997D01*
G03X1193590Y1269314I-1402J0D01*
G03X1193374Y1269297I2J-1402D01*
G02X1192919Y1269762I-61J395D01*
G03X1192940Y1270004I-1381J242D01*
G03X1191538Y1268602I-1402J0D01*
G03X1192031Y1268692I-1J1402D01*
G02X1192287Y1268430I70J-187D01*
G03X1192237Y1268279I1304J-516D01*
G03X1192064Y1267642I1083J-636D01*
G01Y1264194D01*
G02X1191381Y1263911I-400J0D01*
G01X1190826Y1264466D01*
X1180453D01*
X1180436Y1264482D01*
Y1265249D01*
X1180455Y1265288D01*
G03X1180582Y1265872I-1275J583D01*
G03X1177778I-1402J0D01*
G03X1177905Y1265288I1402J-1D01*
G01X1177924Y1265249D01*
Y1263962D01*
G03X1178292Y1263074I1255J0D01*
G01X1178633Y1262732D01*
X1176963Y1261062D01*
X1163632D01*
X1160264Y1264430D01*
X1150654D01*
X1147322Y1261098D01*
X1134309D01*
X1130945Y1264462D01*
X1124040D01*
X1123205Y1263627D01*
X1120465D01*
X1120159Y1263321D01*
X1120134Y1263308D01*
G03X1119566Y1262740I666J-1234D01*
G01X1119553Y1262715D01*
X1118006Y1261168D01*
X1109951D01*
X1107996Y1263122D01*
Y1267279D01*
X1108015Y1267318D01*
G03X1108142Y1267902I-1275J583D01*
G03X1105338I-1402J0D01*
G03X1105465Y1267318I1402J-1D01*
G01X1105484Y1267279D01*
Y1263268D01*
G02X1105142Y1263127I-200J0D01*
G01X1104913Y1263355D01*
X1104924Y1263451D01*
G03X1104932Y1263602I-1394J150D01*
G03X1103530Y1265004I-1402J0D01*
G03X1102226Y1264117I0J-1402D01*
G02X1101571Y1263981I-372J147D01*
G01X1101121Y1264431D01*
X1090735D01*
X1087473Y1261169D01*
X1075736D01*
Y1263119D01*
X1075755Y1263158D01*
G03X1075882Y1263742I-1275J583D01*
G03X1073078I-1402J0D01*
G03X1073205Y1263158I1402J-1D01*
G01X1073224Y1263119D01*
Y1262662D01*
G02X1072541Y1262379I-400J0D01*
G01X1070454Y1264466D01*
X1061518D01*
X1058114Y1261062D01*
X1046186D01*
Y1262869D01*
X1046205Y1262908D01*
G03X1046332Y1263492I-1275J583D01*
G03X1044930Y1264894I-1402J0D01*
G03X1043561Y1263793I0J-1402D01*
G02X1042887Y1263597I-391J86D01*
G01X1042054Y1264430D01*
X1032769D01*
X1032036Y1265162D01*
Y1265909D01*
X1032055Y1265948D01*
G03X1032182Y1266532I-1275J583D01*
G03X1029378I-1402J0D01*
G03X1029505Y1265948I1402J-1D01*
G01X1029524Y1265909D01*
Y1264642D01*
G03X1029892Y1263754I1255J0D01*
G01X1030139Y1263507D01*
X1027800Y1261168D01*
X1015746D01*
X1012413Y1264501D01*
X1003414D01*
X1002614Y1265301D01*
Y1335276D01*
X1004200Y1336862D01*
G37*
G36*
G01X997139Y1286985D02*
G03I-464J0D01*
G37*
G36*
G01X1032040Y1420330D02*
G02I-15800J0D01*
G37*
G36*
G01X1854794Y68469D02*
X1854916Y68506D01*
X1855335Y68361D01*
G02X1855470Y68172I-65J-189D01*
G01Y54252D01*
G02X1849606Y48388I-5864J0D01*
G01X1803945D01*
G03X1794061Y38504I0J-9884D01*
G01Y4980D01*
X1794070D01*
Y3937D01*
G02X1792134Y2001I-1936J0D01*
G01X1529929D01*
G02X1527993Y3937I0J1936D01*
G01Y4980D01*
X1528002D01*
Y38504D01*
G03X1518118Y48388I-9884J0D01*
G01X1026772D01*
G02X1020908Y54252I0J5864D01*
G01Y67437D01*
G02X1021040Y67625I200J0D01*
G01X1021394Y67752D01*
G02X1021462Y67764I68J-188D01*
G01X1021616Y67692D01*
G03X1022852Y66289I24242J20111D01*
G01X1022904Y66177D01*
Y54252D01*
G03X1026772Y50384I3868J0D01*
G01X1168993D01*
G02X1169110Y50327I-24J-198D01*
G01X1169563Y49874D01*
G03X1170451Y49506I888J887D01*
G01X1180965D01*
G03X1181853Y49874I0J1255D01*
G01X1182306Y50327D01*
G02X1182423Y50384I141J-141D01*
G01X1257952D01*
G02X1258069Y50327I-24J-198D01*
G01X1258201Y50195D01*
G03X1258343Y50136I142J141D01*
G01X1267584D01*
G03X1267726Y50195I0J200D01*
G01X1267858Y50327D01*
G02X1267975Y50384I141J-141D01*
G01X1270062D01*
G02X1270179Y50327I-24J-198D01*
G01X1270515Y49991D01*
G03X1270657Y49932I142J141D01*
G01X1287100D01*
G03X1287242Y49991I0J200D01*
G01X1287578Y50327D01*
G02X1287695Y50384I141J-141D01*
G01X1355736D01*
G02X1355853Y50327I-24J-198D01*
G01X1356427Y49752D01*
G03X1357243Y49414I817J818D01*
G01X1417401D01*
G03X1418217Y49752I-1J1156D01*
G01X1418791Y50327D01*
G02X1418908Y50384I141J-141D01*
G01X1518118D01*
G02X1529998Y38504I0J-11880D01*
G01Y15466D01*
X1529977Y15423D01*
G03X1528452Y12480I2077J-2943D01*
G03X1529199Y10283I3604J0D01*
G03X1529920Y9558I2889J2152D01*
G01X1529998Y9402D01*
Y4000D01*
X1792064D01*
Y9351D01*
X1792147Y9512D01*
G03X1792960Y14545I-2105J2922D01*
G03X1792128Y15392I-2951J-2067D01*
G01X1792064Y15517D01*
Y38504D01*
G02X1803945Y50384I11881J-1D01*
G01X1849606D01*
G03X1853474Y54252I0J3868D01*
G01Y66828D01*
X1853522Y66936D01*
G03X1854755Y68419I-23592J20869D01*
G01X1854794Y68469D01*
G37*
G36*
G01X1011420Y150999D02*
X1023010D01*
X1023930Y150079D01*
Y144129D01*
X1023700Y143899D01*
X1011420D01*
X1010520Y144799D01*
Y150099D01*
X1011420Y150999D01*
G37*
G36*
G01X1016135Y215783D02*
X1018399D01*
G02X1018694Y215113I0J-400D01*
G03X1018300Y214099I1108J-1014D01*
G03X1019802Y212597I1502J0D01*
G03X1020111Y212629I1J1502D01*
G02X1020594Y212238I83J-391D01*
G01Y196983D01*
G03X1020689Y196502I1256J-2D01*
G01X1021994Y193352D01*
G02X1021624Y192799I-370J-153D01*
G01X1016520D01*
X1016032Y193287D01*
G02X1016173Y193628I141J141D01*
G01X1016194D01*
Y193864D01*
X1017236D01*
Y196364D01*
X1016194D01*
Y196600D01*
X1015395D01*
Y197590D01*
X1016186D01*
Y197826D01*
X1017230D01*
Y200326D01*
X1016186D01*
Y200562D01*
X1015395D01*
Y204974D01*
X1015795Y205374D01*
Y215443D01*
X1016135Y215783D01*
G37*
G36*
G01X1014220Y344900D02*
G03I-720J0D01*
G37*
G36*
G01X1006005Y380674D02*
X1007205D01*
Y378811D01*
X1006771Y378377D01*
Y374100D01*
X1007695Y373175D01*
Y371368D01*
X1007199Y370872D01*
Y368938D01*
X1006839Y368578D01*
X1005559D01*
X1005109Y369028D01*
Y370769D01*
X1005771Y371431D01*
Y371808D01*
Y373377D01*
X1006421Y374027D01*
Y378367D01*
X1006005Y378783D01*
Y380674D01*
G37*
G36*
G01X1013885Y380617D02*
X1015085D01*
Y378792D01*
X1014703Y378410D01*
Y375928D01*
X1014353D01*
Y378330D01*
X1013885Y378798D01*
Y380617D01*
G37*
G36*
G01X1017932Y393329D02*
Y394529D01*
X1019886D01*
X1020320Y394095D01*
X1024900D01*
X1026183Y395378D01*
X1027370D01*
X1027906Y394841D01*
Y393495D01*
X1027624Y393214D01*
X1025580D01*
X1025049Y393745D01*
X1020281D01*
X1019865Y393329D01*
X1017932D01*
G37*
G36*
G01X1017912Y381559D02*
Y382759D01*
X1019774D01*
X1020262Y382269D01*
X1023192D01*
Y381919D01*
X1020183D01*
X1019823Y381559D01*
X1017912D01*
G37*
G36*
G01X1015086Y403302D02*
X1013886D01*
Y405218D01*
X1014283Y405615D01*
Y411278D01*
X1014993Y411988D01*
X1015843D01*
X1016520Y411311D01*
Y410466D01*
X1015870Y409816D01*
X1015869Y409818D01*
X1014758D01*
X1014633Y409693D01*
Y405622D01*
X1015086Y405169D01*
Y403302D01*
G37*
G36*
G01X1017912Y399276D02*
Y400476D01*
X1019842D01*
X1020278Y400040D01*
X1023192D01*
Y399690D01*
X1020246D01*
X1019832Y399276D01*
X1017912D01*
G37*
G36*
G01X1012331Y430038D02*
G03I-720J0D01*
G37*
G36*
G01X1018231D02*
G03I-720J0D01*
G37*
G36*
G01X1019854Y503823D02*
G03I-709J0D01*
G37*
G36*
G01X1010214Y1552700D02*
Y1551040D01*
X1010454Y1550800D01*
X1012704D01*
X1013774Y1551870D01*
Y1555170D01*
X1013504Y1555440D01*
X1011854D01*
X1011484Y1555070D01*
Y1553690D01*
Y1553220D01*
X1011164Y1552900D01*
X1010414D01*
X1010214Y1552700D01*
G37*
G36*
G01X1006634Y1560400D02*
Y1551480D01*
X1007274Y1550840D01*
X1009094D01*
X1009214Y1550960D01*
Y1553190D01*
X1009534Y1553510D01*
Y1560490D01*
X1009504Y1560520D01*
X1006754D01*
X1006634Y1560400D01*
G37*
G36*
G01X1035486Y-33989D02*
G03I-557J0D01*
G37*
G36*
G01Y-29033D02*
G03I-557J0D01*
G37*
G36*
G01Y-13989D02*
G03I-557J0D01*
G37*
G36*
G01Y-23989D02*
G03I-557J0D01*
G37*
G36*
G01Y-19033D02*
G03I-557J0D01*
G37*
G36*
G01Y-3989D02*
G03I-557J0D01*
G37*
G36*
G01Y967D02*
G03I-557J0D01*
G37*
G36*
G01Y-9033D02*
G03I-557J0D01*
G37*
G36*
G01X1028176Y122732D02*
G03I-656J0D01*
G37*
G36*
G01X1038306Y128842D02*
G03I-656J0D01*
G37*
G36*
G01X1038891Y273706D02*
X1038873Y273688D01*
Y267378D01*
Y263029D01*
Y260655D01*
X1038318Y260100D01*
X1036918D01*
X1036359Y260659D01*
Y263053D01*
Y267261D01*
X1036383Y267285D01*
Y277167D01*
X1036590Y277374D01*
X1037966D01*
X1038333Y277007D01*
X1038891Y276449D01*
Y273706D01*
G37*
G36*
G01X1042521Y275059D02*
X1038341Y279238D01*
X1031488D01*
X1031257Y279469D01*
Y280480D01*
X1031488Y280711D01*
X1044607D01*
X1045480Y281584D01*
Y287221D01*
X1044450Y288251D01*
X1043079Y289622D01*
Y292061D01*
X1043418Y292400D01*
X1060218D01*
X1061018Y291600D01*
Y275400D01*
Y274400D01*
X1060618Y274000D01*
X1043580D01*
X1042521Y275059D01*
G37*
G36*
G01X1038167Y291017D02*
X1036512Y289362D01*
X1035740D01*
X1035370Y288992D01*
Y285134D01*
X1035284Y285048D01*
X1034879D01*
X1034873Y285054D01*
X1034748D01*
X1034629Y285173D01*
Y285298D01*
Y289298D01*
X1035379Y290048D01*
Y290548D01*
X1037019Y292189D01*
Y292724D01*
X1038809Y294514D01*
X1039344D01*
X1040229D01*
X1040509Y294794D01*
Y297444D01*
X1039839Y298114D01*
X1033969D01*
X1033719Y298364D01*
Y299994D01*
X1033949Y300224D01*
X1040959D01*
X1041889Y299294D01*
Y293904D01*
X1041899Y293894D01*
X1041407Y293402D01*
X1039890D01*
X1038167Y291679D01*
Y291017D01*
G37*
G36*
G01X1036433Y284960D02*
Y288282D01*
X1036980D01*
X1039792Y291094D01*
Y291684D01*
X1040429Y292321D01*
X1041857D01*
X1041993Y292185D01*
Y291740D01*
Y290242D01*
X1041721Y289970D01*
X1041194D01*
X1040466Y289242D01*
X1040333Y289109D01*
X1039693Y288469D01*
X1039464Y288240D01*
X1039263Y288039D01*
X1039078Y287854D01*
X1039000Y287776D01*
Y285484D01*
X1038329Y284814D01*
X1036579D01*
X1036433Y284960D01*
G37*
G36*
G01X1027056Y377108D02*
Y377202D01*
X1028141Y378287D01*
X1028270Y378224D01*
G03X1028787Y378104I518J1057D01*
G01X1032323D01*
X1032354Y378094D01*
G03X1032765Y378024I414J1187D01*
G01X1034524D01*
X1037473Y375076D01*
Y366868D01*
X1036643Y366038D01*
X1032006D01*
X1031276Y366768D01*
Y371166D01*
X1031248Y371194D01*
Y371910D01*
X1031242Y371916D01*
X1031239Y371993D01*
G03X1029239Y373895I-2000J-101D01*
G03X1029114Y373891I1J-2002D01*
G01X1029024Y373885D01*
X1028286Y374622D01*
Y375357D01*
G03X1027918Y376245I-1255J0D01*
G01X1027056Y377108D01*
G37*
G36*
G01X1029814Y383070D02*
G03I-720J0D01*
G37*
G36*
G01Y387872D02*
G03I-720J0D01*
G37*
G36*
G01X1027910Y510672D02*
G03I-720J0D01*
G37*
G36*
G01X1029940Y520032D02*
G03I-720J0D01*
G37*
G36*
G01X1031700Y598722D02*
G03I-720J0D01*
G37*
G36*
G01X1024460Y596152D02*
G03I-720J0D01*
G37*
G36*
G01X1037200Y596272D02*
G03I-720J0D01*
G37*
G36*
G01X1033580Y1552700D02*
Y1551040D01*
X1033820Y1550800D01*
X1036070D01*
X1037140Y1551870D01*
Y1555170D01*
X1036870Y1555440D01*
X1035220D01*
X1034850Y1555070D01*
Y1553690D01*
Y1553220D01*
X1034530Y1552900D01*
X1033780D01*
X1033580Y1552700D01*
G37*
G36*
G01X1030000Y1560400D02*
Y1551480D01*
X1030640Y1550840D01*
X1032460D01*
X1032580Y1550960D01*
Y1553190D01*
X1032900Y1553510D01*
Y1560490D01*
X1032870Y1560520D01*
X1030120D01*
X1030000Y1560400D01*
G37*
G36*
G01X1077343Y204724D02*
G02I-19685J0D01*
G37*
G36*
G01X1039270Y360712D02*
X1038709Y361273D01*
Y370158D01*
X1039049Y370498D01*
X1047984D01*
X1049020Y369462D01*
Y362762D01*
X1046970Y360712D01*
X1039270D01*
G37*
G36*
G01X1038743Y378362D02*
X1045720D01*
X1045750Y378332D01*
X1049580D01*
X1050670Y377242D01*
Y372182D01*
X1049960Y371472D01*
X1048426D01*
X1048399Y371500D01*
X1039182D01*
X1038474Y372208D01*
Y375491D01*
X1038320Y375645D01*
Y378062D01*
X1038386Y378128D01*
G03X1038743Y378362I-500J1153D01*
G37*
G36*
G01X1046865Y442699D02*
G03I-709J0D01*
G37*
G36*
G01X1038940Y589862D02*
G03I-720J0D01*
G37*
G36*
G01X1044440Y589362D02*
G03I-720J0D01*
G37*
G36*
G01X1050920Y598062D02*
G03I-720J0D01*
G37*
G36*
G01X1051110Y604172D02*
G03I-720J0D01*
G37*
G36*
G01X1053920Y612162D02*
G03I-720J0D01*
G37*
G36*
G01X1053366Y1560400D02*
Y1551480D01*
X1054006Y1550840D01*
X1055826D01*
X1055946Y1550960D01*
Y1553190D01*
X1056266Y1553510D01*
Y1560490D01*
X1056236Y1560520D01*
X1053486D01*
X1053366Y1560400D01*
G37*
G36*
G01X1067476Y151632D02*
G03I-656J0D01*
G37*
G36*
G01X1057000Y601232D02*
G03I-720J0D01*
G37*
G36*
G01X1056946Y1552700D02*
Y1551040D01*
X1057186Y1550800D01*
X1059436D01*
X1060506Y1551870D01*
Y1555170D01*
X1060236Y1555440D01*
X1058586D01*
X1058216Y1555070D01*
Y1553690D01*
Y1553220D01*
X1057896Y1552900D01*
X1057146D01*
X1056946Y1552700D01*
G37*
G36*
G01X1078926Y93462D02*
G03I-656J0D01*
G37*
G36*
G01X1073309Y294274D02*
X1107930D01*
X1107971Y294233D01*
X1113929D01*
X1116600Y291562D01*
Y230062D01*
X1114100Y227562D01*
X1080700D01*
X1072854Y235408D01*
Y293819D01*
X1073309Y294274D01*
G37*
G36*
G01X1074444Y476867D02*
G03I-720J0D01*
G37*
G36*
G01X1082615Y472577D02*
G03I-709J0D01*
G37*
G36*
G01X1079640Y1423452D02*
X1109300D01*
X1115410Y1417342D01*
Y1399652D01*
X1109250Y1393492D01*
X1106780D01*
X1105360Y1392072D01*
Y1360652D01*
X1106540Y1359472D01*
X1127740D01*
G02X1128084Y1358869I0J-400D01*
G03X1127598Y1357088I3016J-1780D01*
G03X1134602I3502J0D01*
G03X1134116Y1358869I-3502J1D01*
G02X1134460Y1359472I344J203D01*
G01X1152140D01*
G02X1152484Y1358869I0J-400D01*
G03X1151998Y1357088I3016J-1780D01*
G03X1159002I3502J0D01*
G03X1158516Y1358869I-3502J1D01*
G02X1158860Y1359472I344J203D01*
G01X1176540D01*
G02X1176884Y1358869I0J-400D01*
G03X1176398Y1357088I3016J-1780D01*
G03X1183402I3502J0D01*
G03X1182916Y1358869I-3502J1D01*
G02X1183260Y1359472I344J203D01*
G01X1189762D01*
X1190932Y1360642D01*
X1194742D01*
X1194968Y1360416D01*
Y1349139D01*
X1193371Y1347542D01*
X1078800D01*
X1076710Y1349632D01*
Y1420522D01*
X1079640Y1423452D01*
G37*
G36*
G01X1080312Y1552700D02*
Y1551040D01*
X1080552Y1550800D01*
X1082802D01*
X1083872Y1551870D01*
Y1555170D01*
X1083602Y1555440D01*
X1081952D01*
X1081582Y1555070D01*
Y1553690D01*
Y1553220D01*
X1081262Y1552900D01*
X1080512D01*
X1080312Y1552700D01*
G37*
G36*
G01X1076732Y1560400D02*
Y1551480D01*
X1077372Y1550840D01*
X1079192D01*
X1079312Y1550960D01*
Y1553190D01*
X1079632Y1553510D01*
Y1560490D01*
X1079602Y1560520D01*
X1076852D01*
X1076732Y1560400D01*
G37*
G36*
G01X1084580Y1598130D02*
X1091590D01*
X1091970Y1597750D01*
Y1590530D01*
X1092600Y1589900D01*
X1095710D01*
X1095960Y1590150D01*
Y1597550D01*
X1096530Y1598120D01*
X1105930D01*
X1106502Y1597548D01*
Y1565860D01*
X1105142Y1564500D01*
X1085200D01*
X1084200Y1565500D01*
Y1597750D01*
X1084580Y1598130D01*
G37*
G36*
G01X1103136Y133722D02*
G03I-656J0D01*
G37*
G36*
G01X1100098Y1560400D02*
Y1551480D01*
X1100738Y1550840D01*
X1102558D01*
X1102678Y1550960D01*
Y1553190D01*
X1102998Y1553510D01*
Y1560490D01*
X1102968Y1560520D01*
X1100218D01*
X1100098Y1560400D01*
G37*
G36*
G01X1107251Y1392261D02*
X1194567D01*
X1194968Y1391860D01*
Y1364502D01*
G03X1194568Y1363146I2102J-1357D01*
G03X1194654Y1362498I2502J2D01*
G02X1194268Y1361994I-386J-104D01*
G01X1190362D01*
X1189070Y1360702D01*
X1107882D01*
X1106642Y1361942D01*
Y1391652D01*
X1107251Y1392261D01*
G37*
G36*
G01X1157546Y1451234D02*
X1159780D01*
X1160017Y1450997D01*
Y1441628D01*
X1159607Y1441218D01*
X1159413Y1441024D01*
Y1433593D01*
Y1427663D01*
X1160023Y1427053D01*
X1163247D01*
X1165002Y1425298D01*
X1171246D01*
X1171360Y1425412D01*
Y1425564D01*
Y1429062D01*
X1171190Y1429232D01*
X1167475D01*
X1167453Y1429241D01*
X1167271Y1429423D01*
X1167022Y1429672D01*
X1165670D01*
X1165600Y1429742D01*
Y1430502D01*
X1165670Y1430572D01*
X1167386D01*
X1167671Y1430857D01*
X1167953Y1431139D01*
X1168012Y1431281D01*
Y1434599D01*
X1167953Y1434741D01*
X1167871Y1434823D01*
X1167729Y1434882D01*
X1164695D01*
X1164553Y1434941D01*
X1164542Y1434952D01*
X1164512Y1435025D01*
Y1435815D01*
X1164571Y1435957D01*
X1164582Y1435968D01*
X1164655Y1435998D01*
X1167729D01*
X1167871Y1436057D01*
X1167953Y1436139D01*
X1168012Y1436281D01*
Y1437015D01*
X1168071Y1437157D01*
X1168153Y1437239D01*
X1168295Y1437298D01*
X1174929D01*
X1175071Y1437239D01*
X1175253Y1437057D01*
G02X1175295Y1436996I-141J-142D01*
G01Y1428493D01*
X1175693Y1428095D01*
X1175746Y1428042D01*
X1184980D01*
X1185033Y1428095D01*
X1189609D01*
X1189620Y1428085D01*
X1189627Y1428092D01*
X1194886D01*
X1195572D01*
X1196762Y1429282D01*
Y1450442D01*
Y1457664D01*
X1197520Y1458422D01*
X1204560D01*
X1211400Y1451582D01*
X1214832Y1448150D01*
Y1426412D01*
Y1394712D01*
X1213602Y1393482D01*
X1192392D01*
X1120130D01*
X1107632D01*
X1107282D01*
X1107197Y1393567D01*
X1106762Y1394002D01*
Y1421462D01*
X1108752Y1423452D01*
X1117872D01*
X1119198Y1424778D01*
Y1426180D01*
X1120008Y1426990D01*
X1125278D01*
X1126970Y1425298D01*
X1133054D01*
X1133209Y1425453D01*
X1133290Y1425534D01*
Y1428964D01*
X1133209Y1429045D01*
X1133079Y1429175D01*
X1133002Y1429252D01*
X1129299D01*
X1129128Y1429423D01*
X1128869Y1429682D01*
X1127550D01*
X1127470Y1429762D01*
Y1430492D01*
X1127570Y1430592D01*
X1129264D01*
X1129542Y1430870D01*
X1129810Y1431139D01*
X1129869Y1431281D01*
Y1434599D01*
X1129810Y1434741D01*
X1129728Y1434823D01*
X1129586Y1434882D01*
X1126552D01*
X1126410Y1434941D01*
X1126399Y1434952D01*
X1126369Y1435025D01*
Y1435815D01*
X1126428Y1435957D01*
X1126439Y1435968D01*
X1126512Y1435998D01*
X1129586D01*
X1129728Y1436057D01*
X1129810Y1436139D01*
X1129869Y1436281D01*
Y1437015D01*
X1129928Y1437157D01*
X1130010Y1437239D01*
X1130152Y1437298D01*
X1136786D01*
X1136928Y1437239D01*
X1137110Y1437057D01*
G02X1137152Y1436996I-141J-142D01*
G01Y1428493D01*
X1137550Y1428095D01*
X1137633Y1428012D01*
X1146810D01*
X1146893Y1428095D01*
X1151466D01*
X1151477Y1428085D01*
X1151484Y1428092D01*
X1156266D01*
X1156502D01*
X1157223Y1428813D01*
Y1429049D01*
Y1437955D01*
X1157081Y1438097D01*
X1155129Y1440049D01*
Y1448817D01*
X1157546Y1451234D01*
G37*
G36*
G01X1109609Y1526046D02*
G03I-491J0D01*
G37*
G36*
G01X1103678Y1552700D02*
Y1551040D01*
Y1548494D01*
X1104022Y1548150D01*
X1105752D01*
X1106012Y1548410D01*
Y1550800D01*
Y1552670D01*
X1105782Y1552900D01*
X1104628D01*
X1103878D01*
X1103678Y1552700D01*
G37*
G36*
G01X1130604Y66786D02*
G03I-656J0D01*
G37*
G36*
G01X1121264Y312200D02*
G03I-720J0D01*
G37*
G36*
G01X1130715Y301637D02*
G03I-720J0D01*
G37*
G36*
G01X1123210Y1557300D02*
X1134720D01*
X1135660Y1556360D01*
Y1552530D01*
X1134990Y1551860D01*
Y1540650D01*
X1136790Y1538850D01*
Y1522520D01*
X1135660Y1521390D01*
X1123860D01*
X1122500Y1522750D01*
Y1556590D01*
X1123210Y1557300D01*
G37*
G36*
G01X1143022Y366532D02*
G03I-720J0D01*
G37*
G36*
G01X1143372Y611122D02*
G03I-582J0D01*
G37*
G36*
G01X1151974Y1477223D02*
X1192532D01*
X1195586Y1474169D01*
Y1429672D01*
X1195020Y1429106D01*
X1176717D01*
X1176460Y1429362D01*
Y1437405D01*
X1176560Y1437505D01*
X1181888D01*
X1182548Y1438165D01*
Y1440776D01*
X1184082Y1442310D01*
Y1449594D01*
X1180672Y1453004D01*
X1157787D01*
X1154173Y1449390D01*
Y1439469D01*
X1156142Y1437500D01*
Y1429306D01*
X1155942Y1429106D01*
X1138402D01*
X1138348Y1429160D01*
Y1437267D01*
X1138579Y1437498D01*
X1143925D01*
X1144442Y1438015D01*
Y1438464D01*
G03X1144443Y1438485I-797J48D01*
G01Y1440848D01*
G03X1144435Y1440956I-799J-5D01*
G01X1144421Y1441055D01*
X1145956Y1442591D01*
Y1453244D01*
X1149032Y1456320D01*
Y1474281D01*
X1151974Y1477223D01*
G37*
G36*
G01X1144351Y1541730D02*
Y1548778D01*
X1144591Y1549018D01*
X1146447D01*
X1146757Y1548708D01*
Y1539941D01*
Y1537757D01*
X1145920Y1536920D01*
X1142490D01*
X1141970Y1537440D01*
Y1539349D01*
X1144351Y1541730D01*
G37*
G36*
G01X1140454Y1542338D02*
Y1553094D01*
X1141390Y1554030D01*
X1142480D01*
X1142867Y1553643D01*
Y1551138D01*
Y1542331D01*
X1142837Y1542301D01*
X1140491D01*
X1140454Y1542338D01*
G37*
G36*
G01X1154072Y610322D02*
G03I-582J0D01*
G37*
G36*
G01X1166441Y1617729D02*
G03I-491J0D01*
G37*
G36*
G01X1181118Y289814D02*
G03I-720J0D01*
G37*
G36*
G01X1172260Y310902D02*
G03I-720J0D01*
G37*
G36*
G01X1175562Y585632D02*
G03I-582J0D01*
G37*
G36*
G01X1175462Y592652D02*
G03I-582J0D01*
G37*
G36*
G01X1174572Y602192D02*
G03I-582J0D01*
G37*
G36*
G01X1178080Y1552150D02*
X1182370D01*
X1183270Y1551250D01*
Y1522420D01*
X1182326Y1521476D01*
X1177774D01*
X1177020Y1522230D01*
Y1529912D01*
G03Y1535915I-1805J3002D01*
G01Y1551090D01*
X1178080Y1552150D01*
G37*
G36*
G01X1171580Y1628490D02*
X1177580D01*
X1177960Y1628110D01*
Y1625020D01*
X1178320Y1624660D01*
X1181300D01*
X1181360Y1624600D01*
Y1623970D01*
X1181220Y1623830D01*
X1178230D01*
X1177820Y1623420D01*
Y1622250D01*
X1177580Y1622010D01*
X1171920D01*
X1171300Y1622630D01*
Y1628210D01*
X1171580Y1628490D01*
G37*
G36*
G01X1192356Y56822D02*
G03I-656J0D01*
G37*
G36*
G01X1192500Y206362D02*
X1197500D01*
X1198000Y205862D01*
Y179862D01*
X1197500Y179362D01*
X1192600D01*
X1192000Y179962D01*
Y205862D01*
X1192500Y206362D01*
G37*
G36*
G01X1187500Y206862D02*
X1190000D01*
X1190500Y206362D01*
Y195862D01*
Y179862D01*
X1190000Y179362D01*
X1186500D01*
X1185500Y180362D01*
Y186762D01*
X1186700Y187962D01*
Y190262D01*
X1185500Y191462D01*
Y204862D01*
X1187500Y206862D01*
G37*
G36*
G01X1197666Y1563587D02*
G03I-485J0D01*
G37*
G36*
G01X1196714Y1580678D02*
G03I-720J0D01*
G37*
G36*
G01Y1575686D02*
G03I-720J0D01*
G37*
G36*
G01Y1592590D02*
G03I-720J0D01*
G37*
G36*
G01Y1587598D02*
G03I-720J0D01*
G37*
G36*
G01X1184992Y1606521D02*
G03I-491J0D01*
G37*
G36*
G01X1204578Y185451D02*
G03I-720J0D01*
G37*
G36*
G01X1209085Y271151D02*
G03I-720J0D01*
G37*
G36*
G01X1203320Y759662D02*
G03I-720J0D01*
G37*
G36*
G01X1201670Y1580678D02*
G03I-720J0D01*
G37*
G36*
G01Y1575686D02*
G03I-720J0D01*
G37*
G36*
G01X1213730D02*
G03I-720J0D01*
G37*
G36*
G01X1208774D02*
G03I-720J0D01*
G37*
G36*
G01X1213730Y1580678D02*
G03I-720J0D01*
G37*
G36*
G01X1208774D02*
G03I-720J0D01*
G37*
G36*
G01X1202014Y1599884D02*
G03I-720J0D01*
G37*
G36*
G01X1201670Y1592590D02*
G03I-720J0D01*
G37*
G36*
G01Y1587598D02*
G03I-720J0D01*
G37*
G36*
G01X1206970Y1599884D02*
G03I-720J0D01*
G37*
G36*
G01X1214074D02*
G03I-720J0D01*
G37*
G36*
G01X1213730Y1587598D02*
G03I-720J0D01*
G37*
G36*
G01X1208774D02*
G03I-720J0D01*
G37*
G36*
G01X1213730Y1592590D02*
G03I-720J0D01*
G37*
G36*
G01X1208774D02*
G03I-720J0D01*
G37*
G36*
G01X1202014Y1604876D02*
G03I-720J0D01*
G37*
G36*
G01Y1611796D02*
G03I-720J0D01*
G37*
G36*
G01Y1616788D02*
G03I-720J0D01*
G37*
G36*
G01X1206970Y1604876D02*
G03I-720J0D01*
G37*
G36*
G01Y1611796D02*
G03I-720J0D01*
G37*
G36*
G01Y1616788D02*
G03I-720J0D01*
G37*
G36*
G01X1214074D02*
G03I-720J0D01*
G37*
G36*
G01Y1604876D02*
G03I-720J0D01*
G37*
G36*
G01Y1611796D02*
G03I-720J0D01*
G37*
G36*
G01X1228220Y380400D02*
G03I-720J0D01*
G37*
G36*
G01X1260124Y761205D02*
X1323867D01*
X1331056Y754016D01*
Y682126D01*
X1381017Y632165D01*
X1424427D01*
X1439971Y616621D01*
Y604661D01*
X1433221Y597911D01*
X1416481D01*
X1415147Y599245D01*
X1371067D01*
X1234857Y735455D01*
Y746815D01*
X1227027Y754645D01*
Y759895D01*
X1228337Y761205D01*
X1257210D01*
Y751773D01*
X1257205Y751750D01*
G03X1257167Y751485I1462J-345D01*
G02X1256772Y751107I-399J22D01*
G03X1255285Y749605I15J-1502D01*
G03X1256787Y748103I1502J0D01*
G03X1258287Y749525I0J1502D01*
G02X1258682Y749903I399J-22D01*
G03X1260169Y751405I-15J1502D01*
G03X1260129Y751750I-1502J1D01*
G01X1260124Y751773D01*
Y761205D01*
G37*
G36*
G01X1225790Y1580678D02*
G03I-720J0D01*
G37*
G36*
G01Y1575686D02*
G03I-720J0D01*
G37*
G36*
G01X1220834D02*
G03I-720J0D01*
G37*
G36*
G01Y1580678D02*
G03I-720J0D01*
G37*
G36*
G01X1232894D02*
G03I-720J0D01*
G37*
G36*
G01Y1575686D02*
G03I-720J0D01*
G37*
G36*
G01X1219030Y1599884D02*
G03I-720J0D01*
G37*
G36*
G01X1226134D02*
G03I-720J0D01*
G37*
G36*
G01X1231090D02*
G03I-720J0D01*
G37*
G36*
G01X1225790Y1592590D02*
G03I-720J0D01*
G37*
G36*
G01X1220834D02*
G03I-720J0D01*
G37*
G36*
G01X1225790Y1587598D02*
G03I-720J0D01*
G37*
G36*
G01X1220834D02*
G03I-720J0D01*
G37*
G36*
G01X1232894D02*
G03I-720J0D01*
G37*
G36*
G01Y1592590D02*
G03I-720J0D01*
G37*
G36*
G01X1219030Y1616788D02*
G03I-720J0D01*
G37*
G36*
G01Y1604876D02*
G03I-720J0D01*
G37*
G36*
G01Y1611796D02*
G03I-720J0D01*
G37*
G36*
G01X1226134D02*
G03I-720J0D01*
G37*
G36*
G01Y1604876D02*
G03I-720J0D01*
G37*
G36*
G01X1231090Y1611796D02*
G03I-720J0D01*
G37*
G36*
G01Y1604876D02*
G03I-720J0D01*
G37*
G36*
G01X1226134Y1616788D02*
G03I-720J0D01*
G37*
G36*
G01X1231090D02*
G03I-720J0D01*
G37*
G36*
G01X1244464Y116832D02*
G03I-656J0D01*
G37*
G36*
G01X1237850Y1575686D02*
G03I-720J0D01*
G37*
G36*
G01Y1580678D02*
G03I-720J0D01*
G37*
G36*
G01X1244954D02*
G03I-720J0D01*
G37*
G36*
G01X1249910D02*
G03I-720J0D01*
G37*
G36*
G01X1244954Y1575686D02*
G03I-720J0D01*
G37*
G36*
G01X1249910D02*
G03I-720J0D01*
G37*
G36*
G01X1243150Y1599884D02*
G03I-720J0D01*
G37*
G36*
G01X1238194D02*
G03I-720J0D01*
G37*
G36*
G01X1250254D02*
G03I-720J0D01*
G37*
G36*
G01X1237850Y1587598D02*
G03I-720J0D01*
G37*
G36*
G01Y1592590D02*
G03I-720J0D01*
G37*
G36*
G01X1249910D02*
G03I-720J0D01*
G37*
G36*
G01X1244954D02*
G03I-720J0D01*
G37*
G36*
G01Y1587598D02*
G03I-720J0D01*
G37*
G36*
G01X1249910D02*
G03I-720J0D01*
G37*
G36*
G01X1243150Y1616788D02*
G03I-720J0D01*
G37*
G36*
G01X1238194D02*
G03I-720J0D01*
G37*
G36*
G01X1243150Y1611796D02*
G03I-720J0D01*
G37*
G36*
G01Y1604876D02*
G03I-720J0D01*
G37*
G36*
G01X1238194Y1611796D02*
G03I-720J0D01*
G37*
G36*
G01Y1604876D02*
G03I-720J0D01*
G37*
G36*
G01X1250254Y1611796D02*
G03I-720J0D01*
G37*
G36*
G01Y1604876D02*
G03I-720J0D01*
G37*
G36*
G01Y1616788D02*
G03I-720J0D01*
G37*
G36*
G01X1267339Y56823D02*
X1260560D01*
X1258431D01*
X1258110Y56502D01*
Y51702D01*
X1258675Y51137D01*
X1260770D01*
X1267252D01*
X1267661Y51546D01*
Y56501D01*
X1267339Y56823D01*
G37*
G36*
G01X1257610Y58222D02*
X1260534D01*
X1266937D01*
X1267252Y58537D01*
X1267661Y58946D01*
Y63901D01*
Y84859D01*
X1266741Y85779D01*
X1256465D01*
X1255195Y84509D01*
Y58636D01*
X1255609Y58222D01*
X1257610D01*
G37*
G36*
G01X1253617Y111903D02*
G03I-656J0D01*
G37*
G36*
G01X1294952Y142501D02*
X1295867Y144707D01*
G02X1296530Y144826I370J-153D01*
G03X1297605Y144357I1075J998D01*
G03X1298426Y144608I0J1468D01*
G01X1298476Y144642D01*
X1298738D01*
Y144313D01*
X1296558Y142134D01*
G03X1296390Y141726I408J-407D01*
G01Y137440D01*
X1294417Y135467D01*
Y135051D01*
X1292533Y133167D01*
X1292491Y133152D01*
G03X1292251Y132999I225J-617D01*
G01X1289078Y129821D01*
G03X1288886Y129357I465J-464D01*
G01Y128402D01*
X1287943Y127458D01*
X1287877Y127448D01*
G03X1286815Y126752I215J-1487D01*
G01X1286803Y126732D01*
X1285994Y125923D01*
G03X1285582Y125096I1030J-1029D01*
G01X1285572Y125030D01*
X1283720Y123178D01*
G03X1283539Y122957I1031J-1029D01*
G01X1282287Y121084D01*
X1282220Y121017D01*
Y120984D01*
X1279639Y117122D01*
X1274967Y112450D01*
X1274024D01*
X1267531Y118943D01*
X1267516Y118988D01*
G03X1267482Y119078I-1379J-470D01*
G01X1266368Y121768D01*
G03X1266233Y122020I-1345J-558D01*
G01X1264385Y124786D01*
Y126483D01*
X1265244Y127342D01*
G03X1265670Y128372I-1030J1029D01*
G01Y130800D01*
X1268323Y133453D01*
X1269554Y132222D01*
X1270204D01*
X1277208Y139226D01*
X1277452D01*
X1277475Y139220D01*
G03X1277820Y139180I344J1462D01*
G03X1278165Y139220I1J1502D01*
G01X1278188Y139226D01*
X1280314D01*
G03X1281344Y139652I1J1456D01*
G01X1283997Y142306D01*
X1286293D01*
G03X1286740Y142376I1J1456D01*
G01X1286770Y142386D01*
X1288206D01*
G03X1288566Y142434I0J1376D01*
G01X1288678Y142464D01*
X1288902Y142241D01*
X1287038Y140377D01*
X1286959Y140374D01*
G03X1286449Y140153I25J-756D01*
G01X1283150Y136854D01*
X1283046Y136873D01*
G03X1282764Y136900I-284J-1475D01*
G03X1281262Y135398I0J-1502D01*
G03X1281289Y135116I1502J2D01*
G01X1281308Y135012D01*
X1281080Y134784D01*
X1280982Y134882D01*
X1280815Y134714D01*
X1280077Y135452D01*
X1278310Y133685D01*
X1278895Y133099D01*
X1277572Y131775D01*
X1277373Y131974D01*
G03X1276664I-355J-355D01*
G01X1274684Y129994D01*
G03Y129285I355J-355D01*
G01X1275119Y128850D01*
X1274425Y128156D01*
X1272873D01*
X1270971Y130059D01*
G03X1270261I-355J-354D01*
G01X1265241Y125039D01*
G03Y124329I354J-355D01*
G01X1268069Y121501D01*
G03X1268511Y121362I354J355D01*
G01X1268613Y121380D01*
X1272080Y117913D01*
X1272062Y117811D01*
G03X1272201Y117369I494J-88D01*
G01X1275029Y114541D01*
G03X1275739I355J354D01*
G01X1280759Y119561D01*
G03Y120271I-354J355D01*
G01X1280250Y120780D01*
X1281855Y122385D01*
G03X1282076Y122920I-535J534D01*
G01Y123239D01*
X1283738Y124900D01*
G03Y125609I-355J354D01*
G01X1282527Y126820D01*
X1283685Y127977D01*
X1283860Y127803D01*
X1285172Y129115D01*
X1285201Y129129D01*
G03X1285400Y129272I-336J678D01*
G01X1285764Y129636D01*
X1285868Y129617D01*
G03X1286150Y129590I284J1475D01*
G03X1287652Y131092I0J1502D01*
G03X1287625Y131374I-1502J-2D01*
G01X1287606Y131478D01*
X1287991Y131863D01*
G03X1288158Y132117I-536J534D01*
G01X1288174Y132155D01*
X1288890Y132870D01*
X1288722Y133037D01*
X1289460Y133775D01*
X1289459Y133776D01*
X1290185Y134500D01*
X1290352Y134332D01*
X1291096Y135077D01*
G03X1291351Y135814I-629J630D01*
G02X1291691Y136258I397J48D01*
G03X1292980Y137745I-213J1487D01*
G03X1292134Y139096I-1502J0D01*
G01Y139612D01*
X1294810Y142288D01*
G03X1294952Y142501I-465J464D01*
G37*
G36*
G01X1253986Y1304608D02*
X1302316D01*
X1304814Y1302109D01*
Y1299253D01*
X1304816Y1299252D01*
Y1298608D01*
X1314816Y1288608D01*
Y1283608D01*
X1314926Y1283497D01*
Y1283381D01*
X1316501Y1281806D01*
X1316617D01*
X1316816Y1281608D01*
X1335264D01*
X1339965Y1276906D01*
X1340017D01*
X1340316Y1276608D01*
X1345816D01*
X1346314Y1276109D01*
Y1270985D01*
X1346316Y1270984D01*
Y1270608D01*
X1348316Y1268608D01*
X1465316D01*
X1478616Y1281908D01*
X1500916D01*
X1505816Y1286808D01*
Y1297874D01*
X1512336Y1304394D01*
X1571198D01*
X1574130Y1301462D01*
Y1249018D01*
X1516407Y1191295D01*
X1516383D01*
X1514956Y1189868D01*
Y1145200D01*
X1512506Y1142750D01*
X1448395D01*
X1447882Y1142237D01*
Y1139168D01*
G02X1447499Y1138769I-400J1D01*
G03X1447208Y1138723I56J-1300D01*
G01X1447182Y1138716D01*
X1446954D01*
Y1138963D01*
G03X1446653Y1139778I-1251J1D01*
G01X1446604Y1139834D01*
Y1140032D01*
X1446658Y1140089D01*
G03X1447004Y1140973I-956J884D01*
G03X1444402I-1301J0D01*
G03X1444748Y1140089I1302J0D01*
G01X1444802Y1140032D01*
Y1139834D01*
X1444753Y1139778D01*
G03X1444452Y1138963I950J-814D01*
G01Y1138563D01*
G03X1445703Y1137312I1251J0D01*
G03X1445883Y1137325I0J1251D01*
G02X1446320Y1137056I58J-396D01*
G03X1446598Y1136587I1233J414D01*
G02X1446593Y1136310I-147J-136D01*
G03X1446202Y1135359I961J-951D01*
G03X1447498Y1134008I1352J0D01*
G02X1447882Y1133609I-16J-400D01*
G01Y1132759D01*
G02X1447499Y1132360I-400J1D01*
G03X1446253Y1131060I55J-1300D01*
G03X1446598Y1130178I1300J0D01*
G02X1446593Y1129901I-147J-136D01*
G03X1446240Y1129270I961J-952D01*
G02X1446001Y1129123I-194J48D01*
G03X1445704Y1129157I-296J-1267D01*
G03X1444403Y1127856I0J-1301D01*
G03X1444748Y1126974I1300J0D01*
G02X1444743Y1126698I-147J-135D01*
G03X1444389Y1126065I960J-952D01*
G02X1444150Y1125918I-194J48D01*
G03X1443854Y1125952I-295J-1267D01*
G03X1442553Y1124651I0J-1301D01*
G03X1442898Y1123769I1300J0D01*
G02X1442893Y1123492I-147J-136D01*
G03X1442540Y1122861I961J-952D01*
G02X1442301Y1122714I-194J48D01*
G03X1442004Y1122748I-296J-1267D01*
G03X1440703Y1121447I0J-1301D01*
G03X1441048Y1120565I1300J0D01*
G02X1441043Y1120289I-147J-135D01*
G03X1442003Y1117985I960J-952D01*
G03X1442355Y1118032I-1J1352D01*
G02X1442600Y1117893I52J-193D01*
G03X1442897Y1117360I1253J349D01*
G02X1442893Y1117084I-147J-136D01*
G03X1442540Y1116453I961J-952D01*
G02X1442301Y1116306I-194J48D01*
G03X1442004Y1116340I-296J-1267D01*
G03X1440703Y1115039I0J-1301D01*
G03X1441048Y1114157I1300J0D01*
G02X1441043Y1113881I-147J-135D01*
G03X1440689Y1113248I960J-952D01*
G02X1440450Y1113101I-194J48D01*
G03X1440154Y1113135I-295J-1267D01*
G03X1438853Y1111834I0J-1301D01*
G03X1439198Y1110952I1300J0D01*
G02X1439193Y1110675I-147J-136D01*
G03X1438840Y1110044I961J-952D01*
G02X1438601Y1109897I-194J48D01*
G03X1438304Y1109931I-296J-1267D01*
G03X1437003Y1108630I0J-1301D01*
G03X1437348Y1107748I1300J0D01*
G02X1437343Y1107472I-147J-135D01*
G03X1436989Y1106840I960J-953D01*
G02X1436750Y1106693I-194J48D01*
G03X1436454Y1106727I-295J-1267D01*
G03X1435153Y1105426I0J-1301D01*
G03X1435498Y1104544I1300J0D01*
G02X1435493Y1104267I-147J-136D01*
G03X1435140Y1103635I961J-951D01*
G02X1434900Y1103488I-194J48D01*
G03X1434604Y1103522I-295J-1267D01*
G03X1433303Y1102221I0J-1301D01*
G03X1433648Y1101339I1300J0D01*
G02X1433643Y1101063I-147J-135D01*
G03X1433289Y1100431I960J-953D01*
G02X1433050Y1100284I-194J48D01*
G03X1432753Y1100318I-296J-1267D01*
G03X1431452Y1099017I0J-1301D01*
G03X1431797Y1098134I1301J-1D01*
G02X1431793Y1097858I-147J-136D01*
G03X1431440Y1097226I961J-951D01*
G02X1431200Y1097079I-194J47D01*
G03X1430903Y1097113I-296J-1267D01*
G03X1430607Y1097079I-1J-1301D01*
G02X1430368Y1097226I-45J195D01*
G03X1430014Y1097859I-1314J-319D01*
G02X1430009Y1098135I142J141D01*
G03X1430354Y1099017I-955J882D01*
G03X1427752I-1301J0D01*
G03X1428097Y1098134I1301J-1D01*
G02X1428093Y1097858I-147J-136D01*
G03X1427740Y1097226I961J-951D01*
G02X1427500Y1097079I-194J47D01*
G03X1427203Y1097113I-296J-1267D01*
G03X1425902Y1095812I0J-1301D01*
G03X1426247Y1094930I1300J0D01*
G02X1426242Y1094654I-147J-135D01*
G03X1425851Y1093703I961J-951D01*
G03X1427203Y1092351I1352J0D01*
G03X1427555Y1092398I-1J1352D01*
G02X1427800Y1092258I52J-193D01*
G03X1428097Y1091725I1253J349D01*
G02X1428093Y1091449I-147J-136D01*
G03X1427740Y1090818I961J-952D01*
G02X1427501Y1090671I-194J48D01*
G03X1427204Y1090705I-296J-1267D01*
G03X1425903Y1089404I0J-1301D01*
G03X1426248Y1088522I1300J0D01*
G02X1426243Y1088246I-147J-135D01*
G03X1425889Y1087614I960J-953D01*
G02X1425650Y1087467I-194J48D01*
G03X1425354Y1087501I-295J-1267D01*
G03X1424053Y1086200I0J-1301D01*
G03X1424398Y1085318I1300J0D01*
G02X1424393Y1085041I-147J-136D01*
G03X1424040Y1084409I961J-951D01*
G02X1423800Y1084262I-194J47D01*
G03X1423503Y1084296I-296J-1267D01*
G03X1422202Y1082995I0J-1301D01*
G03X1422547Y1082113I1300J0D01*
G02X1422542Y1081836I-147J-136D01*
G03X1422151Y1080885I961J-951D01*
G03X1423081Y1079601I1351J0D01*
G01X1423218Y1079555D01*
Y1077864D01*
X1423083Y1077818D01*
G03X1422202Y1076587I420J-1231D01*
G03X1422547Y1075705I1300J0D01*
G02X1422542Y1075428I-147J-136D01*
G03X1422151Y1074477I961J-951D01*
G03X1423081Y1073193I1351J0D01*
G01X1423218Y1073147D01*
Y1071455D01*
X1423083Y1071409D01*
G03X1422202Y1070178I420J-1231D01*
G03X1422547Y1069296I1300J0D01*
G02X1422542Y1069019I-147J-136D01*
G03X1422151Y1068068I961J-951D01*
G03X1423081Y1066784I1351J0D01*
G01X1423218Y1066738D01*
Y1065047D01*
X1423083Y1065001D01*
G03X1422202Y1063770I420J-1231D01*
G03X1422547Y1062888I1300J0D01*
G02X1422542Y1062611I-147J-136D01*
G03X1422151Y1061660I961J-951D01*
G03X1423081Y1060376I1351J0D01*
G01X1423218Y1060330D01*
Y1058638D01*
X1423083Y1058592D01*
G03X1422202Y1057361I420J-1231D01*
G03X1422547Y1056479I1300J0D01*
G02X1422542Y1056202I-147J-136D01*
G03X1422151Y1055251I961J-951D01*
G03X1423081Y1053967I1351J0D01*
G01X1423218Y1053921D01*
Y1052229D01*
X1423083Y1052183D01*
G03X1422202Y1050952I420J-1231D01*
G03X1422547Y1050070I1300J0D01*
G02X1422542Y1049793I-147J-136D01*
G03X1422151Y1048842I961J-951D01*
G03X1423099Y1047552I1352J0D01*
G01X1423146Y1047537D01*
X1424250Y1046433D01*
X1424175Y1046301D01*
G03X1424002Y1045639I1180J-662D01*
G03X1425354Y1044287I1352J0D01*
G03X1425705Y1044333I1J1352D01*
G02X1425950Y1044194I53J-193D01*
G03X1426247Y1043662I1253J350D01*
G02X1426242Y1043385I-147J-136D01*
G03X1425851Y1042434I961J-951D01*
G03X1427203Y1041082I1352J0D01*
G03X1427555Y1041129I-1J1352D01*
G02X1427800Y1040990I52J-193D01*
G03X1428097Y1040457I1253J349D01*
G02X1428093Y1040181I-147J-136D01*
G03X1427702Y1039230I961J-951D01*
G03X1429054Y1037878I1352J0D01*
G03X1429406Y1037925I-1J1352D01*
G02X1429651Y1037786I52J-193D01*
G03X1430737Y1036846I1253J350D01*
G01X1430911Y1036823D01*
Y1025894D01*
X1429146Y1024129D01*
Y1019369D01*
X1430076Y1018439D01*
X1447757D01*
X1448271Y1017925D01*
Y1011154D01*
X1447726Y1010609D01*
X1431086D01*
X1431051Y1010622D01*
G03X1430584Y1010709I-468J-1214D01*
G03X1430117Y1010622I1J-1301D01*
G01X1430082Y1010609D01*
X1429879D01*
X1429176Y1009906D01*
Y1004799D01*
X1429966Y1004009D01*
X1447906D01*
X1448379Y1003536D01*
Y996398D01*
X1448110Y996129D01*
X1432256D01*
X1431776Y996609D01*
X1429896D01*
X1429186Y995899D01*
Y991249D01*
X1430866Y989569D01*
X1447726D01*
X1448376Y988919D01*
Y982579D01*
X1447616Y981819D01*
X1434116D01*
X1433466Y982469D01*
X1430725D01*
X1430702Y982474D01*
G03X1430404Y982509I-300J-1266D01*
G03X1430106Y982474I2J-1301D01*
G01X1430083Y982469D01*
X1429696D01*
X1429016Y981789D01*
Y978129D01*
X1431926Y975219D01*
X1443786D01*
X1443992Y975013D01*
Y973213D01*
X1443316Y972537D01*
Y972225D01*
X1443066D01*
X1443022Y972248D01*
G03X1442413Y972400I-610J-1149D01*
G03X1441511Y972037I0J-1302D01*
G02X1440947Y972046I-277J288D01*
G03X1440015Y972440I-933J-907D01*
G03Y969838I0J-1301D01*
G03X1440917Y970201I0J1302D01*
G02X1441481Y970192I277J-288D01*
G03X1442413Y969798I933J907D01*
G03X1443051Y969965I0J1302D01*
G01X1443183Y970039D01*
X1443958Y969264D01*
Y968021D01*
X1443956Y968019D01*
Y967519D01*
X1443706Y967269D01*
X1431161D01*
X1431118Y967290D01*
G03X1430534Y967429I-585J-1162D01*
G03X1429950Y967290I1J-1301D01*
G01X1429907Y967269D01*
X1429666D01*
X1429128Y966731D01*
Y962411D01*
X1430841Y960699D01*
X1447846D01*
X1448381Y960164D01*
Y953764D01*
X1447496Y952879D01*
X1429636D01*
X1429086Y952329D01*
Y946818D01*
X1429966Y945939D01*
X1439796D01*
X1439996Y945739D01*
Y943669D01*
X1439903Y943576D01*
X1436108D01*
X1430588Y938056D01*
X1427275D01*
X1427241Y938068D01*
G03X1426771Y938153I-472J-1267D01*
G03X1426418Y938106I0J-1352D01*
G02X1426173Y938245I-52J193D01*
G03X1425876Y938778I-1253J-349D01*
G02X1425881Y939054I147J135D01*
G03X1424921Y941358I-960J952D01*
G03X1424568Y941311I0J-1352D01*
G02X1424323Y941450I-52J193D01*
G03X1424026Y941982I-1253J-350D01*
G02X1424031Y942259I147J136D01*
G03X1424422Y943210I-961J951D01*
G03X1421718I-1352J0D01*
G03X1422109Y942259I1352J0D01*
G02X1422114Y941982I-142J-141D01*
G03X1421817Y941451I955J-883D01*
G02X1421573Y941311I-193J53D01*
G03X1421221Y941358I-353J-1305D01*
G03X1419869Y940006I0J-1352D01*
G03X1420260Y939055I1352J0D01*
G02X1420264Y938779I-143J-140D01*
G03X1419967Y938246I956J-882D01*
G02X1419722Y938106I-193J53D01*
G03X1419370Y938153I-353J-1305D01*
G03X1419018Y938106I1J-1352D01*
G02X1418773Y938246I-52J193D01*
G03X1418476Y938778I-1253J-350D01*
G02X1418481Y939054I147J135D01*
G03X1416169Y940006I-960J952D01*
G03X1416560Y939055I1352J0D01*
G02X1416564Y938779I-143J-140D01*
G03X1416267Y938246I956J-882D01*
G02X1416022Y938106I-193J53D01*
G03X1415670Y938153I-353J-1305D01*
G03X1415318Y938106I1J-1352D01*
G02X1415073Y938246I-52J193D01*
G03X1414776Y938778I-1253J-350D01*
G02X1414781Y939054I147J135D01*
G03X1412469Y940006I-960J952D01*
G03X1412860Y939055I1352J0D01*
G02X1412864Y938779I-143J-140D01*
G03X1412567Y938246I956J-882D01*
G02X1412322Y938107I-192J54D01*
G03X1411971Y938153I-350J-1306D01*
G03X1411618Y938106I0J-1352D01*
G02X1411373Y938245I-52J193D01*
G03X1411076Y938778I-1253J-349D01*
G02X1411081Y939054I147J135D01*
G03X1408769Y940006I-960J952D01*
G03X1409160Y939055I1352J0D01*
G02X1409164Y938779I-143J-140D01*
G03X1408867Y938246I956J-882D01*
G02X1408622Y938106I-193J53D01*
G03X1408270Y938153I-353J-1305D01*
G03X1407918Y938106I1J-1352D01*
G02X1407673Y938246I-52J193D01*
G03X1407376Y938778I-1253J-350D01*
G02X1407381Y939054I147J135D01*
G03X1405069Y940006I-960J952D01*
G03X1405460Y939055I1352J0D01*
G02X1405464Y938779I-143J-140D01*
G03X1405247Y938459I956J-882D01*
G01X1405192Y938345D01*
X1392204D01*
Y939725D01*
G03X1391728Y940513I-890J0D01*
G01X1391620Y940569D01*
Y941612D01*
G03X1391532Y942002I-901J2D01*
G03X1391535Y942097I-1298J89D01*
G03X1390234Y943398I-1301J0D01*
G03X1390018Y943380I0J-1301D01*
G02X1389552Y943774I-66J394D01*
G01Y945515D01*
X1389846Y945809D01*
X1403836D01*
X1404406Y946379D01*
Y951769D01*
X1403506Y952669D01*
X1399786D01*
Y952674D01*
X1397286D01*
Y952669D01*
X1395986D01*
Y952674D01*
X1393486D01*
Y952669D01*
X1391986D01*
Y952674D01*
X1389486D01*
Y952669D01*
X1388186D01*
Y952674D01*
X1385686D01*
Y952669D01*
X1385006D01*
X1384636Y953039D01*
Y960239D01*
X1385016Y960619D01*
X1403856D01*
X1404586Y961349D01*
Y966629D01*
X1403886Y967329D01*
X1390138D01*
X1389628Y967839D01*
Y969507D01*
G02X1390140Y969890I400J-1D01*
G03X1390506Y969838I364J1249D01*
G03X1391420Y970213I0J1301D01*
G02X1391982I281J-284D01*
G03X1392896Y969838I914J926D01*
G03Y972440I0J1301D01*
G03X1391982Y972065I0J-1301D01*
G02X1391420I-281J284D01*
G03X1390506Y972440I-914J-926D01*
G03X1390140Y972388I-2J-1301D01*
G02X1389628Y972771I-112J384D01*
G01Y974791D01*
X1389956Y975119D01*
X1403756D01*
X1404506Y975869D01*
Y981169D01*
X1403966Y981709D01*
X1385076D01*
X1384646Y982139D01*
Y988929D01*
X1385216Y989499D01*
X1403816D01*
X1404616Y990299D01*
Y995469D01*
X1404006Y996079D01*
X1385206D01*
X1384686Y996599D01*
Y1003099D01*
X1385406Y1003819D01*
X1403516D01*
X1404646Y1004949D01*
Y1009769D01*
X1403866Y1010549D01*
X1393436D01*
X1392955Y1011030D01*
Y1012877D01*
G02X1393440Y1013268I400J0D01*
G03X1393716Y1013238I278J1271D01*
G03Y1015840I0J1301D01*
G03X1393440Y1015810I2J-1301D01*
G02X1392955Y1016201I-85J391D01*
G01Y1017555D01*
X1392962Y1017563D01*
Y1017825D01*
X1393306Y1018169D01*
X1403896D01*
X1404636Y1018909D01*
Y1024089D01*
X1403636Y1025089D01*
X1401766D01*
X1400934Y1025921D01*
Y1029516D01*
X1398972Y1031478D01*
X1398128Y1032323D01*
Y1036627D01*
X1399183Y1037682D01*
X1402227D01*
X1402556Y1038011D01*
X1402676Y1037965D01*
G03X1403154Y1037878I477J1265D01*
G03X1404506Y1039230I0J1352D01*
G03X1404419Y1039708I-1352J1D01*
G01X1404373Y1039828D01*
X1405166Y1040621D01*
X1405393D01*
X1406598Y1041826D01*
Y1043598D01*
X1407404Y1044404D01*
X1407435Y1044419D01*
G03X1408073Y1045057I-582J1220D01*
G01X1408088Y1045088D01*
X1409650Y1046650D01*
Y1047877D01*
G03X1410055Y1048842I-947J965D01*
G03X1410036Y1049065I-1352J-3D01*
G01X1410020Y1049167D01*
X1411421Y1050568D01*
Y1051010D01*
G03X1411906Y1052047I-866J1037D01*
G03X1411514Y1052999I-1352J0D01*
G02X1411509Y1053275I142J141D01*
G03X1411854Y1054157I-955J882D01*
G03X1411421Y1055126I-1301J0D01*
G01Y1057418D01*
G03X1411906Y1058455I-866J1037D01*
G03X1411514Y1059407I-1352J0D01*
G02X1411509Y1059683I142J141D01*
G03X1411854Y1060565I-955J882D01*
G03X1411421Y1061534I-1301J0D01*
G01Y1063827D01*
G03X1411906Y1064864I-866J1037D01*
G03X1411514Y1065816I-1352J0D01*
G02X1411509Y1066092I142J141D01*
G03X1411854Y1066974I-955J882D01*
G03X1411421Y1067943I-1301J0D01*
G01Y1070236D01*
G03X1411906Y1071273I-866J1037D01*
G03X1411514Y1072225I-1352J0D01*
G02X1411509Y1072501I142J141D01*
G03X1411854Y1073383I-955J882D01*
G03X1411421Y1074352I-1301J0D01*
G01Y1076644D01*
G03X1411906Y1077681I-866J1037D01*
G03X1411514Y1078633I-1352J0D01*
G02X1411509Y1078909I142J141D01*
G03X1411854Y1079791I-955J882D01*
G03X1411421Y1080760I-1301J0D01*
G01Y1083053D01*
G03X1411906Y1084090I-866J1037D01*
G03X1411514Y1085042I-1352J0D01*
G02X1411509Y1085318I142J141D01*
G03X1411854Y1086200I-955J882D01*
G03X1411421Y1087169I-1301J0D01*
G01Y1087572D01*
X1410513Y1088480D01*
G02X1410741Y1089159I283J283D01*
G03X1411906Y1090498I-187J1339D01*
G03X1411514Y1091450I-1352J0D01*
G02X1411509Y1091726I142J141D01*
G03X1411854Y1092608I-955J882D01*
G03X1410553Y1093909I-1301J0D01*
G03X1410257Y1093875I-1J-1301D01*
G02X1410017Y1094022I-46J195D01*
G03X1409900Y1094332I-1314J-319D01*
G01X1409877Y1094375D01*
Y1095251D01*
X1409894Y1095289D01*
G03X1410004Y1095813I-1191J524D01*
G03X1409894Y1096337I-1301J0D01*
G01X1409877Y1096375D01*
Y1096463D01*
X1409736Y1096604D01*
G03X1409494Y1096846I-1033J-791D01*
G01X1409198Y1097142D01*
X1408482D01*
X1408425Y1097085D01*
X1408373Y1097071D01*
G03X1407570Y1096453I329J-1259D01*
G01X1407513Y1096351D01*
X1406259D01*
X1406105Y1096505D01*
X1406093Y1096523D01*
G03X1405713Y1096903I-1090J-710D01*
G01X1405695Y1096915D01*
X1404272Y1098338D01*
X1404331Y1098465D01*
G03X1404454Y1099017I-1177J552D01*
G03X1404111Y1099897I-1300J0D01*
G01Y1101288D01*
X1400601Y1104798D01*
X1400653Y1104922D01*
G03X1400754Y1105426I-1200J503D01*
G03X1400494Y1106206I-1300J0D01*
G01Y1108860D01*
G03X1400806Y1109724I-1040J864D01*
G03X1400534Y1110537I-1351J0D01*
G01X1400494Y1110590D01*
Y1111051D01*
X1400529Y1111102D01*
G03X1400754Y1111834I-1076J731D01*
G03X1400494Y1112614I-1300J0D01*
G01Y1114099D01*
X1400177Y1114416D01*
G02X1400230Y1115026I283J283D01*
G03X1400806Y1116133I-776J1107D01*
G03X1400414Y1117085I-1352J0D01*
G02X1400409Y1117361I142J141D01*
G03X1400754Y1118243I-955J882D01*
G03X1398152I-1301J0D01*
G03X1398497Y1117360I1301J-1D01*
G02X1398493Y1117084I-147J-136D01*
G03X1398140Y1116453I961J-952D01*
G02X1397901Y1116306I-194J48D01*
G03X1397604Y1116340I-296J-1267D01*
G03X1396795Y1116058I0J-1301D01*
G01X1394918D01*
X1394729Y1116247D01*
Y1117226D01*
X1393281Y1118674D01*
X1393266Y1118713D01*
G03X1392523Y1119456I-1213J-470D01*
G01X1392484Y1119471D01*
X1391269Y1120686D01*
X1391342Y1120818D01*
G03X1391504Y1121447I-1140J629D01*
G03X1391111Y1122379I-1302J0D01*
G01Y1124744D01*
G03X1391555Y1125746I-909J1002D01*
G03X1391168Y1126693I-1352J0D01*
G01X1391111Y1126751D01*
Y1126920D01*
X1391163Y1126977D01*
G03X1391505Y1127856I-959J879D01*
G03X1391111Y1128789I-1302J0D01*
G01Y1131152D01*
G03X1391555Y1132154I-909J1002D01*
G03X1391497Y1132547I-1352J1D01*
G01X1391488Y1132575D01*
Y1134054D01*
X1391490Y1134069D01*
G03X1391505Y1134264I-1286J197D01*
G03X1391490Y1134459I-1301J-2D01*
G01X1391488Y1134474D01*
Y1134635D01*
X1391435Y1134688D01*
X1391419Y1134728D01*
G03X1390668Y1135479I-1215J-464D01*
G01X1390628Y1135495D01*
X1389418Y1136705D01*
X1389491Y1136837D01*
G03X1389610Y1137129I-1136J633D01*
G02X1390049Y1137421I386J-104D01*
G03X1391018Y1137748I154J1142D01*
G03X1391356Y1138603I-814J816D01*
G03X1391296Y1138753I-203J6D01*
G03X1391009I-144J-144D01*
G03X1390954Y1138649I144J-143D01*
G01Y1138525D01*
G02X1390734Y1138032I-751J39D01*
G02X1389672I-531J531D01*
G02X1389452Y1138559I532J532D01*
G01Y1138646D01*
G03X1389397Y1138749I-198J-40D01*
G03X1389284Y1138806I-143J-144D01*
G01X1389114Y1138832D01*
Y1140369D01*
X1385719Y1143764D01*
X1320156D01*
X1317628Y1146291D01*
Y1191904D01*
X1250800Y1258732D01*
Y1301422D01*
X1253986Y1304608D01*
G37*
G36*
G01X1302816Y1313908D02*
X1282860D01*
X1279277Y1310325D01*
X1250736D01*
X1249816Y1311245D01*
Y1315908D01*
Y1324405D01*
Y1327664D01*
X1250207Y1328055D01*
X1272177D01*
X1274786Y1325446D01*
X1279424Y1320808D01*
X1302616D01*
X1303816Y1319608D01*
Y1314908D01*
X1302816Y1313908D01*
G37*
G36*
G01X1453681Y1443346D02*
G02X1453823Y1443404I141J-142D01*
G01X1507658D01*
X1509607Y1441455D01*
Y1433315D01*
X1504387Y1428095D01*
Y1421705D01*
X1506237Y1419855D01*
X1534843D01*
X1535000Y1420012D01*
X1567340D01*
X1576560Y1410792D01*
Y1307242D01*
X1574713Y1305395D01*
X1509657D01*
X1508968Y1306084D01*
Y1312555D01*
X1510204Y1313790D01*
X1528295D01*
X1529578Y1315073D01*
Y1320669D01*
X1528364Y1321882D01*
X1502136D01*
X1497814Y1317561D01*
Y1300823D01*
X1496205Y1299214D01*
X1469466D01*
X1466316Y1296064D01*
Y1288408D01*
X1463816Y1285908D01*
X1347733D01*
X1342733Y1290908D01*
X1337316D01*
X1336316Y1291908D01*
Y1297408D01*
X1334816Y1298908D01*
X1317316D01*
X1313316Y1302908D01*
Y1309037D01*
X1308445Y1313908D01*
X1305818D01*
X1304816Y1314910D01*
Y1320336D01*
X1303244Y1321908D01*
X1281637D01*
X1271340Y1332205D01*
X1251466D01*
X1249816Y1333855D01*
Y1347408D01*
X1251215Y1348807D01*
X1282091D01*
X1283783Y1347115D01*
X1283920D01*
Y1347114D01*
X1290146D01*
Y1350038D01*
X1288908Y1351276D01*
X1287120D01*
X1286794Y1351602D01*
X1286778D01*
X1286638Y1351742D01*
X1284437D01*
Y1352612D01*
X1286618D01*
X1286794Y1352788D01*
Y1353314D01*
X1286802Y1353334D01*
Y1356652D01*
X1286794Y1356672D01*
Y1356982D01*
X1286788D01*
X1286688Y1357082D01*
X1283378D01*
X1283288Y1357172D01*
Y1357822D01*
X1283348Y1357882D01*
X1286698D01*
X1286794Y1357978D01*
Y1358314D01*
X1286802Y1358334D01*
Y1359068D01*
X1286861Y1359210D01*
X1286943Y1359292D01*
X1287056Y1359338D01*
X1287123Y1359319D01*
G03X1287823Y1359218I704J2401D01*
G03X1288597Y1359341I-1J2502D01*
G01X1288628Y1359351D01*
X1293719D01*
X1293861Y1359292D01*
X1294085Y1359068D01*
Y1351276D01*
X1294048Y1351239D01*
Y1350302D01*
X1294480Y1349870D01*
X1303612D01*
Y1349912D01*
X1308279D01*
X1308290Y1349902D01*
X1308297Y1349909D01*
X1308989D01*
X1309440Y1349458D01*
Y1326798D01*
X1310229Y1326009D01*
X1314219D01*
X1315911Y1324317D01*
X1316048D01*
Y1324316D01*
X1321859D01*
X1322160Y1324617D01*
Y1327132D01*
X1321050Y1328242D01*
X1319128D01*
X1318802Y1328568D01*
X1318786D01*
X1318646Y1328708D01*
X1316390D01*
Y1329578D01*
X1318626D01*
X1318802Y1329754D01*
Y1330280D01*
X1318810Y1330300D01*
Y1333618D01*
X1318802Y1333638D01*
Y1333948D01*
X1318796D01*
X1318696Y1334048D01*
X1315386D01*
X1315296Y1334138D01*
Y1334788D01*
X1315356Y1334848D01*
X1318706D01*
X1318802Y1334944D01*
Y1335280D01*
X1318810Y1335300D01*
Y1336034D01*
X1318869Y1336176D01*
X1318951Y1336258D01*
X1319064Y1336304D01*
X1319131Y1336285D01*
G03X1319831Y1336184I704J2401D01*
G03X1320605Y1336307I-1J2502D01*
G01X1320636Y1336317D01*
X1325727D01*
X1325869Y1336258D01*
X1326093Y1336034D01*
Y1328242D01*
X1326056Y1328205D01*
Y1327268D01*
X1326252Y1327072D01*
X1335740D01*
Y1327114D01*
X1340407D01*
X1340418Y1327104D01*
X1340425Y1327111D01*
X1341117D01*
X1341568Y1326660D01*
Y1313187D01*
X1342172Y1312583D01*
X1346347D01*
X1348039Y1310891D01*
X1348176D01*
Y1310890D01*
X1354282D01*
Y1313646D01*
X1354306D01*
Y1313676D01*
X1353166Y1314816D01*
X1350930D01*
Y1315118D01*
X1350916D01*
X1350706Y1315328D01*
X1348520D01*
Y1316138D01*
X1350680D01*
X1350930Y1316388D01*
Y1316854D01*
X1350938Y1316874D01*
Y1320192D01*
X1350930Y1320212D01*
Y1320538D01*
X1350916D01*
X1350816Y1320638D01*
X1347556D01*
X1347406Y1320788D01*
Y1321358D01*
X1347476Y1321428D01*
X1350710D01*
X1350930Y1321648D01*
Y1321854D01*
X1350938Y1321874D01*
Y1322608D01*
X1350997Y1322750D01*
X1351079Y1322832D01*
X1351192Y1322878D01*
X1351259Y1322859D01*
G03X1351959Y1322758I704J2401D01*
G03X1352733Y1322881I-1J2502D01*
G01X1352764Y1322891D01*
X1357855D01*
X1357997Y1322832D01*
X1358221Y1322608D01*
Y1313973D01*
X1358548Y1313646D01*
X1367868D01*
Y1313688D01*
X1372535D01*
X1372546Y1313678D01*
X1372553Y1313685D01*
X1373696D01*
X1374798Y1312583D01*
X1378475D01*
X1380167Y1310891D01*
X1380304D01*
Y1310890D01*
X1386410D01*
X1386450Y1310930D01*
Y1313572D01*
X1385206Y1314816D01*
X1383058D01*
Y1315138D01*
X1382886Y1315310D01*
Y1315318D01*
X1381766D01*
X1381756Y1315308D01*
X1380370D01*
Y1316178D01*
X1382928D01*
X1383058Y1316308D01*
Y1316854D01*
X1383066Y1316874D01*
Y1320192D01*
X1383058Y1320212D01*
Y1320418D01*
X1383056D01*
X1382876Y1320598D01*
X1379596D01*
X1379496Y1320698D01*
Y1321358D01*
X1379606Y1321468D01*
X1382876D01*
X1383058Y1321650D01*
Y1321854D01*
X1383066Y1321874D01*
Y1322608D01*
X1383125Y1322750D01*
X1383207Y1322832D01*
X1383320Y1322878D01*
X1383387Y1322859D01*
G03X1384087Y1322758I704J2401D01*
G03X1384861Y1322881I-1J2502D01*
G01X1384892Y1322891D01*
X1389983D01*
X1390125Y1322832D01*
X1390349Y1322608D01*
Y1313995D01*
X1390698Y1313646D01*
X1399996D01*
Y1313688D01*
X1404663D01*
X1404674Y1313678D01*
X1404681Y1313685D01*
X1405824D01*
X1406926Y1312583D01*
X1410603D01*
X1412295Y1310891D01*
X1412432D01*
Y1310890D01*
X1418538D01*
Y1312086D01*
X1418536Y1312088D01*
Y1314006D01*
X1417726Y1314816D01*
X1415186D01*
Y1315138D01*
X1415176D01*
X1415046Y1315268D01*
X1412720D01*
Y1316158D01*
X1415026D01*
X1415186Y1316318D01*
Y1316854D01*
X1415194Y1316874D01*
Y1320192D01*
X1415186Y1320212D01*
Y1320368D01*
X1414936Y1320618D01*
X1411766D01*
X1411656Y1320728D01*
Y1321268D01*
X1411846Y1321458D01*
X1415066D01*
X1415186Y1321578D01*
Y1321854D01*
X1415194Y1321874D01*
Y1322608D01*
X1415253Y1322750D01*
X1415335Y1322832D01*
X1415447Y1322878D01*
X1415493Y1322865D01*
G03X1415751Y1322802I722J2395D01*
G03X1416206Y1322758I467J2458D01*
G01X1416231D01*
G03X1416990Y1322881I-16J2502D01*
G01X1417020Y1322891D01*
X1422111D01*
X1422253Y1322832D01*
X1422477Y1322608D01*
Y1314137D01*
X1422968Y1313646D01*
X1432124D01*
Y1313688D01*
X1436791D01*
X1436802Y1313678D01*
X1436809Y1313685D01*
X1437952D01*
X1439054Y1312583D01*
X1442731D01*
X1444423Y1310891D01*
X1444560D01*
Y1310890D01*
X1450666D01*
Y1313608D01*
X1449466Y1314808D01*
Y1314816D01*
X1447314D01*
Y1315148D01*
X1447296D01*
X1447146Y1315298D01*
X1444930D01*
Y1316158D01*
X1447164D01*
X1447314Y1316308D01*
Y1316854D01*
X1447322Y1316874D01*
Y1320192D01*
X1447314Y1320212D01*
Y1320368D01*
X1447186Y1320496D01*
Y1320508D01*
X1447086Y1320608D01*
X1443906D01*
X1443796Y1320718D01*
Y1321248D01*
X1444016Y1321468D01*
X1447164D01*
X1447314Y1321618D01*
Y1321854D01*
X1447322Y1321874D01*
Y1322608D01*
X1447381Y1322750D01*
X1447463Y1322832D01*
X1447575Y1322878D01*
X1447621Y1322865D01*
G03X1447879Y1322802I722J2395D01*
G03X1448334Y1322758I467J2458D01*
G01X1448359D01*
G03X1449118Y1322881I-16J2502D01*
G01X1449148Y1322891D01*
X1454239D01*
X1454381Y1322832D01*
X1454605Y1322608D01*
Y1313969D01*
X1454928Y1313646D01*
X1464252D01*
Y1313688D01*
X1468919D01*
X1468930Y1313678D01*
X1468937Y1313685D01*
X1470080D01*
X1471242Y1314847D01*
Y1325539D01*
X1471712Y1326009D01*
X1474859D01*
X1476551Y1324317D01*
X1476688D01*
Y1324316D01*
X1482794D01*
Y1327072D01*
X1482826D01*
Y1327612D01*
X1482196Y1328242D01*
X1479442D01*
Y1328598D01*
X1479436D01*
X1479336Y1328698D01*
X1477030D01*
Y1329558D01*
X1479336D01*
X1479442Y1329664D01*
Y1330280D01*
X1479450Y1330300D01*
Y1333618D01*
X1479442Y1333639D01*
Y1333918D01*
X1479316Y1334044D01*
Y1334058D01*
X1478236D01*
X1478226Y1334048D01*
X1475966D01*
X1475886Y1334128D01*
Y1334778D01*
X1476016Y1334908D01*
X1479336D01*
X1479442Y1335014D01*
Y1335280D01*
X1479450Y1335300D01*
Y1336034D01*
X1479509Y1336176D01*
X1479591Y1336258D01*
X1479703Y1336304D01*
X1479749Y1336291D01*
G03X1480007Y1336228I722J2395D01*
G03X1480462Y1336184I467J2458D01*
G01X1480487D01*
G03X1481246Y1336307I-16J2502D01*
G01X1481276Y1336317D01*
X1486367D01*
X1486509Y1336258D01*
X1486733Y1336034D01*
Y1328298D01*
X1486726Y1328291D01*
Y1327328D01*
X1486982Y1327072D01*
X1496380D01*
Y1327114D01*
X1502538D01*
X1503568Y1328144D01*
Y1348546D01*
X1503829Y1348807D01*
X1506987D01*
X1508679Y1347115D01*
X1508816D01*
Y1347114D01*
X1514922D01*
Y1349572D01*
X1513454Y1351040D01*
X1511570D01*
X1511326Y1351284D01*
Y1351298D01*
X1511136Y1351488D01*
X1509210D01*
Y1352388D01*
X1510196D01*
X1510206Y1352378D01*
X1511340D01*
X1511570Y1352608D01*
Y1353078D01*
X1511578Y1353098D01*
Y1356416D01*
X1511570Y1356437D01*
Y1356598D01*
X1511446Y1356722D01*
Y1356728D01*
X1511396Y1356778D01*
X1508106D01*
X1508026Y1356858D01*
Y1357578D01*
X1508156Y1357708D01*
X1511430D01*
X1511570Y1357848D01*
Y1358078D01*
X1511578Y1358098D01*
Y1358832D01*
X1511637Y1358974D01*
X1511719Y1359056D01*
X1511831Y1359102D01*
X1511877Y1359089D01*
G03X1512135Y1359026I722J2395D01*
G03X1512590Y1358982I467J2458D01*
G01X1512615D01*
G03X1513374Y1359105I-16J2502D01*
G01X1513404Y1359115D01*
X1518495D01*
X1518637Y1359056D01*
X1518861Y1358832D01*
Y1351058D01*
X1518846Y1351043D01*
X1518856Y1351033D01*
Y1350228D01*
X1519214Y1349870D01*
X1528508D01*
Y1349912D01*
X1544580D01*
X1545390Y1350722D01*
Y1377872D01*
X1543470Y1379792D01*
X1542084D01*
X1541927Y1379635D01*
X1491383D01*
X1491130Y1379382D01*
X1491129D01*
X1490164Y1378417D01*
G02X1490023Y1378359I-141J142D01*
G01X1475403D01*
G02X1475262Y1378417I0J200D01*
G01X1475035Y1378644D01*
G02X1474977Y1378785I142J141D01*
G01Y1416224D01*
X1483421D01*
G03X1483563Y1416283I0J200D01*
G01X1483630Y1416350D01*
G02X1483771Y1416408I141J-142D01*
G01X1486603D01*
G03X1486745Y1416467I0J200D01*
G01X1488057Y1417779D01*
G03X1488116Y1417921I-141J142D01*
G01Y1430667D01*
G03X1488057Y1430809I-200J0D01*
G01X1480483Y1438383D01*
G03X1480341Y1438442I-142J-141D01*
G01X1453342D01*
G02X1453201Y1438500I0J200D01*
G01X1453147Y1438554D01*
X1453057Y1438591D01*
Y1442639D01*
G02X1453115Y1442780I200J0D01*
G01X1453681Y1443346D01*
G37*
G36*
G01X1261970Y1575686D02*
G03I-720J0D01*
G37*
G36*
G01X1257014D02*
G03I-720J0D01*
G37*
G36*
G01X1261970Y1580678D02*
G03I-720J0D01*
G37*
G36*
G01X1257014D02*
G03I-720J0D01*
G37*
G36*
G01X1255210Y1599884D02*
G03I-720J0D01*
G37*
G36*
G01X1262314D02*
G03I-720J0D01*
G37*
G36*
G01X1261970Y1587598D02*
G03I-720J0D01*
G37*
G36*
G01X1257014D02*
G03I-720J0D01*
G37*
G36*
G01X1261970Y1592590D02*
G03I-720J0D01*
G37*
G36*
G01X1257014D02*
G03I-720J0D01*
G37*
G36*
G01X1255210Y1611796D02*
G03I-720J0D01*
G37*
G36*
G01Y1604876D02*
G03I-720J0D01*
G37*
G36*
G01Y1616788D02*
G03I-720J0D01*
G37*
G36*
G01X1262314D02*
G03I-720J0D01*
G37*
G36*
G01Y1611796D02*
G03I-720J0D01*
G37*
G36*
G01Y1604876D02*
G03I-720J0D01*
G37*
G36*
G01X1271500Y66862D02*
X1286100D01*
X1287276Y65686D01*
Y51441D01*
X1286887Y51052D01*
X1286886Y51051D01*
G03X1286870Y51035I841J-857D01*
G01X1286768Y50934D01*
X1270989D01*
X1270887Y51035D01*
G03X1270871Y51051I-857J-841D01*
G01X1270870Y51052D01*
X1270160Y51762D01*
Y65522D01*
X1271500Y66862D01*
G37*
G36*
G01X1293255Y146067D02*
X1294411D01*
G02X1294780Y145514I0J-400D01*
G01X1293790Y143124D01*
X1291014Y140348D01*
G03X1290822Y139884I465J-464D01*
G01Y139096D01*
G03X1289978Y137819I656J-1351D01*
G02X1289593Y137438I-400J19D01*
G03X1288995Y137178I31J-890D01*
G01X1288250Y136434D01*
X1288418Y136267D01*
X1287694Y135541D01*
X1287693Y135542D01*
X1286955Y134804D01*
X1286788Y134972D01*
X1286044Y134226D01*
G03X1286049Y132963I630J-629D01*
G01X1286230Y132782D01*
X1286040Y132592D01*
X1285971Y132583D01*
G03X1284665Y131316I179J-1491D01*
G01X1284655Y131251D01*
X1284467Y131063D01*
X1284311Y131219D01*
G03X1283048Y131214I-629J-630D01*
G01X1282216Y130382D01*
G03X1282211Y129119I625J-634D01*
G01X1282449Y128881D01*
X1281471Y127903D01*
X1281343Y127967D01*
G03X1280766Y127872I-222J-450D01*
G01X1278786Y125892D01*
G03Y125183I355J-354D01*
G01X1280564Y123405D01*
Y123233D01*
X1279180Y121850D01*
X1277931Y123099D01*
G03X1277489Y123238I-354J-355D01*
G01X1277387Y123220D01*
X1274305Y126302D01*
G02X1274447Y126644I142J142D01*
G01X1274738D01*
G03X1275273Y126865I1J756D01*
G01X1276188Y127781D01*
X1276947Y127022D01*
G03X1277656I354J355D01*
G01X1279636Y129002D01*
G03Y129711I-355J355D01*
G01X1278641Y130706D01*
X1279816Y131880D01*
X1279937Y131834D01*
G03X1280889Y132041I318J831D01*
G01X1281721Y132873D01*
G03X1281986Y133474I-624J634D01*
G01X1281989Y133553D01*
X1282378Y133942D01*
X1282482Y133923D01*
G03X1282764Y133896I284J1475D01*
G03X1284266Y135398I0J1502D01*
G03X1284239Y135680I-1502J-2D01*
G01X1284220Y135784D01*
X1287295Y138859D01*
X1287374Y138862D01*
G03X1287884Y139083I-25J756D01*
G01X1291101Y142300D01*
G03X1291322Y142835I-535J534D01*
G03X1291259Y143138I-756J1D01*
G01X1291242Y143176D01*
Y144055D01*
X1293255Y146067D01*
G37*
G36*
G01X1278038Y867031D02*
X1277638Y867174D01*
Y867924D01*
X1278038Y868067D01*
X1278238D01*
Y867031D01*
X1278038D01*
G37*
G36*
G01X1280438D02*
X1280038Y867174D01*
Y867924D01*
X1280438Y868067D01*
X1280638D01*
Y867031D01*
X1280438D01*
G37*
G36*
G01X1280838Y864541D02*
X1281238Y864399D01*
Y863649D01*
X1280838Y863507D01*
X1280638D01*
Y864541D01*
X1280838D01*
G37*
G36*
G01Y866891D02*
X1281238Y866749D01*
Y865999D01*
X1280838Y865857D01*
X1280638D01*
Y866891D01*
X1280838D01*
G37*
G36*
G01X1280438Y864681D02*
X1280038Y864824D01*
Y865574D01*
X1280438Y865717D01*
X1280638D01*
Y864681D01*
X1280438D01*
G37*
G36*
G01X1279238Y867031D02*
X1278838Y867174D01*
Y867924D01*
X1279238Y868067D01*
X1279438D01*
Y867031D01*
X1279238D01*
G37*
G36*
G01X1279638Y864541D02*
X1280038Y864399D01*
Y863649D01*
X1279638Y863507D01*
X1279438D01*
Y864541D01*
X1279638D01*
G37*
G36*
G01Y866891D02*
X1280038Y866749D01*
Y865999D01*
X1279638Y865857D01*
X1279438D01*
Y866891D01*
X1279638D01*
G37*
G36*
G01X1281638Y867031D02*
X1281238Y867174D01*
Y867924D01*
X1281638Y868067D01*
X1281838D01*
Y867031D01*
X1281638D01*
G37*
G36*
G01Y864681D02*
X1281238Y864824D01*
Y865574D01*
X1281638Y865717D01*
X1281838D01*
Y864681D01*
X1281638D01*
G37*
G36*
G01Y859981D02*
X1281238Y860124D01*
Y860874D01*
X1281638Y861017D01*
X1281838D01*
Y859981D01*
X1281638D01*
G37*
G36*
G01Y862331D02*
X1281238Y862474D01*
Y863224D01*
X1281638Y863367D01*
X1281838D01*
Y862331D01*
X1281638D01*
G37*
G36*
G01X1281905Y884812D02*
X1282087Y884428D01*
X1281557Y883898D01*
X1281173Y884080D01*
X1281032Y884221D01*
X1281764Y884953D01*
X1281905Y884812D01*
G37*
G36*
G01X1280060Y883532D02*
X1279878Y883915D01*
X1280408Y884446D01*
X1280792Y884263D01*
X1280933Y884122D01*
X1280201Y883390D01*
X1280060Y883532D01*
G37*
G36*
G01X1280244Y883150D02*
X1280426Y882766D01*
X1279895Y882236D01*
X1279512Y882418D01*
X1279370Y882559D01*
X1280102Y883291D01*
X1280244Y883150D01*
G37*
G36*
G01X1278038Y869381D02*
X1277638Y869524D01*
Y870274D01*
X1278038Y870417D01*
X1278238D01*
Y869381D01*
X1278038D01*
G37*
G36*
G01Y878781D02*
X1277638Y878924D01*
Y879674D01*
X1278038Y879817D01*
X1278238D01*
Y878781D01*
X1278038D01*
G37*
G36*
G01Y876431D02*
X1277638Y876574D01*
Y877324D01*
X1278038Y877467D01*
X1278238D01*
Y876431D01*
X1278038D01*
G37*
G36*
G01Y874081D02*
X1277638Y874224D01*
Y874974D01*
X1278038Y875117D01*
X1278238D01*
Y874081D01*
X1278038D01*
G37*
G36*
G01Y871731D02*
X1277638Y871874D01*
Y872624D01*
X1278038Y872767D01*
X1278238D01*
Y871731D01*
X1278038D01*
G37*
G36*
G01X1278438Y869241D02*
X1278838Y869099D01*
Y868349D01*
X1278438Y868207D01*
X1278238D01*
Y869241D01*
X1278438D01*
G37*
G36*
G01Y871591D02*
X1278838Y871449D01*
Y870699D01*
X1278438Y870557D01*
X1278238D01*
Y871591D01*
X1278438D01*
G37*
G36*
G01Y878641D02*
X1278838Y878499D01*
Y877749D01*
X1278438Y877607D01*
X1278238D01*
Y878641D01*
X1278438D01*
G37*
G36*
G01Y876291D02*
X1278838Y876149D01*
Y875399D01*
X1278438Y875257D01*
X1278238D01*
Y876291D01*
X1278438D01*
G37*
G36*
G01Y873941D02*
X1278838Y873799D01*
Y873049D01*
X1278438Y872907D01*
X1278238D01*
Y873941D01*
X1278438D01*
G37*
G36*
G01X1281942Y881452D02*
X1282124Y881068D01*
X1281593Y880538D01*
X1281210Y880720D01*
X1281068Y880861D01*
X1281800Y881593D01*
X1281942Y881452D01*
G37*
G36*
G01X1280838Y869241D02*
X1281238Y869099D01*
Y868349D01*
X1280838Y868207D01*
X1280638D01*
Y869241D01*
X1280838D01*
G37*
G36*
G01X1280438Y878781D02*
X1280038Y878924D01*
Y879674D01*
X1280438Y879817D01*
X1280638D01*
Y878781D01*
X1280438D01*
G37*
G36*
G01X1280838Y878641D02*
X1281238Y878499D01*
Y877749D01*
X1280838Y877607D01*
X1280638D01*
Y878641D01*
X1280838D01*
G37*
G36*
G01Y876291D02*
X1281238Y876149D01*
Y875399D01*
X1280838Y875257D01*
X1280638D01*
Y876291D01*
X1280838D01*
G37*
G36*
G01Y873941D02*
X1281238Y873799D01*
Y873049D01*
X1280838Y872907D01*
X1280638D01*
Y873941D01*
X1280838D01*
G37*
G36*
G01X1280438Y876431D02*
X1280038Y876574D01*
Y877324D01*
X1280438Y877467D01*
X1280638D01*
Y876431D01*
X1280438D01*
G37*
G36*
G01Y874081D02*
X1280038Y874224D01*
Y874974D01*
X1280438Y875117D01*
X1280638D01*
Y874081D01*
X1280438D01*
G37*
G36*
G01Y871731D02*
X1280038Y871874D01*
Y872624D01*
X1280438Y872767D01*
X1280638D01*
Y871731D01*
X1280438D01*
G37*
G36*
G01Y869381D02*
X1280038Y869524D01*
Y870274D01*
X1280438Y870417D01*
X1280638D01*
Y869381D01*
X1280438D01*
G37*
G36*
G01X1280838Y871591D02*
X1281238Y871449D01*
Y870699D01*
X1280838Y870557D01*
X1280638D01*
Y871591D01*
X1280838D01*
G37*
G36*
G01X1279638Y869241D02*
X1280038Y869099D01*
Y868349D01*
X1279638Y868207D01*
X1279438D01*
Y869241D01*
X1279638D01*
G37*
G36*
G01Y871591D02*
X1280038Y871449D01*
Y870699D01*
X1279638Y870557D01*
X1279438D01*
Y871591D01*
X1279638D01*
G37*
G36*
G01X1279238Y869381D02*
X1278838Y869524D01*
Y870274D01*
X1279238Y870417D01*
X1279438D01*
Y869381D01*
X1279238D01*
G37*
G36*
G01Y878781D02*
X1278838Y878924D01*
Y879674D01*
X1279238Y879817D01*
X1279438D01*
Y878781D01*
X1279238D01*
G37*
G36*
G01X1279638Y878641D02*
X1280038Y878499D01*
Y877749D01*
X1279638Y877607D01*
X1279438D01*
Y878641D01*
X1279638D01*
G37*
G36*
G01Y876291D02*
X1280038Y876149D01*
Y875399D01*
X1279638Y875257D01*
X1279438D01*
Y876291D01*
X1279638D01*
G37*
G36*
G01Y873941D02*
X1280038Y873799D01*
Y873049D01*
X1279638Y872907D01*
X1279438D01*
Y873941D01*
X1279638D01*
G37*
G36*
G01X1279238Y876431D02*
X1278838Y876574D01*
Y877324D01*
X1279238Y877467D01*
X1279438D01*
Y876431D01*
X1279238D01*
G37*
G36*
G01Y874081D02*
X1278838Y874224D01*
Y874974D01*
X1279238Y875117D01*
X1279438D01*
Y874081D01*
X1279238D01*
G37*
G36*
G01Y871731D02*
X1278838Y871874D01*
Y872624D01*
X1279238Y872767D01*
X1279438D01*
Y871731D01*
X1279238D01*
G37*
G36*
G01X1281093Y882301D02*
X1281275Y881917D01*
X1280744Y881387D01*
X1280361Y881569D01*
X1280219Y881710D01*
X1280951Y882442D01*
X1281093Y882301D01*
G37*
G36*
G01X1280909Y882683D02*
X1280727Y883066D01*
X1281257Y883597D01*
X1281641Y883414D01*
X1281782Y883273D01*
X1281050Y882541D01*
X1280909Y882683D01*
G37*
G36*
G01X1281638Y869381D02*
X1281238Y869524D01*
Y870274D01*
X1281638Y870417D01*
X1281838D01*
Y869381D01*
X1281638D01*
G37*
G36*
G01Y876431D02*
X1281238Y876574D01*
Y877324D01*
X1281638Y877467D01*
X1281838D01*
Y876431D01*
X1281638D01*
G37*
G36*
G01Y874081D02*
X1281238Y874224D01*
Y874974D01*
X1281638Y875117D01*
X1281838D01*
Y874081D01*
X1281638D01*
G37*
G36*
G01Y871731D02*
X1281238Y871874D01*
Y872624D01*
X1281638Y872767D01*
X1281838D01*
Y871731D01*
X1281638D01*
G37*
G36*
G01X1282302Y970578D02*
X1282160Y970178D01*
X1281410D01*
X1281267Y970578D01*
Y970778D01*
X1282302D01*
Y970578D01*
G37*
G36*
G01Y968178D02*
X1282160Y967778D01*
X1281410D01*
X1281267Y968178D01*
Y968378D01*
X1282302D01*
Y968178D01*
G37*
G36*
G01X1280092Y968578D02*
X1280234Y968978D01*
X1280984D01*
X1281127Y968578D01*
Y968378D01*
X1280092D01*
Y968578D01*
G37*
G36*
G01X1282302Y971778D02*
X1282160Y971378D01*
X1281410D01*
X1281267Y971778D01*
Y971978D01*
X1282302D01*
Y971778D01*
G37*
G36*
G01X1280092Y969778D02*
X1280234Y970178D01*
X1280984D01*
X1281127Y969778D01*
Y969578D01*
X1280092D01*
Y969778D01*
G37*
G36*
G01X1282302Y969378D02*
X1282160Y968978D01*
X1281410D01*
X1281267Y969378D01*
Y969578D01*
X1282302D01*
Y969378D01*
G37*
G36*
G01X1282303Y1046584D02*
X1281920Y1046402D01*
X1281389Y1046932D01*
X1281571Y1047316D01*
X1281713Y1047457D01*
X1282445Y1046725D01*
X1282303Y1046584D01*
G37*
G36*
G01X1280986Y1045069D02*
X1281370Y1045251D01*
X1281900Y1044720D01*
X1281718Y1044337D01*
X1281577Y1044195D01*
X1280845Y1044927D01*
X1280986Y1045069D01*
G37*
G36*
G01X1282266Y1043223D02*
X1281882Y1043041D01*
X1281352Y1043571D01*
X1281534Y1043955D01*
X1281676Y1044096D01*
X1282407Y1043365D01*
X1282266Y1043223D01*
G37*
G36*
G01X1278943Y1046547D02*
X1278559Y1046364D01*
X1278029Y1046895D01*
X1278211Y1047278D01*
X1278352Y1047420D01*
X1279084Y1046688D01*
X1278943Y1046547D01*
G37*
G36*
G01X1279324Y1046730D02*
X1279708Y1046912D01*
X1280238Y1046382D01*
X1280056Y1045998D01*
X1279915Y1045857D01*
X1279183Y1046589D01*
X1279324Y1046730D01*
G37*
G36*
G01X1280604Y1044885D02*
X1280221Y1044703D01*
X1279690Y1045233D01*
X1279872Y1045617D01*
X1280014Y1045758D01*
X1280746Y1045026D01*
X1280604Y1044885D01*
G37*
G36*
G01X1280174Y1047580D02*
X1280558Y1047762D01*
X1281088Y1047232D01*
X1280906Y1046848D01*
X1280764Y1046707D01*
X1280033Y1047438D01*
X1280174Y1047580D01*
G37*
G36*
G01X1281454Y1045734D02*
X1281070Y1045552D01*
X1280540Y1046083D01*
X1280722Y1046466D01*
X1280863Y1046608D01*
X1281595Y1045876D01*
X1281454Y1045734D01*
G37*
G36*
G01X1278093Y1045697D02*
X1277710Y1045515D01*
X1277179Y1046045D01*
X1277361Y1046429D01*
X1277503Y1046570D01*
X1278235Y1045838D01*
X1278093Y1045697D01*
G37*
G36*
G01X1276813Y1047543D02*
X1277197Y1047725D01*
X1277727Y1047194D01*
X1277545Y1046811D01*
X1277404Y1046669D01*
X1276672Y1047401D01*
X1276813Y1047543D01*
G37*
G36*
G01X1281417Y1042374D02*
X1281033Y1042192D01*
X1280503Y1042722D01*
X1280685Y1043105D01*
X1280826Y1043247D01*
X1281558Y1042515D01*
X1281417Y1042374D01*
G37*
G36*
G01X1279755Y1044035D02*
X1279371Y1043853D01*
X1278841Y1044384D01*
X1279023Y1044767D01*
X1279164Y1044909D01*
X1279896Y1044177D01*
X1279755Y1044035D01*
G37*
G36*
G01X1280137Y1044219D02*
X1280520Y1044401D01*
X1281051Y1043871D01*
X1280869Y1043487D01*
X1280727Y1043346D01*
X1279995Y1044078D01*
X1280137Y1044219D01*
G37*
G36*
G01X1278475Y1045881D02*
X1278859Y1046063D01*
X1279389Y1045533D01*
X1279207Y1045149D01*
X1279065Y1045008D01*
X1278334Y1045739D01*
X1278475Y1045881D01*
G37*
G36*
G01X1281080Y1061958D02*
X1281463Y1062140D01*
X1281994Y1061610D01*
X1281811Y1061226D01*
X1281670Y1061085D01*
X1280938Y1061817D01*
X1281080Y1061958D01*
G37*
G36*
G01X1280698Y1061774D02*
X1280314Y1061592D01*
X1279784Y1062123D01*
X1279966Y1062506D01*
X1280107Y1062648D01*
X1280839Y1061916D01*
X1280698Y1061774D01*
G37*
G36*
G01X1282323Y1056752D02*
X1281939Y1056570D01*
X1281409Y1057101D01*
X1281591Y1057484D01*
X1281732Y1057626D01*
X1282464Y1056894D01*
X1282323Y1056752D01*
G37*
G36*
G01X1281043Y1058598D02*
X1281426Y1058780D01*
X1281957Y1058250D01*
X1281775Y1057866D01*
X1281633Y1057725D01*
X1280901Y1058457D01*
X1281043Y1058598D01*
G37*
G36*
G01X1280661Y1058414D02*
X1280277Y1058232D01*
X1279747Y1058762D01*
X1279929Y1059146D01*
X1280071Y1059287D01*
X1280802Y1058556D01*
X1280661Y1058414D01*
G37*
G36*
G01X1279381Y1060260D02*
X1279765Y1060442D01*
X1280295Y1059911D01*
X1280113Y1059528D01*
X1279972Y1059386D01*
X1279240Y1060118D01*
X1279381Y1060260D01*
G37*
G36*
G01X1279849Y1060925D02*
X1279465Y1060743D01*
X1278935Y1061274D01*
X1279117Y1061657D01*
X1279258Y1061799D01*
X1279990Y1061067D01*
X1279849Y1060925D01*
G37*
G36*
G01X1280231Y1061109D02*
X1280614Y1061291D01*
X1281145Y1060761D01*
X1280962Y1060377D01*
X1280821Y1060236D01*
X1280089Y1060968D01*
X1280231Y1061109D01*
G37*
G36*
G01X1281511Y1059264D02*
X1281127Y1059082D01*
X1280597Y1059612D01*
X1280779Y1059996D01*
X1280920Y1060137D01*
X1281652Y1059405D01*
X1281511Y1059264D01*
G37*
G36*
G01X1280194Y1057749D02*
X1280577Y1057931D01*
X1281108Y1057401D01*
X1280926Y1057017D01*
X1280784Y1056876D01*
X1280052Y1057608D01*
X1280194Y1057749D01*
G37*
G36*
G01X1281474Y1055903D02*
X1281090Y1055721D01*
X1280560Y1056252D01*
X1280742Y1056635D01*
X1280883Y1056777D01*
X1281615Y1056045D01*
X1281474Y1055903D01*
G37*
G36*
G01X1277700Y1051753D02*
X1278084Y1051935D01*
X1278614Y1051405D01*
X1278432Y1051021D01*
X1278291Y1050879D01*
X1277559Y1051611D01*
X1277700Y1051753D01*
G37*
G36*
G01X1281023Y1048429D02*
X1281407Y1048611D01*
X1281937Y1048081D01*
X1281755Y1047697D01*
X1281614Y1047556D01*
X1280882Y1048288D01*
X1281023Y1048429D01*
G37*
G36*
G01X1278980Y1049907D02*
X1278596Y1049725D01*
X1278066Y1050255D01*
X1278248Y1050639D01*
X1278390Y1050780D01*
X1279121Y1050049D01*
X1278980Y1049907D01*
G37*
G36*
G01X1279362Y1050091D02*
X1279745Y1050273D01*
X1280276Y1049743D01*
X1280094Y1049359D01*
X1279952Y1049218D01*
X1279220Y1049950D01*
X1279362Y1050091D01*
G37*
G36*
G01X1280642Y1048246D02*
X1280258Y1048063D01*
X1279728Y1048594D01*
X1279910Y1048977D01*
X1280051Y1049119D01*
X1280783Y1048387D01*
X1280642Y1048246D01*
G37*
G36*
G01X1277281Y1048208D02*
X1276897Y1048026D01*
X1276367Y1048556D01*
X1276549Y1048940D01*
X1276691Y1049081D01*
X1277422Y1048350D01*
X1277281Y1048208D01*
G37*
G36*
G01X1277663Y1048392D02*
X1278046Y1048574D01*
X1278577Y1048044D01*
X1278395Y1047660D01*
X1278253Y1047519D01*
X1277521Y1048251D01*
X1277663Y1048392D01*
G37*
G36*
G01X1278130Y1049058D02*
X1277747Y1048876D01*
X1277217Y1049406D01*
X1277399Y1049790D01*
X1277540Y1049931D01*
X1278272Y1049199D01*
X1278130Y1049058D01*
G37*
G36*
G01X1278512Y1049242D02*
X1278896Y1049424D01*
X1279426Y1048893D01*
X1279244Y1048510D01*
X1279103Y1048368D01*
X1278371Y1049100D01*
X1278512Y1049242D01*
G37*
G36*
G01X1279792Y1047396D02*
X1279409Y1047214D01*
X1278878Y1047744D01*
X1279060Y1048128D01*
X1279202Y1048269D01*
X1279934Y1047537D01*
X1279792Y1047396D01*
G37*
G36*
G01X1278075Y1079039D02*
X1277655Y1078976D01*
X1277302Y1079638D01*
X1277587Y1079952D01*
X1277764Y1080046D01*
X1278252Y1079133D01*
X1278075Y1079039D01*
G37*
G36*
G01X1281830Y1074979D02*
X1281447Y1074797D01*
X1280916Y1075327D01*
X1281098Y1075711D01*
X1281240Y1075852D01*
X1281972Y1075120D01*
X1281830Y1074979D01*
G37*
G36*
G01X1280550Y1076824D02*
X1280934Y1077006D01*
X1281464Y1076476D01*
X1281282Y1076093D01*
X1281141Y1075951D01*
X1280409Y1076683D01*
X1280550Y1076824D01*
G37*
G36*
G01X1280169Y1076641D02*
X1279785Y1076458D01*
X1279255Y1076989D01*
X1279437Y1077372D01*
X1279578Y1077514D01*
X1280310Y1076782D01*
X1280169Y1076641D01*
G37*
G36*
G01X1278469Y1074941D02*
X1278085Y1074759D01*
X1277555Y1075289D01*
X1277737Y1075673D01*
X1277879Y1075814D01*
X1278611Y1075082D01*
X1278469Y1074941D01*
G37*
G36*
G01X1277189Y1076787D02*
X1277573Y1076969D01*
X1278103Y1076438D01*
X1277921Y1076055D01*
X1277780Y1075913D01*
X1277048Y1076645D01*
X1277189Y1076787D01*
G37*
G36*
G01X1280513Y1073463D02*
X1280896Y1073645D01*
X1281427Y1073115D01*
X1281244Y1072731D01*
X1281103Y1072590D01*
X1280371Y1073322D01*
X1280513Y1073463D01*
G37*
G36*
G01X1280131Y1073279D02*
X1279747Y1073097D01*
X1279217Y1073628D01*
X1279399Y1074011D01*
X1279540Y1074153D01*
X1280272Y1073421D01*
X1280131Y1073279D01*
G37*
G36*
G01X1278851Y1075125D02*
X1279235Y1075307D01*
X1279765Y1074777D01*
X1279583Y1074393D01*
X1279441Y1074252D01*
X1278710Y1074983D01*
X1278851Y1075125D01*
G37*
G36*
G01X1281793Y1071618D02*
X1281409Y1071436D01*
X1280879Y1071966D01*
X1281061Y1072350D01*
X1281202Y1072491D01*
X1281934Y1071759D01*
X1281793Y1071618D01*
G37*
G36*
G01X1275954Y1077905D02*
X1275534Y1077842D01*
X1275181Y1078504D01*
X1275466Y1078818D01*
X1275643Y1078912D01*
X1276131Y1078000D01*
X1275954Y1077905D01*
G37*
G36*
G01X1275265Y1080043D02*
X1275685Y1080106D01*
X1276039Y1079444D01*
X1275753Y1079130D01*
X1275577Y1079036D01*
X1275089Y1079949D01*
X1275265Y1080043D01*
G37*
G36*
G01X1281363Y1074314D02*
X1281747Y1074496D01*
X1282277Y1073965D01*
X1282095Y1073582D01*
X1281954Y1073440D01*
X1281222Y1074172D01*
X1281363Y1074314D01*
G37*
G36*
G01X1280981Y1074130D02*
X1280598Y1073948D01*
X1280067Y1074478D01*
X1280249Y1074862D01*
X1280391Y1075003D01*
X1281123Y1074271D01*
X1280981Y1074130D01*
G37*
G36*
G01X1279320Y1075792D02*
X1278936Y1075609D01*
X1278406Y1076140D01*
X1278588Y1076523D01*
X1278729Y1076665D01*
X1279461Y1075933D01*
X1279320Y1075792D01*
G37*
G36*
G01X1279701Y1075975D02*
X1280085Y1076157D01*
X1280615Y1075627D01*
X1280433Y1075244D01*
X1280292Y1075102D01*
X1279560Y1075834D01*
X1279701Y1075975D01*
G37*
G36*
G01X1277014Y1078472D02*
X1276594Y1078409D01*
X1276241Y1079070D01*
X1276526Y1079385D01*
X1276703Y1079479D01*
X1277190Y1078566D01*
X1277014Y1078472D01*
G37*
G36*
G01X1273787Y1079412D02*
X1273367Y1079349D01*
X1273014Y1080010D01*
X1273299Y1080324D01*
X1273476Y1080419D01*
X1273964Y1079506D01*
X1273787Y1079412D01*
G37*
G36*
G01X1274206Y1079477D02*
X1274626Y1079540D01*
X1274979Y1078878D01*
X1274694Y1078564D01*
X1274517Y1078470D01*
X1274030Y1079382D01*
X1274206Y1079477D01*
G37*
G36*
G01X1274895Y1077339D02*
X1274475Y1077276D01*
X1274121Y1077938D01*
X1274407Y1078252D01*
X1274583Y1078346D01*
X1275071Y1077433D01*
X1274895Y1077339D01*
G37*
G36*
G01X1276340Y1075937D02*
X1276723Y1076119D01*
X1277254Y1075589D01*
X1277072Y1075205D01*
X1276930Y1075064D01*
X1276198Y1075796D01*
X1276340Y1075937D01*
G37*
G36*
G01X1277620Y1074092D02*
X1277236Y1073909D01*
X1276706Y1074440D01*
X1276888Y1074823D01*
X1277029Y1074965D01*
X1277761Y1074233D01*
X1277620Y1074092D01*
G37*
G36*
G01X1278001Y1074275D02*
X1278385Y1074457D01*
X1278915Y1073927D01*
X1278733Y1073544D01*
X1278592Y1073402D01*
X1277860Y1074134D01*
X1278001Y1074275D01*
G37*
G36*
G01X1279281Y1072430D02*
X1278898Y1072248D01*
X1278367Y1072778D01*
X1278549Y1073162D01*
X1278691Y1073303D01*
X1279423Y1072571D01*
X1279281Y1072430D01*
G37*
G36*
G01X1279663Y1072614D02*
X1280047Y1072796D01*
X1280577Y1072265D01*
X1280395Y1071882D01*
X1280254Y1071740D01*
X1279522Y1072472D01*
X1279663Y1072614D01*
G37*
G36*
G01X1280943Y1070768D02*
X1280559Y1070586D01*
X1280029Y1071116D01*
X1280211Y1071500D01*
X1280353Y1071641D01*
X1281084Y1070910D01*
X1280943Y1070768D01*
G37*
G36*
G01X1281325Y1070952D02*
X1281708Y1071134D01*
X1282239Y1070604D01*
X1282057Y1070220D01*
X1281915Y1070079D01*
X1281183Y1070811D01*
X1281325Y1070952D01*
G37*
G36*
G01X1281637Y1094365D02*
X1281217Y1094427D01*
X1281070Y1095162D01*
X1281435Y1095380D01*
X1281631Y1095419D01*
X1281833Y1094404D01*
X1281637Y1094365D01*
G37*
G36*
G01X1281811Y1087464D02*
X1281391Y1087401D01*
X1281037Y1088063D01*
X1281323Y1088377D01*
X1281499Y1088471D01*
X1281987Y1087559D01*
X1281811Y1087464D01*
G37*
G36*
G01X1280703Y1089537D02*
X1280283Y1089474D01*
X1279930Y1090135D01*
X1280215Y1090450D01*
X1280392Y1090544D01*
X1280879Y1089631D01*
X1280703Y1089537D01*
G37*
G36*
G01X1281122Y1089602D02*
X1281542Y1089665D01*
X1281895Y1089003D01*
X1281610Y1088689D01*
X1281433Y1088595D01*
X1280945Y1089508D01*
X1281122Y1089602D01*
G37*
G36*
G01X1279241Y1096142D02*
X1279661Y1096080D01*
X1279808Y1095345D01*
X1279443Y1095127D01*
X1279247Y1095088D01*
X1279045Y1096103D01*
X1279241Y1096142D01*
G37*
G36*
G01X1279281Y1093896D02*
X1278861Y1093958D01*
X1278715Y1094694D01*
X1279079Y1094911D01*
X1279275Y1094950D01*
X1279477Y1093935D01*
X1279281Y1093896D01*
G37*
G36*
G01X1279701Y1093837D02*
X1280121Y1093775D01*
X1280267Y1093040D01*
X1279903Y1092822D01*
X1279707Y1092783D01*
X1279505Y1093798D01*
X1279701Y1093837D01*
G37*
G36*
G01X1280878Y1094071D02*
X1281298Y1094010D01*
X1281444Y1093274D01*
X1281080Y1093056D01*
X1280884Y1093017D01*
X1280682Y1094032D01*
X1280878Y1094071D01*
G37*
G36*
G01X1280458Y1094130D02*
X1280038Y1094192D01*
X1279892Y1094928D01*
X1280256Y1095146D01*
X1280452Y1095185D01*
X1280654Y1094169D01*
X1280458Y1094130D01*
G37*
G36*
G01X1280419Y1096376D02*
X1280839Y1096314D01*
X1280986Y1095579D01*
X1280621Y1095361D01*
X1280425Y1095322D01*
X1280223Y1096337D01*
X1280419Y1096376D01*
G37*
G36*
G01X1281762Y1090103D02*
X1281342Y1090040D01*
X1280988Y1090701D01*
X1281274Y1091016D01*
X1281450Y1091110D01*
X1281938Y1090197D01*
X1281762Y1090103D01*
G37*
G36*
G01X1278103Y1093662D02*
X1277683Y1093724D01*
X1277536Y1094459D01*
X1277901Y1094677D01*
X1278097Y1094716D01*
X1278299Y1093701D01*
X1278103Y1093662D01*
G37*
G36*
G01X1281859Y1084826D02*
X1281439Y1084763D01*
X1281086Y1085424D01*
X1281371Y1085738D01*
X1281547Y1085833D01*
X1282035Y1084920D01*
X1281859Y1084826D01*
G37*
G36*
G01X1278523Y1093603D02*
X1278943Y1093541D01*
X1279089Y1092805D01*
X1278725Y1092588D01*
X1278528Y1092549D01*
X1278326Y1093564D01*
X1278523Y1093603D01*
G37*
G36*
G01X1278562Y1091357D02*
X1278141Y1091419D01*
X1277995Y1092154D01*
X1278360Y1092372D01*
X1278556Y1092411D01*
X1278758Y1091396D01*
X1278562Y1091357D01*
G37*
G36*
G01X1278064Y1095907D02*
X1278484Y1095846D01*
X1278630Y1095110D01*
X1278266Y1094892D01*
X1278070Y1094853D01*
X1277868Y1095868D01*
X1278064Y1095907D01*
G37*
G36*
G01X1280751Y1086898D02*
X1280331Y1086835D01*
X1279978Y1087497D01*
X1280263Y1087811D01*
X1280440Y1087905D01*
X1280928Y1086992D01*
X1280751Y1086898D01*
G37*
G36*
G01X1280062Y1089036D02*
X1280482Y1089099D01*
X1280836Y1088437D01*
X1280550Y1088123D01*
X1280374Y1088029D01*
X1279886Y1088941D01*
X1280062Y1089036D01*
G37*
G36*
G01X1279643Y1088971D02*
X1279223Y1088908D01*
X1278870Y1089569D01*
X1279155Y1089883D01*
X1279332Y1089978D01*
X1279820Y1089065D01*
X1279643Y1088971D01*
G37*
G36*
G01X1281170Y1086963D02*
X1281590Y1087026D01*
X1281943Y1086365D01*
X1281658Y1086050D01*
X1281481Y1085956D01*
X1280994Y1086869D01*
X1281170Y1086963D01*
G37*
G36*
G01X1271737Y1094260D02*
X1271317Y1094322D01*
X1271171Y1095057D01*
X1271535Y1095275D01*
X1271732Y1095314D01*
X1271933Y1094299D01*
X1271737Y1094260D01*
G37*
G36*
G01X1271699Y1096505D02*
X1272119Y1096444D01*
X1272265Y1095708D01*
X1271900Y1095490D01*
X1271704Y1095451D01*
X1271502Y1096467D01*
X1271699Y1096505D01*
G37*
G36*
G01X1272615Y1091896D02*
X1273035Y1091834D01*
X1273182Y1091098D01*
X1272817Y1090881D01*
X1272621Y1090842D01*
X1272419Y1091857D01*
X1272615Y1091896D01*
G37*
G36*
G01X1272157Y1094201D02*
X1272577Y1094139D01*
X1272723Y1093403D01*
X1272359Y1093185D01*
X1272163Y1093146D01*
X1271961Y1094162D01*
X1272157Y1094201D01*
G37*
G36*
G01X1272654Y1089650D02*
X1272234Y1089712D01*
X1272088Y1090448D01*
X1272452Y1090665D01*
X1272648Y1090704D01*
X1272850Y1089689D01*
X1272654Y1089650D01*
G37*
G36*
G01X1272196Y1091955D02*
X1271775Y1092017D01*
X1271629Y1092752D01*
X1271994Y1092970D01*
X1272190Y1093009D01*
X1272392Y1091994D01*
X1272196Y1091955D01*
G37*
G36*
G01X1273643Y1087328D02*
X1273223Y1087266D01*
X1272869Y1087927D01*
X1273155Y1088241D01*
X1273331Y1088336D01*
X1273819Y1087423D01*
X1273643Y1087328D01*
G37*
G36*
G01X1274751Y1085256D02*
X1274331Y1085193D01*
X1273977Y1085855D01*
X1274263Y1086169D01*
X1274439Y1086263D01*
X1274927Y1085350D01*
X1274751Y1085256D01*
G37*
G36*
G01X1274062Y1087394D02*
X1274482Y1087457D01*
X1274835Y1086795D01*
X1274550Y1086481D01*
X1274373Y1086387D01*
X1273885Y1087299D01*
X1274062Y1087394D01*
G37*
G36*
G01X1276967Y1081112D02*
X1276547Y1081049D01*
X1276194Y1081710D01*
X1276479Y1082024D01*
X1276656Y1082119D01*
X1277144Y1081206D01*
X1276967Y1081112D01*
G37*
G36*
G01X1276278Y1083249D02*
X1276698Y1083312D01*
X1277052Y1082650D01*
X1276766Y1082336D01*
X1276590Y1082242D01*
X1276102Y1083155D01*
X1276278Y1083249D01*
G37*
G36*
G01X1275170Y1085321D02*
X1275590Y1085384D01*
X1275943Y1084723D01*
X1275658Y1084409D01*
X1275481Y1084314D01*
X1274993Y1085227D01*
X1275170Y1085321D01*
G37*
G36*
G01X1275859Y1083184D02*
X1275439Y1083121D01*
X1275086Y1083782D01*
X1275371Y1084097D01*
X1275548Y1084191D01*
X1276035Y1083278D01*
X1275859Y1083184D01*
G37*
G36*
G01X1277386Y1081177D02*
X1277806Y1081240D01*
X1278160Y1080578D01*
X1277874Y1080264D01*
X1277698Y1080170D01*
X1277210Y1081082D01*
X1277386Y1081177D01*
G37*
G36*
G01X1272631Y1084123D02*
X1272211Y1084060D01*
X1271858Y1084721D01*
X1272143Y1085036D01*
X1272320Y1085130D01*
X1272807Y1084217D01*
X1272631Y1084123D01*
G37*
G36*
G01X1273739Y1082050D02*
X1273319Y1081988D01*
X1272965Y1082649D01*
X1273251Y1082963D01*
X1273427Y1083057D01*
X1273915Y1082145D01*
X1273739Y1082050D01*
G37*
G36*
G01X1273050Y1084188D02*
X1273470Y1084251D01*
X1273823Y1083589D01*
X1273538Y1083275D01*
X1273361Y1083181D01*
X1272873Y1084094D01*
X1273050Y1084188D01*
G37*
G36*
G01X1274847Y1079978D02*
X1274427Y1079915D01*
X1274073Y1080576D01*
X1274359Y1080891D01*
X1274535Y1080985D01*
X1275023Y1080072D01*
X1274847Y1079978D01*
G37*
G36*
G01X1274158Y1082116D02*
X1274578Y1082178D01*
X1274931Y1081517D01*
X1274645Y1081203D01*
X1274469Y1081108D01*
X1273981Y1082021D01*
X1274158Y1082116D01*
G37*
G36*
G01X1271523Y1086195D02*
X1271103Y1086133D01*
X1270750Y1086794D01*
X1271035Y1087108D01*
X1271212Y1087203D01*
X1271700Y1086290D01*
X1271523Y1086195D01*
G37*
G36*
G01X1271942Y1086261D02*
X1272362Y1086323D01*
X1272716Y1085662D01*
X1272430Y1085348D01*
X1272254Y1085253D01*
X1271766Y1086166D01*
X1271942Y1086261D01*
G37*
G36*
G01X1269381Y1093791D02*
X1268961Y1093853D01*
X1268814Y1094588D01*
X1269179Y1094806D01*
X1269375Y1094845D01*
X1269577Y1093830D01*
X1269381Y1093791D01*
G37*
G36*
G01X1269801Y1093732D02*
X1270221Y1093670D01*
X1270367Y1092934D01*
X1270002Y1092717D01*
X1269806Y1092678D01*
X1269604Y1093693D01*
X1269801Y1093732D01*
G37*
G36*
G01X1270298Y1089181D02*
X1269878Y1089243D01*
X1269731Y1089979D01*
X1270096Y1090196D01*
X1270292Y1090236D01*
X1270494Y1089220D01*
X1270298Y1089181D01*
G37*
G36*
G01X1270259Y1091427D02*
X1270679Y1091365D01*
X1270825Y1090630D01*
X1270461Y1090412D01*
X1270265Y1090373D01*
X1270063Y1091388D01*
X1270259Y1091427D01*
G37*
G36*
G01X1269839Y1091486D02*
X1269419Y1091548D01*
X1269273Y1092284D01*
X1269637Y1092501D01*
X1269834Y1092540D01*
X1270036Y1091525D01*
X1269839Y1091486D01*
G37*
G36*
G01X1274798Y1082617D02*
X1274378Y1082554D01*
X1274025Y1083215D01*
X1274311Y1083530D01*
X1274487Y1083624D01*
X1274975Y1082711D01*
X1274798Y1082617D01*
G37*
G36*
G01X1274109Y1084754D02*
X1274529Y1084817D01*
X1274883Y1084156D01*
X1274597Y1083842D01*
X1274421Y1083747D01*
X1273933Y1084660D01*
X1274109Y1084754D01*
G37*
G36*
G01X1273691Y1084689D02*
X1273271Y1084626D01*
X1272917Y1085288D01*
X1273203Y1085602D01*
X1273379Y1085696D01*
X1273867Y1084784D01*
X1273691Y1084689D01*
G37*
G36*
G01X1273002Y1086827D02*
X1273421Y1086890D01*
X1273775Y1086228D01*
X1273489Y1085914D01*
X1273313Y1085820D01*
X1272825Y1086733D01*
X1273002Y1086827D01*
G37*
G36*
G01X1272583Y1086762D02*
X1272163Y1086699D01*
X1271809Y1087360D01*
X1272095Y1087675D01*
X1272271Y1087769D01*
X1272759Y1086856D01*
X1272583Y1086762D01*
G37*
G36*
G01X1270560Y1094026D02*
X1270140Y1094087D01*
X1269993Y1094823D01*
X1270358Y1095041D01*
X1270554Y1095080D01*
X1270756Y1094065D01*
X1270560Y1094026D01*
G37*
G36*
G01X1270521Y1096271D02*
X1270941Y1096209D01*
X1271087Y1095474D01*
X1270723Y1095256D01*
X1270527Y1095217D01*
X1270325Y1096232D01*
X1270521Y1096271D01*
G37*
G36*
G01X1270979Y1093966D02*
X1271399Y1093905D01*
X1271546Y1093169D01*
X1271181Y1092951D01*
X1270985Y1092912D01*
X1270783Y1093927D01*
X1270979Y1093966D01*
G37*
G36*
G01X1271476Y1089416D02*
X1271056Y1089478D01*
X1270910Y1090213D01*
X1271274Y1090431D01*
X1271470Y1090470D01*
X1271672Y1089455D01*
X1271476Y1089416D01*
G37*
G36*
G01X1271018Y1091721D02*
X1270598Y1091782D01*
X1270451Y1092518D01*
X1270816Y1092736D01*
X1271012Y1092775D01*
X1271214Y1091760D01*
X1271018Y1091721D01*
G37*
G36*
G01X1271437Y1091661D02*
X1271857Y1091600D01*
X1272004Y1090864D01*
X1271639Y1090646D01*
X1271443Y1090607D01*
X1271241Y1091622D01*
X1271437Y1091661D01*
G37*
G36*
G01X1275217Y1082682D02*
X1275637Y1082745D01*
X1275991Y1082083D01*
X1275705Y1081769D01*
X1275529Y1081675D01*
X1275041Y1082588D01*
X1275217Y1082682D01*
G37*
G36*
G01X1275906Y1080544D02*
X1275486Y1080481D01*
X1275133Y1081143D01*
X1275418Y1081457D01*
X1275595Y1081551D01*
X1276083Y1080639D01*
X1275906Y1080544D01*
G37*
G36*
G01X1276325Y1080609D02*
X1276745Y1080672D01*
X1277099Y1080011D01*
X1276813Y1079697D01*
X1276637Y1079602D01*
X1276149Y1080515D01*
X1276325Y1080609D01*
G37*
G36*
G01X1268661Y1091252D02*
X1268241Y1091313D01*
X1268095Y1092049D01*
X1268459Y1092267D01*
X1268655Y1092306D01*
X1268857Y1091291D01*
X1268661Y1091252D01*
G37*
G36*
G01X1268203Y1093557D02*
X1267782Y1093618D01*
X1267636Y1094354D01*
X1268001Y1094572D01*
X1268197Y1094611D01*
X1268399Y1093596D01*
X1268203Y1093557D01*
G37*
G36*
G01X1270882Y1085694D02*
X1271302Y1085757D01*
X1271656Y1085096D01*
X1271370Y1084781D01*
X1271194Y1084687D01*
X1270706Y1085600D01*
X1270882Y1085694D01*
G37*
G36*
G01X1271571Y1083556D02*
X1271151Y1083494D01*
X1270798Y1084155D01*
X1271083Y1084469D01*
X1271260Y1084564D01*
X1271748Y1083651D01*
X1271571Y1083556D01*
G37*
G36*
G01X1271990Y1083622D02*
X1272410Y1083684D01*
X1272764Y1083023D01*
X1272478Y1082709D01*
X1272302Y1082615D01*
X1271814Y1083527D01*
X1271990Y1083622D01*
G37*
G36*
G01X1272679Y1081484D02*
X1272259Y1081421D01*
X1271906Y1082083D01*
X1272191Y1082397D01*
X1272368Y1082491D01*
X1272856Y1081578D01*
X1272679Y1081484D01*
G37*
G36*
G01X1273098Y1081549D02*
X1273518Y1081612D01*
X1273872Y1080951D01*
X1273586Y1080636D01*
X1273410Y1080542D01*
X1272922Y1081455D01*
X1273098Y1081549D01*
G37*
G36*
G01X1268622Y1093497D02*
X1269042Y1093436D01*
X1269189Y1092700D01*
X1268824Y1092482D01*
X1268628Y1092443D01*
X1268426Y1093458D01*
X1268622Y1093497D01*
G37*
G36*
G01X1269081Y1091193D02*
X1269501Y1091131D01*
X1269647Y1090395D01*
X1269283Y1090177D01*
X1269087Y1090138D01*
X1268885Y1091154D01*
X1269081Y1091193D01*
G37*
G36*
G01X1269120Y1088947D02*
X1268700Y1089009D01*
X1268553Y1089744D01*
X1268918Y1089962D01*
X1269114Y1090001D01*
X1269316Y1088986D01*
X1269120Y1088947D01*
G37*
G36*
G01X1270464Y1085629D02*
X1270044Y1085566D01*
X1269690Y1086227D01*
X1269976Y1086542D01*
X1270152Y1086636D01*
X1270640Y1085723D01*
X1270464Y1085629D01*
G37*
G36*
G01X1281370Y1111076D02*
X1280970Y1111219D01*
Y1111969D01*
X1281370Y1112111D01*
X1281570D01*
Y1111076D01*
X1281370D01*
G37*
G36*
G01Y1108726D02*
X1280970Y1108869D01*
Y1109619D01*
X1281370Y1109761D01*
X1281570D01*
Y1108726D01*
X1281370D01*
G37*
G36*
G01X1281598Y1096611D02*
X1282018Y1096549D01*
X1282164Y1095813D01*
X1281800Y1095595D01*
X1281604Y1095556D01*
X1281402Y1096572D01*
X1281598Y1096611D01*
G37*
G36*
G01X1280261Y1101279D02*
X1279841Y1101341D01*
X1279695Y1102077D01*
X1280059Y1102295D01*
X1280255Y1102334D01*
X1280457Y1101318D01*
X1280261Y1101279D01*
G37*
G36*
G01X1281178Y1096670D02*
X1280758Y1096732D01*
X1280612Y1097467D01*
X1280976Y1097685D01*
X1281173Y1097724D01*
X1281374Y1096709D01*
X1281178Y1096670D01*
G37*
G36*
G01X1280720Y1098975D02*
X1280300Y1099036D01*
X1280153Y1099772D01*
X1280518Y1099990D01*
X1280714Y1100029D01*
X1280916Y1099014D01*
X1280720Y1098975D01*
G37*
G36*
G01X1280681Y1101220D02*
X1281101Y1101159D01*
X1281247Y1100423D01*
X1280883Y1100205D01*
X1280687Y1100166D01*
X1280485Y1101181D01*
X1280681Y1101220D01*
G37*
G36*
G01X1281139Y1098915D02*
X1281560Y1098854D01*
X1281706Y1098118D01*
X1281341Y1097900D01*
X1281145Y1097861D01*
X1280943Y1098876D01*
X1281139Y1098915D01*
G37*
G36*
G01X1279305Y1108135D02*
X1279725Y1108073D01*
X1279872Y1107337D01*
X1279507Y1107120D01*
X1279311Y1107081D01*
X1279109Y1108096D01*
X1279305Y1108135D01*
G37*
G36*
G01X1278886Y1108194D02*
X1278465Y1108256D01*
X1278319Y1108991D01*
X1278684Y1109209D01*
X1278880Y1109248D01*
X1279082Y1108233D01*
X1278886Y1108194D01*
G37*
G36*
G01X1279344Y1105889D02*
X1278924Y1105951D01*
X1278778Y1106686D01*
X1279142Y1106904D01*
X1279338Y1106943D01*
X1279540Y1105928D01*
X1279344Y1105889D01*
G37*
G36*
G01X1279803Y1103584D02*
X1279383Y1103646D01*
X1279236Y1104382D01*
X1279601Y1104599D01*
X1279797Y1104638D01*
X1279999Y1103623D01*
X1279803Y1103584D01*
G37*
G36*
G01X1279764Y1105830D02*
X1280184Y1105768D01*
X1280330Y1105033D01*
X1279966Y1104815D01*
X1279770Y1104776D01*
X1279568Y1105791D01*
X1279764Y1105830D01*
G37*
G36*
G01X1280222Y1103525D02*
X1280642Y1103463D01*
X1280789Y1102728D01*
X1280424Y1102510D01*
X1280228Y1102471D01*
X1280026Y1103486D01*
X1280222Y1103525D01*
G37*
G36*
G01X1277905Y1100811D02*
X1277485Y1100872D01*
X1277339Y1101608D01*
X1277703Y1101826D01*
X1277899Y1101865D01*
X1278101Y1100850D01*
X1277905Y1100811D01*
G37*
G36*
G01X1278364Y1098506D02*
X1277944Y1098568D01*
X1277797Y1099303D01*
X1278162Y1099521D01*
X1278358Y1099560D01*
X1278560Y1098545D01*
X1278364Y1098506D01*
G37*
G36*
G01X1278782Y1098447D02*
X1279203Y1098385D01*
X1279349Y1097649D01*
X1278984Y1097432D01*
X1278788Y1097393D01*
X1278586Y1098408D01*
X1278782Y1098447D01*
G37*
G36*
G01X1278325Y1100751D02*
X1278745Y1100690D01*
X1278891Y1099954D01*
X1278527Y1099736D01*
X1278331Y1099697D01*
X1278129Y1100712D01*
X1278325Y1100751D01*
G37*
G36*
G01X1278822Y1096201D02*
X1278402Y1096263D01*
X1278256Y1096998D01*
X1278620Y1097216D01*
X1278817Y1097255D01*
X1279019Y1096240D01*
X1278822Y1096201D01*
G37*
G36*
G01X1276949Y1107666D02*
X1277369Y1107604D01*
X1277515Y1106869D01*
X1277151Y1106651D01*
X1276955Y1106612D01*
X1276753Y1107627D01*
X1276949Y1107666D01*
G37*
G36*
G01X1277447Y1103116D02*
X1277026Y1103177D01*
X1276880Y1103913D01*
X1277245Y1104131D01*
X1277441Y1104170D01*
X1277643Y1103155D01*
X1277447Y1103116D01*
G37*
G36*
G01X1276988Y1105420D02*
X1276568Y1105482D01*
X1276421Y1106218D01*
X1276786Y1106435D01*
X1276982Y1106474D01*
X1277184Y1105459D01*
X1276988Y1105420D01*
G37*
G36*
G01X1277408Y1105361D02*
X1277828Y1105299D01*
X1277974Y1104564D01*
X1277610Y1104346D01*
X1277413Y1104307D01*
X1277211Y1105322D01*
X1277408Y1105361D01*
G37*
G36*
G01X1277865Y1103056D02*
X1278285Y1102995D01*
X1278432Y1102259D01*
X1278067Y1102041D01*
X1277871Y1102002D01*
X1277669Y1103017D01*
X1277865Y1103056D01*
G37*
G36*
G01X1278126Y1107900D02*
X1278546Y1107838D01*
X1278693Y1107103D01*
X1278328Y1106885D01*
X1278132Y1106846D01*
X1277930Y1107861D01*
X1278126Y1107900D01*
G37*
G36*
G01X1277708Y1107959D02*
X1277287Y1108021D01*
X1277141Y1108757D01*
X1277506Y1108974D01*
X1277702Y1109014D01*
X1277904Y1107998D01*
X1277708Y1107959D01*
G37*
G36*
G01X1278585Y1105595D02*
X1279005Y1105534D01*
X1279151Y1104798D01*
X1278787Y1104580D01*
X1278591Y1104541D01*
X1278389Y1105556D01*
X1278585Y1105595D01*
G37*
G36*
G01X1278165Y1105655D02*
X1277745Y1105716D01*
X1277599Y1106452D01*
X1277963Y1106670D01*
X1278159Y1106709D01*
X1278361Y1105694D01*
X1278165Y1105655D01*
G37*
G36*
G01X1279043Y1103290D02*
X1279464Y1103229D01*
X1279610Y1102493D01*
X1279245Y1102275D01*
X1279049Y1102236D01*
X1278847Y1103251D01*
X1279043Y1103290D01*
G37*
G36*
G01X1278625Y1103350D02*
X1278205Y1103411D01*
X1278058Y1104147D01*
X1278423Y1104365D01*
X1278619Y1104404D01*
X1278821Y1103389D01*
X1278625Y1103350D01*
G37*
G36*
G01X1279542Y1098740D02*
X1279122Y1098802D01*
X1278975Y1099537D01*
X1279340Y1099755D01*
X1279536Y1099794D01*
X1279738Y1098779D01*
X1279542Y1098740D01*
G37*
G36*
G01X1279961Y1098681D02*
X1280381Y1098619D01*
X1280527Y1097884D01*
X1280163Y1097666D01*
X1279966Y1097627D01*
X1279764Y1098642D01*
X1279961Y1098681D01*
G37*
G36*
G01X1279082Y1101045D02*
X1278662Y1101107D01*
X1278516Y1101842D01*
X1278880Y1102060D01*
X1279077Y1102099D01*
X1279279Y1101084D01*
X1279082Y1101045D01*
G37*
G36*
G01X1279502Y1100986D02*
X1279922Y1100924D01*
X1280068Y1100188D01*
X1279704Y1099971D01*
X1279508Y1099932D01*
X1279306Y1100947D01*
X1279502Y1100986D01*
G37*
G36*
G01X1280001Y1096435D02*
X1279580Y1096497D01*
X1279434Y1097233D01*
X1279799Y1097450D01*
X1279995Y1097489D01*
X1280197Y1096474D01*
X1280001Y1096435D01*
G37*
G36*
G01X1277605Y1098212D02*
X1278025Y1098151D01*
X1278172Y1097415D01*
X1277807Y1097197D01*
X1277611Y1097158D01*
X1277409Y1098173D01*
X1277605Y1098212D01*
G37*
G36*
G01X1277186Y1098272D02*
X1276766Y1098333D01*
X1276619Y1099069D01*
X1276984Y1099287D01*
X1277180Y1099326D01*
X1277382Y1098311D01*
X1277186Y1098272D01*
G37*
G36*
G01X1277644Y1095967D02*
X1277224Y1096028D01*
X1277078Y1096764D01*
X1277442Y1096982D01*
X1277638Y1097021D01*
X1277840Y1096006D01*
X1277644Y1095967D01*
G37*
G36*
G01X1277147Y1100517D02*
X1277567Y1100455D01*
X1277713Y1099720D01*
X1277349Y1099502D01*
X1277152Y1099463D01*
X1276951Y1100478D01*
X1277147Y1100517D01*
G37*
G36*
G01X1276727Y1100576D02*
X1276307Y1100638D01*
X1276161Y1101374D01*
X1276525Y1101591D01*
X1276721Y1101630D01*
X1276923Y1100615D01*
X1276727Y1100576D01*
G37*
G36*
G01X1275351Y1107491D02*
X1274931Y1107552D01*
X1274785Y1108288D01*
X1275149Y1108506D01*
X1275345Y1108545D01*
X1275547Y1107530D01*
X1275351Y1107491D01*
G37*
G36*
G01X1276268Y1102881D02*
X1275848Y1102943D01*
X1275702Y1103678D01*
X1276066Y1103896D01*
X1276263Y1103935D01*
X1276465Y1102920D01*
X1276268Y1102881D01*
G37*
G36*
G01X1276229Y1105127D02*
X1276650Y1105065D01*
X1276796Y1104329D01*
X1276431Y1104112D01*
X1276235Y1104073D01*
X1276033Y1105088D01*
X1276229Y1105127D01*
G37*
G36*
G01X1275810Y1105186D02*
X1275390Y1105248D01*
X1275243Y1105983D01*
X1275608Y1106201D01*
X1275804Y1106240D01*
X1276006Y1105225D01*
X1275810Y1105186D01*
G37*
G36*
G01X1275771Y1107432D02*
X1276191Y1107370D01*
X1276337Y1106634D01*
X1275973Y1106416D01*
X1275777Y1106377D01*
X1275575Y1107392D01*
X1275771Y1107432D01*
G37*
G36*
G01X1276688Y1102822D02*
X1277108Y1102760D01*
X1277255Y1102025D01*
X1276890Y1101807D01*
X1276694Y1101768D01*
X1276492Y1102783D01*
X1276688Y1102822D01*
G37*
G36*
G01X1281370Y1113426D02*
X1280970Y1113569D01*
Y1114319D01*
X1281370Y1114461D01*
X1281570D01*
Y1113426D01*
X1281370D01*
G37*
G36*
G01Y1115776D02*
X1280970Y1115919D01*
Y1116669D01*
X1281370Y1116811D01*
X1281570D01*
Y1115776D01*
X1281370D01*
G37*
G36*
G01Y1118126D02*
X1280970Y1118269D01*
Y1119019D01*
X1281370Y1119161D01*
X1281570D01*
Y1118126D01*
X1281370D01*
G37*
G36*
G01Y1120476D02*
X1280970Y1120619D01*
Y1121369D01*
X1281370Y1121511D01*
X1281570D01*
Y1120476D01*
X1281370D01*
G37*
G36*
G01X1274030Y1580678D02*
G03I-720J0D01*
G37*
G36*
G01Y1575592D02*
G03I-720J0D01*
G37*
G36*
G01X1269074D02*
G03I-720J0D01*
G37*
G36*
G01Y1580678D02*
G03I-720J0D01*
G37*
G36*
G01X1281134Y1575686D02*
G03I-720J0D01*
G37*
G36*
G01Y1580678D02*
G03I-720J0D01*
G37*
G36*
G01X1267270Y1599884D02*
G03I-720J0D01*
G37*
G36*
G01X1274374Y1599790D02*
G03I-720J0D01*
G37*
G36*
G01X1279330D02*
G03I-720J0D01*
G37*
G36*
G01X1274030Y1592590D02*
G03I-720J0D01*
G37*
G36*
G01X1269074D02*
G03I-720J0D01*
G37*
G36*
G01X1274030Y1587598D02*
G03I-720J0D01*
G37*
G36*
G01X1269074D02*
G03I-720J0D01*
G37*
G36*
G01X1281134D02*
G03I-720J0D01*
G37*
G36*
G01Y1592590D02*
G03I-720J0D01*
G37*
G36*
G01X1267270Y1616788D02*
G03I-720J0D01*
G37*
G36*
G01Y1611796D02*
G03I-720J0D01*
G37*
G36*
G01Y1604876D02*
G03I-720J0D01*
G37*
G36*
G01X1274374Y1611796D02*
G03I-720J0D01*
G37*
G36*
G01Y1604876D02*
G03I-720J0D01*
G37*
G36*
G01X1279330Y1611796D02*
G03I-720J0D01*
G37*
G36*
G01Y1604876D02*
G03I-720J0D01*
G37*
G36*
G01X1274374Y1616788D02*
G03I-720J0D01*
G37*
G36*
G01X1279330D02*
G03I-720J0D01*
G37*
G36*
G01X1288352Y-29033D02*
G03I-557J0D01*
G37*
G36*
G01Y-33989D02*
G03I-557J0D01*
G37*
G36*
G01Y-13989D02*
G03I-557J0D01*
G37*
G36*
G01Y-19033D02*
G03I-557J0D01*
G37*
G36*
G01Y-23989D02*
G03I-557J0D01*
G37*
G36*
G01Y967D02*
G03I-557J0D01*
G37*
G36*
G01Y-3989D02*
G03I-557J0D01*
G37*
G36*
G01Y-9033D02*
G03I-557J0D01*
G37*
G36*
G01X1290358Y64562D02*
X1294100D01*
X1294144Y64518D01*
Y61408D01*
G03X1294512Y60520I1255J0D01*
G01X1295324Y59707D01*
Y55951D01*
G03X1295693Y55063I1256J1D01*
G01X1295802Y54953D01*
Y54290D01*
X1296770Y53322D01*
X1300360D01*
X1301170Y52512D01*
Y50710D01*
X1300480Y50020D01*
X1289785D01*
X1289385Y50420D01*
Y63589D01*
X1290358Y64562D01*
G37*
G36*
G01X1296607Y315571D02*
G03I-720J0D01*
G37*
G36*
G01X1288038Y849777D02*
X1288438Y849634D01*
Y848884D01*
X1288038Y848741D01*
X1287838D01*
Y849777D01*
X1288038D01*
G37*
G36*
G01X1287638Y847567D02*
X1287238Y847709D01*
Y848459D01*
X1287638Y848601D01*
X1287838D01*
Y847567D01*
X1287638D01*
G37*
G36*
G01Y849917D02*
X1287238Y850059D01*
Y850809D01*
X1287638Y850951D01*
X1287838D01*
Y849917D01*
X1287638D01*
G37*
G36*
G01X1288038Y852127D02*
X1288438Y851984D01*
Y851234D01*
X1288038Y851091D01*
X1287838D01*
Y852127D01*
X1288038D01*
G37*
G36*
G01X1290038Y847567D02*
X1289638Y847709D01*
Y848459D01*
X1290038Y848601D01*
X1290238D01*
Y847567D01*
X1290038D01*
G37*
G36*
G01Y849917D02*
X1289638Y850059D01*
Y850809D01*
X1290038Y850951D01*
X1290238D01*
Y849917D01*
X1290038D01*
G37*
G36*
G01X1290438Y852127D02*
X1290838Y851984D01*
Y851234D01*
X1290438Y851091D01*
X1290238D01*
Y852127D01*
X1290438D01*
G37*
G36*
G01Y847427D02*
X1290838Y847284D01*
Y846534D01*
X1290438Y846391D01*
X1290238D01*
Y847427D01*
X1290438D01*
G37*
G36*
G01Y849777D02*
X1290838Y849634D01*
Y848884D01*
X1290438Y848741D01*
X1290238D01*
Y849777D01*
X1290438D01*
G37*
G36*
G01X1289238Y852127D02*
X1289638Y851984D01*
Y851234D01*
X1289238Y851091D01*
X1289038D01*
Y852127D01*
X1289238D01*
G37*
G36*
G01Y847427D02*
X1289638Y847284D01*
Y846534D01*
X1289238Y846391D01*
X1289038D01*
Y847427D01*
X1289238D01*
G37*
G36*
G01Y849777D02*
X1289638Y849634D01*
Y848884D01*
X1289238Y848741D01*
X1289038D01*
Y849777D01*
X1289238D01*
G37*
G36*
G01X1288838Y847567D02*
X1288438Y847709D01*
Y848459D01*
X1288838Y848601D01*
X1289038D01*
Y847567D01*
X1288838D01*
G37*
G36*
G01Y849917D02*
X1288438Y850059D01*
Y850809D01*
X1288838Y850951D01*
X1289038D01*
Y849917D01*
X1288838D01*
G37*
G36*
G01X1291238Y845217D02*
X1290838Y845359D01*
Y846109D01*
X1291238Y846251D01*
X1291438D01*
Y845217D01*
X1291238D01*
G37*
G36*
G01Y847567D02*
X1290838Y847709D01*
Y848459D01*
X1291238Y848601D01*
X1291438D01*
Y847567D01*
X1291238D01*
G37*
G36*
G01Y849917D02*
X1290838Y850059D01*
Y850809D01*
X1291238Y850951D01*
X1291438D01*
Y849917D01*
X1291238D01*
G37*
G36*
G01X1291638Y852127D02*
X1292038Y851984D01*
Y851234D01*
X1291638Y851091D01*
X1291438D01*
Y852127D01*
X1291638D01*
G37*
G36*
G01Y847427D02*
X1292038Y847284D01*
Y846534D01*
X1291638Y846391D01*
X1291438D01*
Y847427D01*
X1291638D01*
G37*
G36*
G01Y849777D02*
X1292038Y849634D01*
Y848884D01*
X1291638Y848741D01*
X1291438D01*
Y849777D01*
X1291638D01*
G37*
G36*
G01X1296818Y852647D02*
X1297218Y852504D01*
Y851754D01*
X1296818Y851611D01*
X1296618D01*
Y852647D01*
X1296818D01*
G37*
G36*
G01X1282038Y864541D02*
X1282438Y864399D01*
Y863649D01*
X1282038Y863507D01*
X1281838D01*
Y864541D01*
X1282038D01*
G37*
G36*
G01Y866891D02*
X1282438Y866749D01*
Y865999D01*
X1282038Y865857D01*
X1281838D01*
Y866891D01*
X1282038D01*
G37*
G36*
G01Y862191D02*
X1282438Y862049D01*
Y861299D01*
X1282038Y861157D01*
X1281838D01*
Y862191D01*
X1282038D01*
G37*
G36*
G01X1288038Y866227D02*
X1288438Y866084D01*
Y865334D01*
X1288038Y865191D01*
X1287838D01*
Y866227D01*
X1288038D01*
G37*
G36*
G01Y863877D02*
X1288438Y863734D01*
Y862984D01*
X1288038Y862841D01*
X1287838D01*
Y863877D01*
X1288038D01*
G37*
G36*
G01X1287638Y866367D02*
X1287238Y866509D01*
Y867259D01*
X1287638Y867401D01*
X1287838D01*
Y866367D01*
X1287638D01*
G37*
G36*
G01Y864017D02*
X1287238Y864159D01*
Y864909D01*
X1287638Y865051D01*
X1287838D01*
Y864017D01*
X1287638D01*
G37*
G36*
G01X1288038Y861527D02*
X1288438Y861384D01*
Y860634D01*
X1288038Y860491D01*
X1287838D01*
Y861527D01*
X1288038D01*
G37*
G36*
G01Y856827D02*
X1288438Y856684D01*
Y855934D01*
X1288038Y855791D01*
X1287838D01*
Y856827D01*
X1288038D01*
G37*
G36*
G01Y859177D02*
X1288438Y859034D01*
Y858284D01*
X1288038Y858141D01*
X1287838D01*
Y859177D01*
X1288038D01*
G37*
G36*
G01X1287638Y861667D02*
X1287238Y861809D01*
Y862559D01*
X1287638Y862701D01*
X1287838D01*
Y861667D01*
X1287638D01*
G37*
G36*
G01Y859317D02*
X1287238Y859459D01*
Y860209D01*
X1287638Y860351D01*
X1287838D01*
Y859317D01*
X1287638D01*
G37*
G36*
G01Y854617D02*
X1287238Y854759D01*
Y855509D01*
X1287638Y855651D01*
X1287838D01*
Y854617D01*
X1287638D01*
G37*
G36*
G01Y856967D02*
X1287238Y857109D01*
Y857859D01*
X1287638Y858001D01*
X1287838D01*
Y856967D01*
X1287638D01*
G37*
G36*
G01X1288038Y854477D02*
X1288438Y854334D01*
Y853584D01*
X1288038Y853441D01*
X1287838D01*
Y854477D01*
X1288038D01*
G37*
G36*
G01X1287638Y852267D02*
X1287238Y852409D01*
Y853159D01*
X1287638Y853301D01*
X1287838D01*
Y852267D01*
X1287638D01*
G37*
G36*
G01X1288038Y868577D02*
X1288438Y868434D01*
Y867684D01*
X1288038Y867541D01*
X1287838D01*
Y868577D01*
X1288038D01*
G37*
G36*
G01X1290438D02*
X1290838Y868434D01*
Y867684D01*
X1290438Y867541D01*
X1290238D01*
Y868577D01*
X1290438D01*
G37*
G36*
G01Y866227D02*
X1290838Y866084D01*
Y865334D01*
X1290438Y865191D01*
X1290238D01*
Y866227D01*
X1290438D01*
G37*
G36*
G01Y863877D02*
X1290838Y863734D01*
Y862984D01*
X1290438Y862841D01*
X1290238D01*
Y863877D01*
X1290438D01*
G37*
G36*
G01X1290038Y866367D02*
X1289638Y866509D01*
Y867259D01*
X1290038Y867401D01*
X1290238D01*
Y866367D01*
X1290038D01*
G37*
G36*
G01Y864017D02*
X1289638Y864159D01*
Y864909D01*
X1290038Y865051D01*
X1290238D01*
Y864017D01*
X1290038D01*
G37*
G36*
G01X1290438Y861527D02*
X1290838Y861384D01*
Y860634D01*
X1290438Y860491D01*
X1290238D01*
Y861527D01*
X1290438D01*
G37*
G36*
G01Y859177D02*
X1290838Y859034D01*
Y858284D01*
X1290438Y858141D01*
X1290238D01*
Y859177D01*
X1290438D01*
G37*
G36*
G01Y856827D02*
X1290838Y856684D01*
Y855934D01*
X1290438Y855791D01*
X1290238D01*
Y856827D01*
X1290438D01*
G37*
G36*
G01X1290038Y861667D02*
X1289638Y861809D01*
Y862559D01*
X1290038Y862701D01*
X1290238D01*
Y861667D01*
X1290038D01*
G37*
G36*
G01Y859317D02*
X1289638Y859459D01*
Y860209D01*
X1290038Y860351D01*
X1290238D01*
Y859317D01*
X1290038D01*
G37*
G36*
G01Y854617D02*
X1289638Y854759D01*
Y855509D01*
X1290038Y855651D01*
X1290238D01*
Y854617D01*
X1290038D01*
G37*
G36*
G01Y856967D02*
X1289638Y857109D01*
Y857859D01*
X1290038Y858001D01*
X1290238D01*
Y856967D01*
X1290038D01*
G37*
G36*
G01X1290438Y854477D02*
X1290838Y854334D01*
Y853584D01*
X1290438Y853441D01*
X1290238D01*
Y854477D01*
X1290438D01*
G37*
G36*
G01X1290038Y852267D02*
X1289638Y852409D01*
Y853159D01*
X1290038Y853301D01*
X1290238D01*
Y852267D01*
X1290038D01*
G37*
G36*
G01X1288838Y864017D02*
X1288438Y864159D01*
Y864909D01*
X1288838Y865051D01*
X1289038D01*
Y864017D01*
X1288838D01*
G37*
G36*
G01X1289238Y861527D02*
X1289638Y861384D01*
Y860634D01*
X1289238Y860491D01*
X1289038D01*
Y861527D01*
X1289238D01*
G37*
G36*
G01Y856827D02*
X1289638Y856684D01*
Y855934D01*
X1289238Y855791D01*
X1289038D01*
Y856827D01*
X1289238D01*
G37*
G36*
G01Y859177D02*
X1289638Y859034D01*
Y858284D01*
X1289238Y858141D01*
X1289038D01*
Y859177D01*
X1289238D01*
G37*
G36*
G01X1288838Y861667D02*
X1288438Y861809D01*
Y862559D01*
X1288838Y862701D01*
X1289038D01*
Y861667D01*
X1288838D01*
G37*
G36*
G01Y859317D02*
X1288438Y859459D01*
Y860209D01*
X1288838Y860351D01*
X1289038D01*
Y859317D01*
X1288838D01*
G37*
G36*
G01Y854617D02*
X1288438Y854759D01*
Y855509D01*
X1288838Y855651D01*
X1289038D01*
Y854617D01*
X1288838D01*
G37*
G36*
G01Y856967D02*
X1288438Y857109D01*
Y857859D01*
X1288838Y858001D01*
X1289038D01*
Y856967D01*
X1288838D01*
G37*
G36*
G01X1289238Y854477D02*
X1289638Y854334D01*
Y853584D01*
X1289238Y853441D01*
X1289038D01*
Y854477D01*
X1289238D01*
G37*
G36*
G01X1288838Y852267D02*
X1288438Y852409D01*
Y853159D01*
X1288838Y853301D01*
X1289038D01*
Y852267D01*
X1288838D01*
G37*
G36*
G01X1289238Y868577D02*
X1289638Y868434D01*
Y867684D01*
X1289238Y867541D01*
X1289038D01*
Y868577D01*
X1289238D01*
G37*
G36*
G01Y866227D02*
X1289638Y866084D01*
Y865334D01*
X1289238Y865191D01*
X1289038D01*
Y866227D01*
X1289238D01*
G37*
G36*
G01Y863877D02*
X1289638Y863734D01*
Y862984D01*
X1289238Y862841D01*
X1289038D01*
Y863877D01*
X1289238D01*
G37*
G36*
G01X1288838Y866367D02*
X1288438Y866509D01*
Y867259D01*
X1288838Y867401D01*
X1289038D01*
Y866367D01*
X1288838D01*
G37*
G36*
G01X1291238Y854617D02*
X1290838Y854759D01*
Y855509D01*
X1291238Y855651D01*
X1291438D01*
Y854617D01*
X1291238D01*
G37*
G36*
G01Y856967D02*
X1290838Y857109D01*
Y857859D01*
X1291238Y858001D01*
X1291438D01*
Y856967D01*
X1291238D01*
G37*
G36*
G01Y861667D02*
X1290838Y861809D01*
Y862559D01*
X1291238Y862701D01*
X1291438D01*
Y861667D01*
X1291238D01*
G37*
G36*
G01Y859317D02*
X1290838Y859459D01*
Y860209D01*
X1291238Y860351D01*
X1291438D01*
Y859317D01*
X1291238D01*
G37*
G36*
G01Y852267D02*
X1290838Y852409D01*
Y853159D01*
X1291238Y853301D01*
X1291438D01*
Y852267D01*
X1291238D01*
G37*
G36*
G01Y866367D02*
X1290838Y866509D01*
Y867259D01*
X1291238Y867401D01*
X1291438D01*
Y866367D01*
X1291238D01*
G37*
G36*
G01Y864017D02*
X1290838Y864159D01*
Y864909D01*
X1291238Y865051D01*
X1291438D01*
Y864017D01*
X1291238D01*
G37*
G36*
G01X1291638Y863877D02*
X1292038Y863734D01*
Y862984D01*
X1291638Y862841D01*
X1291438D01*
Y863877D01*
X1291638D01*
G37*
G36*
G01Y856827D02*
X1292038Y856684D01*
Y855934D01*
X1291638Y855791D01*
X1291438D01*
Y856827D01*
X1291638D01*
G37*
G36*
G01Y859177D02*
X1292038Y859034D01*
Y858284D01*
X1291638Y858141D01*
X1291438D01*
Y859177D01*
X1291638D01*
G37*
G36*
G01Y861527D02*
X1292038Y861384D01*
Y860634D01*
X1291638Y860491D01*
X1291438D01*
Y861527D01*
X1291638D01*
G37*
G36*
G01Y854477D02*
X1292038Y854334D01*
Y853584D01*
X1291638Y853441D01*
X1291438D01*
Y854477D01*
X1291638D01*
G37*
G36*
G01Y868577D02*
X1292038Y868434D01*
Y867684D01*
X1291638Y867541D01*
X1291438D01*
Y868577D01*
X1291638D01*
G37*
G36*
G01Y866227D02*
X1292038Y866084D01*
Y865334D01*
X1291638Y865191D01*
X1291438D01*
Y866227D01*
X1291638D01*
G37*
G36*
G01X1296818Y859697D02*
X1297218Y859554D01*
Y858804D01*
X1296818Y858661D01*
X1296618D01*
Y859697D01*
X1296818D01*
G37*
G36*
G01Y857347D02*
X1297218Y857204D01*
Y856454D01*
X1296818Y856311D01*
X1296618D01*
Y857347D01*
X1296818D01*
G37*
G36*
G01Y854997D02*
X1297218Y854854D01*
Y854104D01*
X1296818Y853961D01*
X1296618D01*
Y854997D01*
X1296818D01*
G37*
G36*
G01X1296418Y857487D02*
X1296018Y857629D01*
Y858379D01*
X1296418Y858521D01*
X1296618D01*
Y857487D01*
X1296418D01*
G37*
G36*
G01Y855137D02*
X1296018Y855279D01*
Y856029D01*
X1296418Y856171D01*
X1296618D01*
Y855137D01*
X1296418D01*
G37*
G36*
G01Y852787D02*
X1296018Y852929D01*
Y853679D01*
X1296418Y853821D01*
X1296618D01*
Y852787D01*
X1296418D01*
G37*
G36*
G01X1297618Y857487D02*
X1297218Y857629D01*
Y858379D01*
X1297618Y858521D01*
X1297818D01*
Y857487D01*
X1297618D01*
G37*
G36*
G01Y855137D02*
X1297218Y855279D01*
Y856029D01*
X1297618Y856171D01*
X1297818D01*
Y855137D01*
X1297618D01*
G37*
G36*
G01Y852787D02*
X1297218Y852929D01*
Y853679D01*
X1297618Y853821D01*
X1297818D01*
Y852787D01*
X1297618D01*
G37*
G36*
G01X1285265Y884775D02*
X1285447Y884392D01*
X1284917Y883861D01*
X1284533Y884043D01*
X1284392Y884185D01*
X1285124Y884917D01*
X1285265Y884775D01*
G37*
G36*
G01X1283420Y883495D02*
X1283237Y883879D01*
X1283768Y884409D01*
X1284151Y884227D01*
X1284293Y884086D01*
X1283561Y883354D01*
X1283420Y883495D01*
G37*
G36*
G01X1283603Y883114D02*
X1283785Y882730D01*
X1283255Y882200D01*
X1282871Y882382D01*
X1282730Y882523D01*
X1283462Y883255D01*
X1283603Y883114D01*
G37*
G36*
G01X1281758Y881834D02*
X1281576Y882217D01*
X1282106Y882748D01*
X1282490Y882565D01*
X1282631Y882424D01*
X1281899Y881692D01*
X1281758Y881834D01*
G37*
G36*
G01X1282571Y884344D02*
X1282388Y884728D01*
X1282919Y885258D01*
X1283302Y885076D01*
X1283444Y884935D01*
X1282712Y884203D01*
X1282571Y884344D01*
G37*
G36*
G01X1282754Y883963D02*
X1282936Y883579D01*
X1282406Y883049D01*
X1282022Y883231D01*
X1281881Y883372D01*
X1282613Y884104D01*
X1282754Y883963D01*
G37*
G36*
G01X1282038Y869241D02*
X1282438Y869099D01*
Y868349D01*
X1282038Y868207D01*
X1281838D01*
Y869241D01*
X1282038D01*
G37*
G36*
G01Y871591D02*
X1282438Y871449D01*
Y870699D01*
X1282038Y870557D01*
X1281838D01*
Y871591D01*
X1282038D01*
G37*
G36*
G01Y878641D02*
X1282438Y878499D01*
Y877749D01*
X1282038Y877607D01*
X1281838D01*
Y878641D01*
X1282038D01*
G37*
G36*
G01Y876291D02*
X1282438Y876149D01*
Y875399D01*
X1282038Y875257D01*
X1281838D01*
Y876291D01*
X1282038D01*
G37*
G36*
G01Y873941D02*
X1282438Y873799D01*
Y873049D01*
X1282038Y872907D01*
X1281838D01*
Y873941D01*
X1282038D01*
G37*
G36*
G01X1284269Y882646D02*
X1284086Y883030D01*
X1284617Y883560D01*
X1285000Y883378D01*
X1285142Y883237D01*
X1284410Y882505D01*
X1284269Y882646D01*
G37*
G36*
G01X1282607Y880985D02*
X1282425Y881368D01*
X1282955Y881899D01*
X1283339Y881716D01*
X1283480Y881575D01*
X1282748Y880843D01*
X1282607Y880985D01*
G37*
G36*
G01X1284452Y882265D02*
X1284634Y881881D01*
X1284104Y881351D01*
X1283720Y881533D01*
X1283579Y881674D01*
X1284311Y882406D01*
X1284452Y882265D01*
G37*
G36*
G01X1285930Y884308D02*
X1285748Y884692D01*
X1286278Y885222D01*
X1286662Y885040D01*
X1286803Y884898D01*
X1286072Y884167D01*
X1285930Y884308D01*
G37*
G36*
G01X1286114Y883926D02*
X1286296Y883543D01*
X1285766Y883012D01*
X1285382Y883194D01*
X1285241Y883336D01*
X1285973Y884068D01*
X1286114Y883926D01*
G37*
G36*
G01X1291505Y880830D02*
X1291687Y880446D01*
X1291157Y879916D01*
X1290773Y880098D01*
X1290632Y880239D01*
X1291364Y880971D01*
X1291505Y880830D01*
G37*
G36*
G01X1289660Y879550D02*
X1289478Y879933D01*
X1290008Y880464D01*
X1290392Y880281D01*
X1290533Y880140D01*
X1289801Y879408D01*
X1289660Y879550D01*
G37*
G36*
G01X1289844Y879168D02*
X1290026Y878784D01*
X1289495Y878254D01*
X1289112Y878436D01*
X1288970Y878577D01*
X1289702Y879309D01*
X1289844Y879168D01*
G37*
G36*
G01X1287638Y875767D02*
X1287238Y875909D01*
Y876659D01*
X1287638Y876801D01*
X1287838D01*
Y875767D01*
X1287638D01*
G37*
G36*
G01Y873417D02*
X1287238Y873559D01*
Y874309D01*
X1287638Y874451D01*
X1287838D01*
Y873417D01*
X1287638D01*
G37*
G36*
G01X1288038Y870927D02*
X1288438Y870784D01*
Y870034D01*
X1288038Y869891D01*
X1287838D01*
Y870927D01*
X1288038D01*
G37*
G36*
G01X1287638Y871067D02*
X1287238Y871209D01*
Y871959D01*
X1287638Y872101D01*
X1287838D01*
Y871067D01*
X1287638D01*
G37*
G36*
G01Y868717D02*
X1287238Y868859D01*
Y869609D01*
X1287638Y869751D01*
X1287838D01*
Y868717D01*
X1287638D01*
G37*
G36*
G01X1288038Y875627D02*
X1288438Y875484D01*
Y874734D01*
X1288038Y874591D01*
X1287838D01*
Y875627D01*
X1288038D01*
G37*
G36*
G01Y873277D02*
X1288438Y873134D01*
Y872384D01*
X1288038Y872241D01*
X1287838D01*
Y873277D01*
X1288038D01*
G37*
G36*
G01X1293167Y882491D02*
X1293349Y882108D01*
X1292819Y881577D01*
X1292435Y881759D01*
X1292294Y881901D01*
X1293026Y882633D01*
X1293167Y882491D01*
G37*
G36*
G01X1291322Y881211D02*
X1291139Y881595D01*
X1291670Y882125D01*
X1292053Y881943D01*
X1292195Y881802D01*
X1291463Y881070D01*
X1291322Y881211D01*
G37*
G36*
G01X1291542Y877470D02*
X1291724Y877086D01*
X1291193Y876556D01*
X1290810Y876738D01*
X1290668Y876879D01*
X1291400Y877611D01*
X1291542Y877470D01*
G37*
G36*
G01X1290438Y870927D02*
X1290838Y870784D01*
Y870034D01*
X1290438Y869891D01*
X1290238D01*
Y870927D01*
X1290438D01*
G37*
G36*
G01X1290038Y871067D02*
X1289638Y871209D01*
Y871959D01*
X1290038Y872101D01*
X1290238D01*
Y871067D01*
X1290038D01*
G37*
G36*
G01Y868717D02*
X1289638Y868859D01*
Y869609D01*
X1290038Y869751D01*
X1290238D01*
Y868717D01*
X1290038D01*
G37*
G36*
G01X1290438Y875627D02*
X1290838Y875484D01*
Y874734D01*
X1290438Y874591D01*
X1290238D01*
Y875627D01*
X1290438D01*
G37*
G36*
G01Y873277D02*
X1290838Y873134D01*
Y872384D01*
X1290438Y872241D01*
X1290238D01*
Y873277D01*
X1290438D01*
G37*
G36*
G01X1290038Y873417D02*
X1289638Y873559D01*
Y874309D01*
X1290038Y874451D01*
X1290238D01*
Y873417D01*
X1290038D01*
G37*
G36*
G01X1296358Y883933D02*
X1295958Y884076D01*
Y884826D01*
X1296358Y884969D01*
X1296558D01*
Y883933D01*
X1296358D01*
G37*
G36*
G01X1294865Y880793D02*
X1295047Y880410D01*
X1294517Y879879D01*
X1294133Y880061D01*
X1293992Y880203D01*
X1294724Y880935D01*
X1294865Y880793D01*
G37*
G36*
G01X1293020Y879513D02*
X1292837Y879897D01*
X1293368Y880427D01*
X1293751Y880245D01*
X1293893Y880104D01*
X1293161Y879372D01*
X1293020Y879513D01*
G37*
G36*
G01X1293203Y879132D02*
X1293385Y878748D01*
X1292855Y878218D01*
X1292471Y878400D01*
X1292330Y878541D01*
X1293062Y879273D01*
X1293203Y879132D01*
G37*
G36*
G01X1291358Y877852D02*
X1291176Y878235D01*
X1291706Y878766D01*
X1292090Y878583D01*
X1292231Y878442D01*
X1291499Y877710D01*
X1291358Y877852D01*
G37*
G36*
G01X1294681Y881175D02*
X1294499Y881559D01*
X1295029Y882089D01*
X1295413Y881907D01*
X1295554Y881765D01*
X1294823Y881034D01*
X1294681Y881175D01*
G37*
G36*
G01X1288838Y871067D02*
X1288438Y871209D01*
Y871959D01*
X1288838Y872101D01*
X1289038D01*
Y871067D01*
X1288838D01*
G37*
G36*
G01Y868717D02*
X1288438Y868859D01*
Y869609D01*
X1288838Y869751D01*
X1289038D01*
Y868717D01*
X1288838D01*
G37*
G36*
G01X1289238Y870927D02*
X1289638Y870784D01*
Y870034D01*
X1289238Y869891D01*
X1289038D01*
Y870927D01*
X1289238D01*
G37*
G36*
G01X1288838Y873417D02*
X1288438Y873559D01*
Y874309D01*
X1288838Y874451D01*
X1289038D01*
Y873417D01*
X1288838D01*
G37*
G36*
G01X1289238Y875627D02*
X1289638Y875484D01*
Y874734D01*
X1289238Y874591D01*
X1289038D01*
Y875627D01*
X1289238D01*
G37*
G36*
G01Y873277D02*
X1289638Y873134D01*
Y872384D01*
X1289238Y872241D01*
X1289038D01*
Y873277D01*
X1289238D01*
G37*
G36*
G01X1290693Y878319D02*
X1290875Y877935D01*
X1290344Y877405D01*
X1289961Y877587D01*
X1289819Y877728D01*
X1290551Y878460D01*
X1290693Y878319D01*
G37*
G36*
G01X1290509Y878701D02*
X1290327Y879084D01*
X1290857Y879615D01*
X1291241Y879432D01*
X1291382Y879291D01*
X1290650Y878559D01*
X1290509Y878701D01*
G37*
G36*
G01X1294016Y881642D02*
X1294198Y881259D01*
X1293668Y880728D01*
X1293284Y880910D01*
X1293143Y881052D01*
X1293875Y881784D01*
X1294016Y881642D01*
G37*
G36*
G01X1293832Y882024D02*
X1293650Y882408D01*
X1294180Y882938D01*
X1294564Y882756D01*
X1294705Y882614D01*
X1293974Y881883D01*
X1293832Y882024D01*
G37*
G36*
G01X1292171Y880362D02*
X1291988Y880746D01*
X1292519Y881276D01*
X1292902Y881094D01*
X1293044Y880953D01*
X1292312Y880221D01*
X1292171Y880362D01*
G37*
G36*
G01X1292354Y879981D02*
X1292536Y879597D01*
X1292006Y879067D01*
X1291622Y879249D01*
X1291481Y879390D01*
X1292213Y880122D01*
X1292354Y879981D01*
G37*
G36*
G01X1295158Y883933D02*
X1294758Y884076D01*
Y884826D01*
X1295158Y884969D01*
X1295358D01*
Y883933D01*
X1295158D01*
G37*
G36*
G01X1291238Y871067D02*
X1290838Y871209D01*
Y871959D01*
X1291238Y872101D01*
X1291438D01*
Y871067D01*
X1291238D01*
G37*
G36*
G01Y868717D02*
X1290838Y868859D01*
Y869609D01*
X1291238Y869751D01*
X1291438D01*
Y868717D01*
X1291238D01*
G37*
G36*
G01Y873417D02*
X1290838Y873559D01*
Y874309D01*
X1291238Y874451D01*
X1291438D01*
Y873417D01*
X1291238D01*
G37*
G36*
G01X1291638Y870927D02*
X1292038Y870784D01*
Y870034D01*
X1291638Y869891D01*
X1291438D01*
Y870927D01*
X1291638D01*
G37*
G36*
G01Y873277D02*
X1292038Y873134D01*
Y872384D01*
X1291638Y872241D01*
X1291438D01*
Y873277D01*
X1291638D01*
G37*
G36*
G01X1292207Y877003D02*
X1292025Y877386D01*
X1292555Y877917D01*
X1292939Y877734D01*
X1293080Y877593D01*
X1292348Y876861D01*
X1292207Y877003D01*
G37*
G36*
G01X1293869Y878664D02*
X1293686Y879048D01*
X1294217Y879578D01*
X1294600Y879396D01*
X1294742Y879255D01*
X1294010Y878523D01*
X1293869Y878664D01*
G37*
G36*
G01X1294052Y878283D02*
X1294234Y877899D01*
X1293704Y877369D01*
X1293320Y877551D01*
X1293179Y877692D01*
X1293911Y878424D01*
X1294052Y878283D01*
G37*
G36*
G01X1295714Y879944D02*
X1295896Y879561D01*
X1295366Y879030D01*
X1294982Y879212D01*
X1294841Y879354D01*
X1295573Y880086D01*
X1295714Y879944D01*
G37*
G36*
G01X1295530Y880326D02*
X1295348Y880710D01*
X1295878Y881240D01*
X1296262Y881058D01*
X1296403Y880916D01*
X1295672Y880185D01*
X1295530Y880326D01*
G37*
G36*
G01X1297376Y881606D02*
X1297558Y881222D01*
X1297028Y880692D01*
X1296644Y880874D01*
X1296502Y881015D01*
X1297234Y881747D01*
X1297376Y881606D01*
G37*
G36*
G01X1297558Y883933D02*
X1297158Y884076D01*
Y884826D01*
X1297558Y884969D01*
X1297758D01*
Y883933D01*
X1297558D01*
G37*
G36*
G01X1284837Y900072D02*
X1284655Y900456D01*
X1285186Y900986D01*
X1285569Y900804D01*
X1285711Y900663D01*
X1284979Y899931D01*
X1284837Y900072D01*
G37*
G36*
G01X1286683Y901352D02*
X1286865Y900968D01*
X1286335Y900438D01*
X1285951Y900620D01*
X1285810Y900762D01*
X1286541Y901493D01*
X1286683Y901352D01*
G37*
G36*
G01X1284758Y894827D02*
X1285158Y894684D01*
Y893934D01*
X1284758Y893791D01*
X1284558D01*
Y894827D01*
X1284758D01*
G37*
G36*
G01X1284358Y892617D02*
X1283958Y892759D01*
Y893509D01*
X1284358Y893651D01*
X1284558D01*
Y892617D01*
X1284358D01*
G37*
G36*
G01X1284758Y892477D02*
X1285158Y892334D01*
Y891584D01*
X1284758Y891441D01*
X1284558D01*
Y892477D01*
X1284758D01*
G37*
G36*
G01Y890127D02*
X1285158Y889984D01*
Y889234D01*
X1284758Y889091D01*
X1284558D01*
Y890127D01*
X1284758D01*
G37*
G36*
G01X1284358Y890267D02*
X1283958Y890409D01*
Y891159D01*
X1284358Y891301D01*
X1284558D01*
Y890267D01*
X1284358D01*
G37*
G36*
G01X1281722Y885193D02*
X1281539Y885577D01*
X1282070Y886107D01*
X1282453Y885925D01*
X1282595Y885784D01*
X1281863Y885052D01*
X1281722Y885193D01*
G37*
G36*
G01X1283567Y886473D02*
X1283749Y886090D01*
X1283219Y885559D01*
X1282835Y885741D01*
X1282694Y885883D01*
X1283426Y886615D01*
X1283567Y886473D01*
G37*
G36*
G01X1289197Y900527D02*
X1289379Y900143D01*
X1288848Y899613D01*
X1288465Y899795D01*
X1288323Y899936D01*
X1289055Y900668D01*
X1289197Y900527D01*
G37*
G36*
G01X1285873Y897204D02*
X1286055Y896820D01*
X1285525Y896290D01*
X1285141Y896472D01*
X1285000Y896613D01*
X1285732Y897345D01*
X1285873Y897204D01*
G37*
G36*
G01X1287535Y898865D02*
X1287717Y898482D01*
X1287187Y897951D01*
X1286803Y898133D01*
X1286662Y898275D01*
X1287394Y899007D01*
X1287535Y898865D01*
G37*
G36*
G01X1285689Y897585D02*
X1285507Y897969D01*
X1286038Y898499D01*
X1286421Y898317D01*
X1286563Y898176D01*
X1285831Y897444D01*
X1285689Y897585D01*
G37*
G36*
G01X1287351Y899247D02*
X1287169Y899631D01*
X1287699Y900161D01*
X1288083Y899979D01*
X1288224Y899837D01*
X1287493Y899106D01*
X1287351Y899247D01*
G37*
G36*
G01X1285081Y885157D02*
X1284899Y885541D01*
X1285429Y886071D01*
X1285813Y885889D01*
X1285954Y885747D01*
X1285223Y885016D01*
X1285081Y885157D01*
G37*
G36*
G01X1289233Y897167D02*
X1289415Y896784D01*
X1288885Y896253D01*
X1288501Y896435D01*
X1288360Y896577D01*
X1289092Y897309D01*
X1289233Y897167D01*
G37*
G36*
G01X1290895Y898829D02*
X1291077Y898445D01*
X1290546Y897915D01*
X1290163Y898097D01*
X1290021Y898238D01*
X1290753Y898970D01*
X1290895Y898829D01*
G37*
G36*
G01X1289049Y897549D02*
X1288867Y897933D01*
X1289397Y898463D01*
X1289781Y898281D01*
X1289922Y898139D01*
X1289191Y897408D01*
X1289049Y897549D01*
G37*
G36*
G01X1290711Y899211D02*
X1290529Y899594D01*
X1291059Y900125D01*
X1291443Y899943D01*
X1291584Y899801D01*
X1290852Y899069D01*
X1290711Y899211D01*
G37*
G36*
G01X1287387Y895887D02*
X1287205Y896271D01*
X1287736Y896801D01*
X1288119Y896619D01*
X1288261Y896478D01*
X1287529Y895746D01*
X1287387Y895887D01*
G37*
G36*
G01X1286758Y887917D02*
X1286358Y888059D01*
Y888809D01*
X1286758Y888951D01*
X1286958D01*
Y887917D01*
X1286758D01*
G37*
G36*
G01X1287158Y892477D02*
X1287558Y892334D01*
Y891584D01*
X1287158Y891441D01*
X1286958D01*
Y892477D01*
X1287158D01*
G37*
G36*
G01X1286758Y890267D02*
X1286358Y890409D01*
Y891159D01*
X1286758Y891301D01*
X1286958D01*
Y890267D01*
X1286758D01*
G37*
G36*
G01Y892617D02*
X1286358Y892759D01*
Y893509D01*
X1286758Y893651D01*
X1286958D01*
Y892617D01*
X1286758D01*
G37*
G36*
G01X1287158Y890127D02*
X1287558Y889984D01*
Y889234D01*
X1287158Y889091D01*
X1286958D01*
Y890127D01*
X1287158D01*
G37*
G36*
G01X1292556Y900491D02*
X1292739Y900107D01*
X1292208Y899577D01*
X1291825Y899759D01*
X1291683Y899900D01*
X1292415Y900632D01*
X1292556Y900491D01*
G37*
G36*
G01X1284416Y885624D02*
X1284598Y885241D01*
X1284068Y884710D01*
X1283684Y884892D01*
X1283543Y885034D01*
X1284275Y885766D01*
X1284416Y885624D01*
G37*
G36*
G01X1284232Y886006D02*
X1284050Y886390D01*
X1284580Y886920D01*
X1284964Y886738D01*
X1285105Y886596D01*
X1284374Y885865D01*
X1284232Y886006D01*
G37*
G36*
G01X1285558Y887917D02*
X1285158Y888059D01*
Y888809D01*
X1285558Y888951D01*
X1285758D01*
Y887917D01*
X1285558D01*
G37*
G36*
G01X1285958Y894827D02*
X1286358Y894684D01*
Y893934D01*
X1285958Y893791D01*
X1285758D01*
Y894827D01*
X1285958D01*
G37*
G36*
G01X1285558Y892617D02*
X1285158Y892759D01*
Y893509D01*
X1285558Y893651D01*
X1285758D01*
Y892617D01*
X1285558D01*
G37*
G36*
G01X1285958Y892477D02*
X1286358Y892334D01*
Y891584D01*
X1285958Y891441D01*
X1285758D01*
Y892477D01*
X1285958D01*
G37*
G36*
G01Y890127D02*
X1286358Y889984D01*
Y889234D01*
X1285958Y889091D01*
X1285758D01*
Y890127D01*
X1285958D01*
G37*
G36*
G01X1285558Y890267D02*
X1285158Y890409D01*
Y891159D01*
X1285558Y891301D01*
X1285758D01*
Y890267D01*
X1285558D01*
G37*
G36*
G01X1289862Y900060D02*
X1289680Y900443D01*
X1290210Y900974D01*
X1290594Y900792D01*
X1290735Y900650D01*
X1290003Y899918D01*
X1289862Y900060D01*
G37*
G36*
G01X1290046Y899678D02*
X1290228Y899294D01*
X1289697Y898764D01*
X1289314Y898946D01*
X1289172Y899087D01*
X1289904Y899819D01*
X1290046Y899678D01*
G37*
G36*
G01X1288384Y898016D02*
X1288566Y897633D01*
X1288036Y897102D01*
X1287652Y897284D01*
X1287511Y897426D01*
X1288243Y898158D01*
X1288384Y898016D01*
G37*
G36*
G01X1286538Y896736D02*
X1286356Y897120D01*
X1286887Y897650D01*
X1287270Y897468D01*
X1287412Y897327D01*
X1286680Y896595D01*
X1286538Y896736D01*
G37*
G36*
G01X1288200Y898398D02*
X1288018Y898782D01*
X1288548Y899312D01*
X1288932Y899130D01*
X1289073Y898988D01*
X1288342Y898257D01*
X1288200Y898398D01*
G37*
G36*
G01X1291707Y901340D02*
X1291890Y900956D01*
X1291359Y900426D01*
X1290976Y900608D01*
X1290834Y900749D01*
X1291566Y901481D01*
X1291707Y901340D01*
G37*
G36*
G01X1287776Y885588D02*
X1287958Y885204D01*
X1287428Y884674D01*
X1287044Y884856D01*
X1286902Y884997D01*
X1287634Y885729D01*
X1287776Y885588D01*
G37*
G36*
G01X1287958Y887917D02*
X1287558Y888059D01*
Y888809D01*
X1287958Y888951D01*
X1288158D01*
Y887917D01*
X1287958D01*
G37*
G36*
G01Y892617D02*
X1287558Y892759D01*
Y893509D01*
X1287958Y893651D01*
X1288158D01*
Y892617D01*
X1287958D01*
G37*
G36*
G01Y890267D02*
X1287558Y890409D01*
Y891159D01*
X1287958Y891301D01*
X1288158D01*
Y890267D01*
X1287958D01*
G37*
G36*
G01X1288358Y892477D02*
X1288758Y892334D01*
Y891584D01*
X1288358Y891441D01*
X1288158D01*
Y892477D01*
X1288358D01*
G37*
G36*
G01Y890127D02*
X1288758Y889984D01*
Y889234D01*
X1288358Y889091D01*
X1288158D01*
Y890127D01*
X1288358D01*
G37*
G36*
G01X1289898Y896700D02*
X1289716Y897084D01*
X1290246Y897614D01*
X1290630Y897432D01*
X1290771Y897290D01*
X1290040Y896559D01*
X1289898Y896700D01*
G37*
G36*
G01X1290082Y896318D02*
X1290264Y895935D01*
X1289734Y895404D01*
X1289350Y895586D01*
X1289209Y895728D01*
X1289941Y896460D01*
X1290082Y896318D01*
G37*
G36*
G01X1291744Y897980D02*
X1291926Y897596D01*
X1291395Y897066D01*
X1291012Y897248D01*
X1290870Y897389D01*
X1291602Y898121D01*
X1291744Y897980D01*
G37*
G36*
G01X1295067Y901303D02*
X1295249Y900920D01*
X1294719Y900389D01*
X1294335Y900571D01*
X1294194Y900713D01*
X1294926Y901445D01*
X1295067Y901303D01*
G37*
G36*
G01X1293222Y900023D02*
X1293040Y900407D01*
X1293570Y900937D01*
X1293953Y900755D01*
X1294095Y900614D01*
X1293363Y899882D01*
X1293222Y900023D01*
G37*
G36*
G01X1293405Y899642D02*
X1293588Y899258D01*
X1293057Y898728D01*
X1292674Y898910D01*
X1292532Y899051D01*
X1293264Y899783D01*
X1293405Y899642D01*
G37*
G36*
G01X1291560Y898362D02*
X1291378Y898745D01*
X1291908Y899276D01*
X1292292Y899094D01*
X1292433Y898952D01*
X1291701Y898220D01*
X1291560Y898362D01*
G37*
G36*
G01X1298414Y896160D02*
X1298596Y895776D01*
X1298065Y895246D01*
X1297682Y895428D01*
X1297540Y895569D01*
X1298272Y896301D01*
X1298414Y896160D01*
G37*
G36*
G01X1296752Y894498D02*
X1296934Y894114D01*
X1296404Y893584D01*
X1296020Y893766D01*
X1295879Y893908D01*
X1296611Y894640D01*
X1296752Y894498D01*
G37*
G36*
G01X1294906Y893218D02*
X1294724Y893602D01*
X1295255Y894132D01*
X1295638Y893950D01*
X1295780Y893809D01*
X1295048Y893077D01*
X1294906Y893218D01*
G37*
G36*
G01X1296568Y894880D02*
X1296386Y895264D01*
X1296916Y895794D01*
X1297300Y895612D01*
X1297441Y895470D01*
X1296710Y894739D01*
X1296568Y894880D01*
G37*
G36*
G01X1294358Y886143D02*
X1294758Y886001D01*
Y885251D01*
X1294358Y885109D01*
X1294158D01*
Y886143D01*
X1294358D01*
G37*
G36*
G01Y888493D02*
X1294758Y888351D01*
Y887601D01*
X1294358Y887459D01*
X1294158D01*
Y888493D01*
X1294358D01*
G37*
G36*
G01X1293958Y886283D02*
X1293558Y886426D01*
Y887176D01*
X1293958Y887319D01*
X1294158D01*
Y886283D01*
X1293958D01*
G37*
G36*
G01X1294358Y890843D02*
X1294758Y890701D01*
Y889951D01*
X1294358Y889809D01*
X1294158D01*
Y890843D01*
X1294358D01*
G37*
G36*
G01X1293958Y888633D02*
X1293558Y888776D01*
Y889526D01*
X1293958Y889669D01*
X1294158D01*
Y888633D01*
X1293958D01*
G37*
G36*
G01X1298450Y892800D02*
X1298633Y892416D01*
X1298102Y891886D01*
X1297719Y892068D01*
X1297577Y892209D01*
X1298309Y892941D01*
X1298450Y892800D01*
G37*
G36*
G01X1296758Y886143D02*
X1297158Y886001D01*
Y885251D01*
X1296758Y885109D01*
X1296558D01*
Y886143D01*
X1296758D01*
G37*
G36*
G01Y888493D02*
X1297158Y888351D01*
Y887601D01*
X1296758Y887459D01*
X1296558D01*
Y888493D01*
X1296758D01*
G37*
G36*
G01X1296358Y886283D02*
X1295958Y886426D01*
Y887176D01*
X1296358Y887319D01*
X1296558D01*
Y886283D01*
X1296358D01*
G37*
G36*
G01Y888633D02*
X1295958Y888776D01*
Y889526D01*
X1296358Y889669D01*
X1296558D01*
Y888633D01*
X1296358D01*
G37*
G36*
G01X1295558Y886143D02*
X1295958Y886001D01*
Y885251D01*
X1295558Y885109D01*
X1295358D01*
Y886143D01*
X1295558D01*
G37*
G36*
G01Y888493D02*
X1295958Y888351D01*
Y887601D01*
X1295558Y887459D01*
X1295358D01*
Y888493D01*
X1295558D01*
G37*
G36*
G01X1295158Y886283D02*
X1294758Y886426D01*
Y887176D01*
X1295158Y887319D01*
X1295358D01*
Y886283D01*
X1295158D01*
G37*
G36*
G01X1295558Y890843D02*
X1295958Y890701D01*
Y889951D01*
X1295558Y889809D01*
X1295358D01*
Y890843D01*
X1295558D01*
G37*
G36*
G01X1295158Y888633D02*
X1294758Y888776D01*
Y889526D01*
X1295158Y889669D01*
X1295358D01*
Y888633D01*
X1295158D01*
G37*
G36*
G01X1297418Y894030D02*
X1297236Y894414D01*
X1297766Y894944D01*
X1298149Y894762D01*
X1298291Y894621D01*
X1297559Y893889D01*
X1297418Y894030D01*
G37*
G36*
G01X1297601Y893649D02*
X1297784Y893265D01*
X1297253Y892735D01*
X1296870Y892917D01*
X1296728Y893058D01*
X1297460Y893790D01*
X1297601Y893649D01*
G37*
G36*
G01X1295756Y892369D02*
X1295574Y892752D01*
X1296104Y893283D01*
X1296488Y893101D01*
X1296629Y892959D01*
X1295897Y892227D01*
X1295756Y892369D01*
G37*
G36*
G01X1297558Y886283D02*
X1297158Y886426D01*
Y887176D01*
X1297558Y887319D01*
X1297758D01*
Y886283D01*
X1297558D01*
G37*
G36*
G01Y888633D02*
X1297158Y888776D01*
Y889526D01*
X1297558Y889669D01*
X1297758D01*
Y888633D01*
X1297558D01*
G37*
G36*
G01X1284799Y916450D02*
X1284981Y916066D01*
X1284451Y915536D01*
X1284067Y915718D01*
X1283926Y915859D01*
X1284658Y916591D01*
X1284799Y916450D01*
G37*
G36*
G01X1284615Y916831D02*
X1284433Y917215D01*
X1284964Y917745D01*
X1285347Y917563D01*
X1285489Y917422D01*
X1284757Y916690D01*
X1284615Y916831D01*
G37*
G36*
G01X1284652Y913472D02*
X1284470Y913855D01*
X1285000Y914386D01*
X1285384Y914203D01*
X1285525Y914062D01*
X1284793Y913330D01*
X1284652Y913472D01*
G37*
G36*
G01X1284836Y913090D02*
X1285018Y912706D01*
X1284487Y912176D01*
X1284104Y912358D01*
X1283962Y912499D01*
X1284694Y913231D01*
X1284836Y913090D01*
G37*
G36*
G01X1287975Y916795D02*
X1287793Y917179D01*
X1288323Y917709D01*
X1288707Y917527D01*
X1288848Y917385D01*
X1288117Y916654D01*
X1287975Y916795D01*
G37*
G36*
G01X1288159Y916413D02*
X1288341Y916030D01*
X1287811Y915499D01*
X1287427Y915681D01*
X1287286Y915823D01*
X1288018Y916555D01*
X1288159Y916413D01*
G37*
G36*
G01X1286313Y915133D02*
X1286131Y915517D01*
X1286662Y916047D01*
X1287045Y915865D01*
X1287187Y915724D01*
X1286455Y914992D01*
X1286313Y915133D01*
G37*
G36*
G01X1286497Y914752D02*
X1286679Y914368D01*
X1286149Y913838D01*
X1285765Y914020D01*
X1285624Y914161D01*
X1286356Y914893D01*
X1286497Y914752D01*
G37*
G36*
G01X1284135Y903900D02*
X1284317Y903516D01*
X1283787Y902986D01*
X1283404Y903168D01*
X1283262Y903309D01*
X1283994Y904041D01*
X1284135Y903900D01*
G37*
G36*
G01X1283952Y904281D02*
X1283769Y904665D01*
X1284300Y905195D01*
X1284683Y905013D01*
X1284825Y904872D01*
X1284093Y904140D01*
X1283952Y904281D01*
G37*
G36*
G01X1289120Y908885D02*
X1289303Y908501D01*
X1288772Y907971D01*
X1288389Y908153D01*
X1288247Y908294D01*
X1288979Y909026D01*
X1289120Y908885D01*
G37*
G36*
G01X1290782Y910546D02*
X1290964Y910163D01*
X1290434Y909632D01*
X1290050Y909815D01*
X1289909Y909956D01*
X1290641Y910688D01*
X1290782Y910546D01*
G37*
G36*
G01X1288937Y909266D02*
X1288755Y909650D01*
X1289285Y910180D01*
X1289669Y909998D01*
X1289810Y909857D01*
X1289078Y909125D01*
X1288937Y909266D01*
G37*
G36*
G01X1290598Y910928D02*
X1290416Y911312D01*
X1290947Y911842D01*
X1291330Y911660D01*
X1291472Y911519D01*
X1290740Y910787D01*
X1290598Y910928D01*
G37*
G36*
G01X1287275Y907605D02*
X1287093Y907988D01*
X1287623Y908519D01*
X1288007Y908337D01*
X1288148Y908195D01*
X1287416Y907463D01*
X1287275Y907605D01*
G37*
G36*
G01X1285797Y905561D02*
X1285979Y905178D01*
X1285449Y904647D01*
X1285065Y904829D01*
X1284924Y904971D01*
X1285656Y905703D01*
X1285797Y905561D01*
G37*
G36*
G01X1287459Y907223D02*
X1287641Y906839D01*
X1287111Y906309D01*
X1286727Y906491D01*
X1286586Y906633D01*
X1287317Y907364D01*
X1287459Y907223D01*
G37*
G36*
G01X1285613Y905943D02*
X1285431Y906327D01*
X1285961Y906857D01*
X1286345Y906675D01*
X1286487Y906534D01*
X1285755Y905802D01*
X1285613Y905943D01*
G37*
G36*
G01X1294106Y913870D02*
X1294288Y913486D01*
X1293757Y912956D01*
X1293374Y913138D01*
X1293232Y913279D01*
X1293964Y914011D01*
X1294106Y913870D01*
G37*
G36*
G01X1293922Y914252D02*
X1293740Y914635D01*
X1294270Y915166D01*
X1294654Y914983D01*
X1294795Y914842D01*
X1294063Y914110D01*
X1293922Y914252D01*
G37*
G36*
G01X1292260Y912590D02*
X1292078Y912974D01*
X1292608Y913504D01*
X1292992Y913322D01*
X1293133Y913180D01*
X1292401Y912448D01*
X1292260Y912590D01*
G37*
G36*
G01X1292444Y912208D02*
X1292626Y911824D01*
X1292096Y911294D01*
X1291712Y911476D01*
X1291571Y911618D01*
X1292302Y912349D01*
X1292444Y912208D01*
G37*
G36*
G01X1297429Y917193D02*
X1297611Y916810D01*
X1297081Y916279D01*
X1296697Y916461D01*
X1296556Y916603D01*
X1297288Y917335D01*
X1297429Y917193D01*
G37*
G36*
G01X1295583Y915913D02*
X1295401Y916297D01*
X1295932Y916827D01*
X1296315Y916645D01*
X1296457Y916504D01*
X1295725Y915772D01*
X1295583Y915913D01*
G37*
G36*
G01X1295767Y915531D02*
X1295949Y915148D01*
X1295419Y914618D01*
X1295035Y914800D01*
X1294894Y914941D01*
X1295626Y915673D01*
X1295767Y915531D01*
G37*
G36*
G01X1285834Y902201D02*
X1286016Y901817D01*
X1285486Y901287D01*
X1285102Y901469D01*
X1284961Y901611D01*
X1285692Y902342D01*
X1285834Y902201D01*
G37*
G36*
G01X1285650Y902583D02*
X1285468Y902966D01*
X1285998Y903497D01*
X1286382Y903315D01*
X1286523Y903173D01*
X1285791Y902441D01*
X1285650Y902583D01*
G37*
G36*
G01X1290635Y907568D02*
X1290453Y907952D01*
X1290983Y908482D01*
X1291367Y908300D01*
X1291508Y908158D01*
X1290777Y907427D01*
X1290635Y907568D01*
G37*
G36*
G01X1288973Y905906D02*
X1288791Y906290D01*
X1289322Y906820D01*
X1289705Y906638D01*
X1289847Y906497D01*
X1289115Y905765D01*
X1288973Y905906D01*
G37*
G36*
G01X1290819Y907186D02*
X1291001Y906803D01*
X1290471Y906272D01*
X1290087Y906454D01*
X1289946Y906596D01*
X1290678Y907328D01*
X1290819Y907186D01*
G37*
G36*
G01X1289157Y905524D02*
X1289339Y905141D01*
X1288809Y904611D01*
X1288425Y904793D01*
X1288284Y904934D01*
X1289016Y905666D01*
X1289157Y905524D01*
G37*
G36*
G01X1287312Y904245D02*
X1287130Y904628D01*
X1287660Y905159D01*
X1288044Y904976D01*
X1288185Y904835D01*
X1287453Y904103D01*
X1287312Y904245D01*
G37*
G36*
G01X1287496Y903863D02*
X1287678Y903479D01*
X1287147Y902949D01*
X1286764Y903131D01*
X1286622Y903272D01*
X1287354Y904004D01*
X1287496Y903863D01*
G37*
G36*
G01X1293959Y910891D02*
X1293776Y911275D01*
X1294307Y911805D01*
X1294690Y911623D01*
X1294832Y911482D01*
X1294100Y910750D01*
X1293959Y910891D01*
G37*
G36*
G01X1292297Y909230D02*
X1292115Y909613D01*
X1292645Y910144D01*
X1293029Y909962D01*
X1293170Y909820D01*
X1292438Y909088D01*
X1292297Y909230D01*
G37*
G36*
G01X1294142Y910510D02*
X1294324Y910126D01*
X1293794Y909596D01*
X1293411Y909778D01*
X1293269Y909919D01*
X1294001Y910651D01*
X1294142Y910510D01*
G37*
G36*
G01X1292481Y908848D02*
X1292663Y908464D01*
X1292132Y907934D01*
X1291749Y908116D01*
X1291607Y908257D01*
X1292339Y908989D01*
X1292481Y908848D01*
G37*
G36*
G01X1297282Y914215D02*
X1297100Y914598D01*
X1297630Y915129D01*
X1298014Y914947D01*
X1298155Y914805D01*
X1297423Y914073D01*
X1297282Y914215D01*
G37*
G36*
G01X1295620Y912553D02*
X1295438Y912937D01*
X1295969Y913467D01*
X1296352Y913285D01*
X1296494Y913144D01*
X1295762Y912412D01*
X1295620Y912553D01*
G37*
G36*
G01X1297466Y913833D02*
X1297648Y913449D01*
X1297118Y912919D01*
X1296734Y913101D01*
X1296593Y913243D01*
X1297324Y913974D01*
X1297466Y913833D01*
G37*
G36*
G01X1295804Y912171D02*
X1295986Y911788D01*
X1295456Y911257D01*
X1295072Y911439D01*
X1294931Y911581D01*
X1295663Y912313D01*
X1295804Y912171D01*
G37*
G36*
G01X1284985Y903050D02*
X1285167Y902666D01*
X1284637Y902136D01*
X1284253Y902318D01*
X1284112Y902460D01*
X1284843Y903191D01*
X1284985Y903050D01*
G37*
G36*
G01X1284801Y903432D02*
X1284619Y903815D01*
X1285149Y904346D01*
X1285533Y904164D01*
X1285674Y904022D01*
X1284942Y903290D01*
X1284801Y903432D01*
G37*
G36*
G01X1286463Y905094D02*
X1286281Y905477D01*
X1286811Y906008D01*
X1287195Y905825D01*
X1287336Y905684D01*
X1286604Y904952D01*
X1286463Y905094D01*
G37*
G36*
G01X1288124Y906755D02*
X1287942Y907139D01*
X1288473Y907669D01*
X1288856Y907487D01*
X1288998Y907346D01*
X1288266Y906614D01*
X1288124Y906755D01*
G37*
G36*
G01X1286647Y904712D02*
X1286829Y904328D01*
X1286298Y903798D01*
X1285915Y903980D01*
X1285773Y904121D01*
X1286505Y904853D01*
X1286647Y904712D01*
G37*
G36*
G01X1288308Y906373D02*
X1288490Y905990D01*
X1287960Y905460D01*
X1287576Y905642D01*
X1287435Y905783D01*
X1288167Y906515D01*
X1288308Y906373D01*
G37*
G36*
G01X1289786Y908417D02*
X1289604Y908801D01*
X1290134Y909331D01*
X1290518Y909149D01*
X1290659Y909007D01*
X1289928Y908276D01*
X1289786Y908417D01*
G37*
G36*
G01X1291632Y909697D02*
X1291814Y909313D01*
X1291283Y908783D01*
X1290900Y908965D01*
X1290758Y909106D01*
X1291490Y909838D01*
X1291632Y909697D01*
G37*
G36*
G01X1289970Y908035D02*
X1290152Y907652D01*
X1289622Y907121D01*
X1289238Y907303D01*
X1289097Y907445D01*
X1289829Y908177D01*
X1289970Y908035D01*
G37*
G36*
G01X1293110Y911740D02*
X1292927Y912124D01*
X1293458Y912654D01*
X1293841Y912472D01*
X1293983Y912331D01*
X1293251Y911599D01*
X1293110Y911740D01*
G37*
G36*
G01X1294955Y913020D02*
X1295137Y912637D01*
X1294607Y912106D01*
X1294223Y912288D01*
X1294082Y912430D01*
X1294814Y913162D01*
X1294955Y913020D01*
G37*
G36*
G01X1293293Y911359D02*
X1293475Y910975D01*
X1292945Y910445D01*
X1292562Y910627D01*
X1292420Y910768D01*
X1293152Y911500D01*
X1293293Y911359D01*
G37*
G36*
G01X1291448Y910079D02*
X1291266Y910462D01*
X1291796Y910993D01*
X1292180Y910811D01*
X1292321Y910669D01*
X1291589Y909937D01*
X1291448Y910079D01*
G37*
G36*
G01X1294771Y913402D02*
X1294589Y913786D01*
X1295120Y914316D01*
X1295503Y914134D01*
X1295645Y913993D01*
X1294913Y913261D01*
X1294771Y913402D01*
G37*
G36*
G01X1298279Y916344D02*
X1298461Y915960D01*
X1297930Y915430D01*
X1297547Y915612D01*
X1297405Y915753D01*
X1298137Y916485D01*
X1298279Y916344D01*
G37*
G36*
G01X1296433Y915064D02*
X1296251Y915447D01*
X1296781Y915978D01*
X1297165Y915796D01*
X1297306Y915654D01*
X1296574Y914922D01*
X1296433Y915064D01*
G37*
G36*
G01X1296617Y914682D02*
X1296799Y914298D01*
X1296269Y913768D01*
X1295885Y913950D01*
X1295744Y914092D01*
X1296475Y914823D01*
X1296617Y914682D01*
G37*
G36*
G01X1286499Y901734D02*
X1286317Y902117D01*
X1286847Y902648D01*
X1287231Y902466D01*
X1287372Y902324D01*
X1286640Y901592D01*
X1286499Y901734D01*
G37*
G36*
G01X1288345Y903014D02*
X1288527Y902630D01*
X1287996Y902100D01*
X1287613Y902282D01*
X1287471Y902423D01*
X1288203Y903155D01*
X1288345Y903014D01*
G37*
G36*
G01X1289822Y905057D02*
X1289640Y905441D01*
X1290171Y905971D01*
X1290554Y905789D01*
X1290696Y905648D01*
X1289964Y904916D01*
X1289822Y905057D01*
G37*
G36*
G01X1291668Y906337D02*
X1291850Y905954D01*
X1291320Y905423D01*
X1290936Y905605D01*
X1290795Y905747D01*
X1291527Y906479D01*
X1291668Y906337D01*
G37*
G36*
G01X1290006Y904675D02*
X1290188Y904292D01*
X1289658Y903762D01*
X1289274Y903944D01*
X1289133Y904085D01*
X1289865Y904817D01*
X1290006Y904675D01*
G37*
G36*
G01X1288161Y903396D02*
X1287979Y903779D01*
X1288509Y904310D01*
X1288893Y904127D01*
X1289034Y903986D01*
X1288302Y903254D01*
X1288161Y903396D01*
G37*
G36*
G01X1294991Y909661D02*
X1295173Y909277D01*
X1294643Y908747D01*
X1294260Y908929D01*
X1294118Y909070D01*
X1294850Y909802D01*
X1294991Y909661D01*
G37*
G36*
G01X1293330Y907999D02*
X1293512Y907615D01*
X1292981Y907085D01*
X1292598Y907267D01*
X1292456Y907408D01*
X1293188Y908140D01*
X1293330Y907999D01*
G37*
G36*
G01X1291484Y906719D02*
X1291302Y907103D01*
X1291832Y907633D01*
X1292216Y907451D01*
X1292357Y907309D01*
X1291626Y906578D01*
X1291484Y906719D01*
G37*
G36*
G01X1293146Y908381D02*
X1292964Y908764D01*
X1293494Y909295D01*
X1293878Y909113D01*
X1294019Y908971D01*
X1293287Y908239D01*
X1293146Y908381D01*
G37*
G36*
G01X1294808Y910042D02*
X1294625Y910426D01*
X1295156Y910956D01*
X1295539Y910774D01*
X1295681Y910633D01*
X1294949Y909901D01*
X1294808Y910042D01*
G37*
G36*
G01X1298315Y912984D02*
X1298497Y912600D01*
X1297967Y912070D01*
X1297583Y912252D01*
X1297442Y912394D01*
X1298173Y913125D01*
X1298315Y912984D01*
G37*
G36*
G01X1296469Y911704D02*
X1296287Y912088D01*
X1296818Y912618D01*
X1297201Y912436D01*
X1297343Y912295D01*
X1296611Y911563D01*
X1296469Y911704D01*
G37*
G36*
G01X1296653Y911322D02*
X1296835Y910939D01*
X1296305Y910408D01*
X1295921Y910590D01*
X1295780Y910732D01*
X1296512Y911464D01*
X1296653Y911322D01*
G37*
G36*
G01X1290858Y902189D02*
X1291041Y901805D01*
X1290510Y901275D01*
X1290127Y901457D01*
X1289985Y901598D01*
X1290717Y902330D01*
X1290858Y902189D01*
G37*
G36*
G01X1289013Y900909D02*
X1288831Y901292D01*
X1289361Y901823D01*
X1289745Y901641D01*
X1289886Y901499D01*
X1289154Y900767D01*
X1289013Y900909D01*
G37*
G36*
G01X1290675Y902570D02*
X1290493Y902954D01*
X1291023Y903484D01*
X1291406Y903302D01*
X1291548Y903161D01*
X1290816Y902429D01*
X1290675Y902570D01*
G37*
G36*
G01X1292520Y903850D02*
X1292702Y903467D01*
X1292172Y902936D01*
X1291788Y903118D01*
X1291647Y903260D01*
X1292379Y903992D01*
X1292520Y903850D01*
G37*
G36*
G01X1294182Y905512D02*
X1294364Y905128D01*
X1293834Y904598D01*
X1293450Y904780D01*
X1293309Y904922D01*
X1294040Y905653D01*
X1294182Y905512D01*
G37*
G36*
G01X1293998Y905894D02*
X1293816Y906277D01*
X1294346Y906808D01*
X1294730Y906626D01*
X1294871Y906484D01*
X1294139Y905752D01*
X1293998Y905894D01*
G37*
G36*
G01X1292336Y904232D02*
X1292154Y904616D01*
X1292685Y905146D01*
X1293068Y904964D01*
X1293210Y904823D01*
X1292478Y904091D01*
X1292336Y904232D01*
G37*
G36*
G01X1297321Y909217D02*
X1297139Y909601D01*
X1297670Y910131D01*
X1298053Y909949D01*
X1298195Y909808D01*
X1297463Y909076D01*
X1297321Y909217D01*
G37*
G36*
G01X1297505Y908835D02*
X1297687Y908452D01*
X1297157Y907921D01*
X1296773Y908104D01*
X1296632Y908245D01*
X1297364Y908977D01*
X1297505Y908835D01*
G37*
G36*
G01X1295660Y907556D02*
X1295478Y907939D01*
X1296008Y908469D01*
X1296392Y908287D01*
X1296533Y908146D01*
X1295801Y907414D01*
X1295660Y907556D01*
G37*
G36*
G01X1295844Y907174D02*
X1296026Y906790D01*
X1295495Y906260D01*
X1295112Y906442D01*
X1294970Y906583D01*
X1295702Y907315D01*
X1295844Y907174D01*
G37*
G36*
G01X1294218Y902152D02*
X1294400Y901769D01*
X1293870Y901238D01*
X1293486Y901420D01*
X1293345Y901562D01*
X1294077Y902294D01*
X1294218Y902152D01*
G37*
G36*
G01X1292373Y900872D02*
X1292191Y901256D01*
X1292721Y901786D01*
X1293104Y901604D01*
X1293246Y901463D01*
X1292514Y900731D01*
X1292373Y900872D01*
G37*
G36*
G01X1294034Y902534D02*
X1293852Y902918D01*
X1294383Y903448D01*
X1294766Y903266D01*
X1294908Y903125D01*
X1294176Y902393D01*
X1294034Y902534D01*
G37*
G36*
G01X1297358Y905858D02*
X1297176Y906241D01*
X1297706Y906771D01*
X1298090Y906589D01*
X1298231Y906448D01*
X1297499Y905716D01*
X1297358Y905858D01*
G37*
G36*
G01X1295880Y903814D02*
X1296062Y903430D01*
X1295532Y902900D01*
X1295148Y903082D01*
X1295007Y903224D01*
X1295738Y903955D01*
X1295880Y903814D01*
G37*
G36*
G01X1297542Y905476D02*
X1297724Y905092D01*
X1297193Y904562D01*
X1296810Y904744D01*
X1296668Y904885D01*
X1297400Y905617D01*
X1297542Y905476D01*
G37*
G36*
G01X1295696Y904196D02*
X1295514Y904579D01*
X1296044Y905110D01*
X1296428Y904928D01*
X1296569Y904786D01*
X1295837Y904054D01*
X1295696Y904196D01*
G37*
G36*
G01X1291524Y901721D02*
X1291342Y902105D01*
X1291872Y902635D01*
X1292255Y902453D01*
X1292397Y902312D01*
X1291665Y901580D01*
X1291524Y901721D01*
G37*
G36*
G01X1293369Y903001D02*
X1293551Y902618D01*
X1293021Y902087D01*
X1292637Y902269D01*
X1292496Y902411D01*
X1293228Y903143D01*
X1293369Y903001D01*
G37*
G36*
G01X1295031Y904663D02*
X1295213Y904279D01*
X1294683Y903749D01*
X1294299Y903931D01*
X1294158Y904073D01*
X1294889Y904804D01*
X1295031Y904663D01*
G37*
G36*
G01X1293185Y903383D02*
X1293003Y903767D01*
X1293534Y904297D01*
X1293917Y904115D01*
X1294059Y903974D01*
X1293327Y903242D01*
X1293185Y903383D01*
G37*
G36*
G01X1298354Y907986D02*
X1298536Y907603D01*
X1298006Y907072D01*
X1297622Y907255D01*
X1297481Y907396D01*
X1298213Y908128D01*
X1298354Y907986D01*
G37*
G36*
G01X1296693Y906325D02*
X1296875Y905941D01*
X1296344Y905411D01*
X1295961Y905593D01*
X1295819Y905734D01*
X1296551Y906466D01*
X1296693Y906325D01*
G37*
G36*
G01X1296509Y906707D02*
X1296327Y907090D01*
X1296857Y907620D01*
X1297241Y907438D01*
X1297382Y907297D01*
X1296650Y906565D01*
X1296509Y906707D01*
G37*
G36*
G01X1294847Y905045D02*
X1294665Y905428D01*
X1295195Y905959D01*
X1295579Y905777D01*
X1295720Y905635D01*
X1294988Y904903D01*
X1294847Y905045D01*
G37*
G36*
G01X1298391Y904627D02*
X1298573Y904243D01*
X1298042Y903713D01*
X1297659Y903895D01*
X1297517Y904036D01*
X1298249Y904768D01*
X1298391Y904627D01*
G37*
G36*
G01X1296545Y903347D02*
X1296363Y903730D01*
X1296893Y904261D01*
X1297277Y904079D01*
X1297418Y903937D01*
X1296686Y903205D01*
X1296545Y903347D01*
G37*
G36*
G01X1294883Y901685D02*
X1294701Y902069D01*
X1295232Y902599D01*
X1295615Y902417D01*
X1295757Y902276D01*
X1295025Y901544D01*
X1294883Y901685D01*
G37*
G36*
G01X1296729Y902965D02*
X1296911Y902581D01*
X1296381Y902051D01*
X1295997Y902233D01*
X1295856Y902375D01*
X1296587Y903106D01*
X1296729Y902965D01*
G37*
G36*
G01X1283803Y914321D02*
X1283621Y914704D01*
X1284151Y915235D01*
X1284535Y915052D01*
X1284676Y914911D01*
X1283944Y914179D01*
X1283803Y914321D01*
G37*
G36*
G01X1283987Y913939D02*
X1284169Y913555D01*
X1283638Y913025D01*
X1283255Y913207D01*
X1283113Y913348D01*
X1283845Y914080D01*
X1283987Y913939D01*
G37*
G36*
G01X1285648Y915601D02*
X1285830Y915217D01*
X1285300Y914687D01*
X1284916Y914869D01*
X1284775Y915010D01*
X1285507Y915742D01*
X1285648Y915601D01*
G37*
G36*
G01X1285464Y915982D02*
X1285282Y916366D01*
X1285813Y916896D01*
X1286196Y916714D01*
X1286338Y916573D01*
X1285606Y915841D01*
X1285464Y915982D01*
G37*
G36*
G01X1287310Y917262D02*
X1287492Y916879D01*
X1286962Y916348D01*
X1286578Y916530D01*
X1286437Y916672D01*
X1287169Y917404D01*
X1287310Y917262D01*
G37*
G36*
G01X1286461Y918111D02*
X1286643Y917728D01*
X1286113Y917197D01*
X1285729Y917379D01*
X1285588Y917521D01*
X1286320Y918253D01*
X1286461Y918111D01*
G37*
G36*
G01X1286277Y918493D02*
X1286095Y918877D01*
X1286625Y919407D01*
X1287009Y919225D01*
X1287150Y919083D01*
X1286419Y918352D01*
X1286277Y918493D01*
G37*
G36*
G01X1291446Y923096D02*
X1291628Y922713D01*
X1291098Y922182D01*
X1290714Y922364D01*
X1290573Y922506D01*
X1291305Y923238D01*
X1291446Y923096D01*
G37*
G36*
G01X1289784Y921435D02*
X1289967Y921051D01*
X1289436Y920521D01*
X1289053Y920703D01*
X1288911Y920844D01*
X1289643Y921576D01*
X1289784Y921435D01*
G37*
G36*
G01X1289601Y921816D02*
X1289419Y922200D01*
X1289949Y922730D01*
X1290332Y922548D01*
X1290474Y922407D01*
X1289742Y921675D01*
X1289601Y921816D01*
G37*
G36*
G01X1288123Y919773D02*
X1288305Y919389D01*
X1287774Y918859D01*
X1287391Y919041D01*
X1287249Y919182D01*
X1287981Y919914D01*
X1288123Y919773D01*
G37*
G36*
G01X1287939Y920155D02*
X1287757Y920538D01*
X1288287Y921069D01*
X1288671Y920887D01*
X1288812Y920745D01*
X1288080Y920013D01*
X1287939Y920155D01*
G37*
G36*
G01X1294770Y926420D02*
X1294952Y926036D01*
X1294421Y925506D01*
X1294038Y925688D01*
X1293896Y925829D01*
X1294628Y926561D01*
X1294770Y926420D01*
G37*
G36*
G01X1292924Y925140D02*
X1292742Y925523D01*
X1293272Y926054D01*
X1293656Y925872D01*
X1293797Y925730D01*
X1293065Y924998D01*
X1292924Y925140D01*
G37*
G36*
G01X1293108Y924758D02*
X1293290Y924374D01*
X1292760Y923844D01*
X1292376Y924026D01*
X1292235Y924168D01*
X1292966Y924899D01*
X1293108Y924758D01*
G37*
G36*
G01X1291262Y923478D02*
X1291080Y923862D01*
X1291611Y924392D01*
X1291994Y924210D01*
X1292136Y924069D01*
X1291404Y923337D01*
X1291262Y923478D01*
G37*
G36*
G01X1296247Y928463D02*
X1296065Y928847D01*
X1296596Y929377D01*
X1296979Y929195D01*
X1297121Y929054D01*
X1296389Y928322D01*
X1296247Y928463D01*
G37*
G36*
G01X1294586Y926802D02*
X1294404Y927185D01*
X1294934Y927715D01*
X1295318Y927533D01*
X1295459Y927392D01*
X1294727Y926660D01*
X1294586Y926802D01*
G37*
G36*
G01X1296431Y928081D02*
X1296613Y927698D01*
X1296083Y927167D01*
X1295699Y927350D01*
X1295558Y927491D01*
X1296290Y928223D01*
X1296431Y928081D01*
G37*
G36*
G01X1298093Y929743D02*
X1298275Y929360D01*
X1297745Y928829D01*
X1297361Y929011D01*
X1297220Y929153D01*
X1297952Y929885D01*
X1298093Y929743D01*
G37*
G36*
G01X1289821Y918075D02*
X1290003Y917691D01*
X1289472Y917161D01*
X1289089Y917343D01*
X1288947Y917484D01*
X1289679Y918216D01*
X1289821Y918075D01*
G37*
G36*
G01X1289637Y918457D02*
X1289455Y918840D01*
X1289985Y919371D01*
X1290369Y919189D01*
X1290510Y919047D01*
X1289778Y918315D01*
X1289637Y918457D01*
G37*
G36*
G01X1291482Y919737D02*
X1291665Y919353D01*
X1291134Y918823D01*
X1290751Y919005D01*
X1290609Y919146D01*
X1291341Y919878D01*
X1291482Y919737D01*
G37*
G36*
G01X1292960Y921780D02*
X1292778Y922164D01*
X1293309Y922694D01*
X1293692Y922512D01*
X1293834Y922371D01*
X1293102Y921639D01*
X1292960Y921780D01*
G37*
G36*
G01X1294806Y923060D02*
X1294988Y922676D01*
X1294458Y922146D01*
X1294074Y922328D01*
X1293933Y922470D01*
X1294664Y923201D01*
X1294806Y923060D01*
G37*
G36*
G01X1293144Y921398D02*
X1293326Y921015D01*
X1292796Y920484D01*
X1292412Y920666D01*
X1292271Y920808D01*
X1293003Y921540D01*
X1293144Y921398D01*
G37*
G36*
G01X1291299Y920118D02*
X1291117Y920502D01*
X1291647Y921032D01*
X1292030Y920850D01*
X1292172Y920709D01*
X1291440Y919977D01*
X1291299Y920118D01*
G37*
G36*
G01X1294622Y923442D02*
X1294440Y923825D01*
X1294970Y924356D01*
X1295354Y924174D01*
X1295495Y924032D01*
X1294763Y923300D01*
X1294622Y923442D01*
G37*
G36*
G01X1298129Y926383D02*
X1298311Y926000D01*
X1297781Y925469D01*
X1297397Y925652D01*
X1297256Y925793D01*
X1297988Y926525D01*
X1298129Y926383D01*
G37*
G36*
G01X1296284Y925104D02*
X1296102Y925487D01*
X1296632Y926017D01*
X1297016Y925835D01*
X1297157Y925694D01*
X1296425Y924962D01*
X1296284Y925104D01*
G37*
G36*
G01X1296468Y924722D02*
X1296650Y924338D01*
X1296119Y923808D01*
X1295736Y923990D01*
X1295594Y924131D01*
X1296326Y924863D01*
X1296468Y924722D01*
G37*
G36*
G01X1297245Y917575D02*
X1297063Y917959D01*
X1297593Y918489D01*
X1297977Y918307D01*
X1298118Y918165D01*
X1297387Y917434D01*
X1297245Y917575D01*
G37*
G36*
G01X1285612Y918960D02*
X1285794Y918577D01*
X1285264Y918046D01*
X1284880Y918228D01*
X1284739Y918370D01*
X1285471Y919102D01*
X1285612Y918960D01*
G37*
G36*
G01X1290597Y923945D02*
X1290779Y923562D01*
X1290249Y923031D01*
X1289865Y923213D01*
X1289724Y923355D01*
X1290456Y924087D01*
X1290597Y923945D01*
G37*
G36*
G01X1290413Y924327D02*
X1290231Y924711D01*
X1290762Y925241D01*
X1291145Y925059D01*
X1291287Y924918D01*
X1290555Y924186D01*
X1290413Y924327D01*
G37*
G36*
G01X1288752Y922665D02*
X1288570Y923049D01*
X1289100Y923579D01*
X1289483Y923397D01*
X1289625Y923256D01*
X1288893Y922524D01*
X1288752Y922665D01*
G37*
G36*
G01X1287274Y920622D02*
X1287456Y920238D01*
X1286925Y919708D01*
X1286542Y919890D01*
X1286400Y920031D01*
X1287132Y920763D01*
X1287274Y920622D01*
G37*
G36*
G01X1288935Y922284D02*
X1289118Y921900D01*
X1288587Y921370D01*
X1288204Y921552D01*
X1288062Y921693D01*
X1288794Y922425D01*
X1288935Y922284D01*
G37*
G36*
G01X1285428Y919342D02*
X1285246Y919726D01*
X1285776Y920256D01*
X1286160Y920074D01*
X1286301Y919932D01*
X1285570Y919201D01*
X1285428Y919342D01*
G37*
G36*
G01X1287090Y921004D02*
X1286908Y921387D01*
X1287438Y921918D01*
X1287822Y921736D01*
X1287963Y921594D01*
X1287231Y920862D01*
X1287090Y921004D01*
G37*
G36*
G01X1293921Y927269D02*
X1294103Y926885D01*
X1293572Y926355D01*
X1293189Y926537D01*
X1293047Y926678D01*
X1293779Y927410D01*
X1293921Y927269D01*
G37*
G36*
G01X1293737Y927651D02*
X1293555Y928034D01*
X1294085Y928564D01*
X1294469Y928382D01*
X1294610Y928241D01*
X1293878Y927509D01*
X1293737Y927651D01*
G37*
G36*
G01X1292075Y925989D02*
X1291893Y926372D01*
X1292423Y926903D01*
X1292807Y926721D01*
X1292948Y926579D01*
X1292216Y925847D01*
X1292075Y925989D01*
G37*
G36*
G01X1292259Y925607D02*
X1292441Y925223D01*
X1291911Y924693D01*
X1291527Y924875D01*
X1291386Y925017D01*
X1292117Y925748D01*
X1292259Y925607D01*
G37*
G36*
G01X1297060Y930974D02*
X1296878Y931358D01*
X1297408Y931888D01*
X1297792Y931706D01*
X1297933Y931564D01*
X1297202Y930833D01*
X1297060Y930974D01*
G37*
G36*
G01X1297244Y930592D02*
X1297426Y930209D01*
X1296896Y929678D01*
X1296512Y929860D01*
X1296371Y930002D01*
X1297103Y930734D01*
X1297244Y930592D01*
G37*
G36*
G01X1295582Y928930D02*
X1295764Y928547D01*
X1295234Y928016D01*
X1294850Y928199D01*
X1294709Y928340D01*
X1295441Y929072D01*
X1295582Y928930D01*
G37*
G36*
G01X1295398Y929312D02*
X1295216Y929696D01*
X1295747Y930226D01*
X1296130Y930044D01*
X1296272Y929903D01*
X1295540Y929171D01*
X1295398Y929312D01*
G37*
G36*
G01X1287126Y917644D02*
X1286944Y918028D01*
X1287474Y918558D01*
X1287858Y918376D01*
X1287999Y918234D01*
X1287268Y917503D01*
X1287126Y917644D01*
G37*
G36*
G01X1288972Y918924D02*
X1289154Y918540D01*
X1288623Y918010D01*
X1288240Y918192D01*
X1288098Y918333D01*
X1288830Y919065D01*
X1288972Y918924D01*
G37*
G36*
G01X1288788Y919306D02*
X1288606Y919689D01*
X1289136Y920220D01*
X1289520Y920038D01*
X1289661Y919896D01*
X1288929Y919164D01*
X1288788Y919306D01*
G37*
G36*
G01X1290633Y920586D02*
X1290816Y920202D01*
X1290285Y919672D01*
X1289902Y919854D01*
X1289760Y919995D01*
X1290492Y920727D01*
X1290633Y920586D01*
G37*
G36*
G01X1290450Y920967D02*
X1290268Y921351D01*
X1290798Y921881D01*
X1291181Y921699D01*
X1291323Y921558D01*
X1290591Y920826D01*
X1290450Y920967D01*
G37*
G36*
G01X1292295Y922247D02*
X1292477Y921864D01*
X1291947Y921333D01*
X1291563Y921515D01*
X1291422Y921657D01*
X1292154Y922389D01*
X1292295Y922247D01*
G37*
G36*
G01X1292111Y922629D02*
X1291929Y923013D01*
X1292460Y923543D01*
X1292843Y923361D01*
X1292985Y923220D01*
X1292253Y922488D01*
X1292111Y922629D01*
G37*
G36*
G01X1293773Y924291D02*
X1293591Y924674D01*
X1294121Y925205D01*
X1294505Y925023D01*
X1294646Y924881D01*
X1293914Y924149D01*
X1293773Y924291D01*
G37*
G36*
G01X1293957Y923909D02*
X1294139Y923525D01*
X1293609Y922995D01*
X1293225Y923177D01*
X1293084Y923319D01*
X1293815Y924050D01*
X1293957Y923909D01*
G37*
G36*
G01X1297096Y927614D02*
X1296914Y927998D01*
X1297445Y928528D01*
X1297828Y928346D01*
X1297970Y928205D01*
X1297238Y927473D01*
X1297096Y927614D01*
G37*
G36*
G01X1297280Y927232D02*
X1297462Y926849D01*
X1296932Y926318D01*
X1296548Y926501D01*
X1296407Y926642D01*
X1297139Y927374D01*
X1297280Y927232D01*
G37*
G36*
G01X1295435Y925953D02*
X1295253Y926336D01*
X1295783Y926866D01*
X1296167Y926684D01*
X1296308Y926543D01*
X1295576Y925811D01*
X1295435Y925953D01*
G37*
G36*
G01X1295619Y925571D02*
X1295801Y925187D01*
X1295270Y924657D01*
X1294887Y924839D01*
X1294745Y924980D01*
X1295477Y925712D01*
X1295619Y925571D01*
G37*
G36*
G01X1284652Y981379D02*
X1284510Y980979D01*
X1283760D01*
X1283617Y981379D01*
Y981579D01*
X1284652D01*
Y981379D01*
G37*
G36*
G01X1284792Y981779D02*
X1284934Y982179D01*
X1285684D01*
X1285827Y981779D01*
Y981579D01*
X1284792D01*
Y981779D01*
G37*
G36*
G01X1289352Y981379D02*
X1289210Y980979D01*
X1288460D01*
X1288317Y981379D01*
Y981579D01*
X1289352D01*
Y981379D01*
G37*
G36*
G01X1287002D02*
X1286860Y980979D01*
X1286110D01*
X1285967Y981379D01*
Y981579D01*
X1287002D01*
Y981379D01*
G37*
G36*
G01X1289492Y981779D02*
X1289634Y982179D01*
X1290384D01*
X1290527Y981779D01*
Y981579D01*
X1289492D01*
Y981779D01*
G37*
G36*
G01X1291702Y981379D02*
X1291560Y980979D01*
X1290810D01*
X1290667Y981379D01*
Y981579D01*
X1291702D01*
Y981379D01*
G37*
G36*
G01X1287142Y981779D02*
X1287284Y982179D01*
X1288034D01*
X1288177Y981779D01*
Y981579D01*
X1287142D01*
Y981779D01*
G37*
G36*
G01X1291842D02*
X1291984Y982179D01*
X1292734D01*
X1292877Y981779D01*
Y981579D01*
X1291842D01*
Y981779D01*
G37*
G36*
G01X1294192D02*
X1294334Y982179D01*
X1295084D01*
X1295227Y981779D01*
Y981579D01*
X1294192D01*
Y981779D01*
G37*
G36*
G01X1294052Y981379D02*
X1293910Y980979D01*
X1293160D01*
X1293017Y981379D01*
Y981579D01*
X1294052D01*
Y981379D01*
G37*
G36*
G01X1296402D02*
X1296260Y980979D01*
X1295510D01*
X1295367Y981379D01*
Y981579D01*
X1296402D01*
Y981379D01*
G37*
G36*
G01X1284652Y980178D02*
X1284510Y979778D01*
X1283760D01*
X1283617Y980178D01*
Y980378D01*
X1284652D01*
Y980178D01*
G37*
G36*
G01X1284792Y980578D02*
X1284934Y980978D01*
X1285684D01*
X1285827Y980578D01*
Y980378D01*
X1284792D01*
Y980578D01*
G37*
G36*
G01X1282442D02*
X1282584Y980978D01*
X1283334D01*
X1283477Y980578D01*
Y980378D01*
X1282442D01*
Y980578D01*
G37*
G36*
G01X1287002Y980178D02*
X1286860Y979778D01*
X1286110D01*
X1285967Y980178D01*
Y980378D01*
X1287002D01*
Y980178D01*
G37*
G36*
G01X1289352D02*
X1289210Y979778D01*
X1288460D01*
X1288317Y980178D01*
Y980378D01*
X1289352D01*
Y980178D01*
G37*
G36*
G01X1287142Y980578D02*
X1287284Y980978D01*
X1288034D01*
X1288177Y980578D01*
Y980378D01*
X1287142D01*
Y980578D01*
G37*
G36*
G01X1291702Y980178D02*
X1291560Y979778D01*
X1290810D01*
X1290667Y980178D01*
Y980378D01*
X1291702D01*
Y980178D01*
G37*
G36*
G01X1289492Y980578D02*
X1289634Y980978D01*
X1290384D01*
X1290527Y980578D01*
Y980378D01*
X1289492D01*
Y980578D01*
G37*
G36*
G01X1294052Y980178D02*
X1293910Y979778D01*
X1293160D01*
X1293017Y980178D01*
Y980378D01*
X1294052D01*
Y980178D01*
G37*
G36*
G01X1294192Y980578D02*
X1294334Y980978D01*
X1295084D01*
X1295227Y980578D01*
Y980378D01*
X1294192D01*
Y980578D01*
G37*
G36*
G01X1291842D02*
X1291984Y980978D01*
X1292734D01*
X1292877Y980578D01*
Y980378D01*
X1291842D01*
Y980578D01*
G37*
G36*
G01X1284652Y978978D02*
X1284510Y978578D01*
X1283760D01*
X1283617Y978978D01*
Y979178D01*
X1284652D01*
Y978978D01*
G37*
G36*
G01X1284792Y979378D02*
X1284934Y979778D01*
X1285684D01*
X1285827Y979378D01*
Y979178D01*
X1284792D01*
Y979378D01*
G37*
G36*
G01X1289352Y978978D02*
X1289210Y978578D01*
X1288460D01*
X1288317Y978978D01*
Y979178D01*
X1289352D01*
Y978978D01*
G37*
G36*
G01X1287002D02*
X1286860Y978578D01*
X1286110D01*
X1285967Y978978D01*
Y979178D01*
X1287002D01*
Y978978D01*
G37*
G36*
G01X1287142Y979378D02*
X1287284Y979778D01*
X1288034D01*
X1288177Y979378D01*
Y979178D01*
X1287142D01*
Y979378D01*
G37*
G36*
G01X1291702Y978978D02*
X1291560Y978578D01*
X1290810D01*
X1290667Y978978D01*
Y979178D01*
X1291702D01*
Y978978D01*
G37*
G36*
G01X1289492Y979378D02*
X1289634Y979778D01*
X1290384D01*
X1290527Y979378D01*
Y979178D01*
X1289492D01*
Y979378D01*
G37*
G36*
G01X1291842D02*
X1291984Y979778D01*
X1292734D01*
X1292877Y979378D01*
Y979178D01*
X1291842D01*
Y979378D01*
G37*
G36*
G01X1294052Y978978D02*
X1293910Y978578D01*
X1293160D01*
X1293017Y978978D01*
Y979178D01*
X1294052D01*
Y978978D01*
G37*
G36*
G01X1294192Y979378D02*
X1294334Y979778D01*
X1295084D01*
X1295227Y979378D01*
Y979178D01*
X1294192D01*
Y979378D01*
G37*
G36*
G01X1296402Y978978D02*
X1296260Y978578D01*
X1295510D01*
X1295367Y978978D01*
Y979178D01*
X1296402D01*
Y978978D01*
G37*
G36*
G01X1284652Y977778D02*
X1284510Y977378D01*
X1283760D01*
X1283617Y977778D01*
Y977978D01*
X1284652D01*
Y977778D01*
G37*
G36*
G01X1284792Y978178D02*
X1284934Y978578D01*
X1285684D01*
X1285827Y978178D01*
Y977978D01*
X1284792D01*
Y978178D01*
G37*
G36*
G01X1287002Y977778D02*
X1286860Y977378D01*
X1286110D01*
X1285967Y977778D01*
Y977978D01*
X1287002D01*
Y977778D01*
G37*
G36*
G01X1289352D02*
X1289210Y977378D01*
X1288460D01*
X1288317Y977778D01*
Y977978D01*
X1289352D01*
Y977778D01*
G37*
G36*
G01X1287142Y978178D02*
X1287284Y978578D01*
X1288034D01*
X1288177Y978178D01*
Y977978D01*
X1287142D01*
Y978178D01*
G37*
G36*
G01X1291702Y977778D02*
X1291560Y977378D01*
X1290810D01*
X1290667Y977778D01*
Y977978D01*
X1291702D01*
Y977778D01*
G37*
G36*
G01X1289492Y978178D02*
X1289634Y978578D01*
X1290384D01*
X1290527Y978178D01*
Y977978D01*
X1289492D01*
Y978178D01*
G37*
G36*
G01X1291842D02*
X1291984Y978578D01*
X1292734D01*
X1292877Y978178D01*
Y977978D01*
X1291842D01*
Y978178D01*
G37*
G36*
G01X1294052Y977778D02*
X1293910Y977378D01*
X1293160D01*
X1293017Y977778D01*
Y977978D01*
X1294052D01*
Y977778D01*
G37*
G36*
G01X1294192Y978178D02*
X1294334Y978578D01*
X1295084D01*
X1295227Y978178D01*
Y977978D01*
X1294192D01*
Y978178D01*
G37*
G36*
G01X1296402Y977778D02*
X1296260Y977378D01*
X1295510D01*
X1295367Y977778D01*
Y977978D01*
X1296402D01*
Y977778D01*
G37*
G36*
G01X1284652Y976578D02*
X1284510Y976178D01*
X1283760D01*
X1283617Y976578D01*
Y976778D01*
X1284652D01*
Y976578D01*
G37*
G36*
G01X1284792Y976978D02*
X1284934Y977378D01*
X1285684D01*
X1285827Y976978D01*
Y976778D01*
X1284792D01*
Y976978D01*
G37*
G36*
G01X1287002Y976578D02*
X1286860Y976178D01*
X1286110D01*
X1285967Y976578D01*
Y976778D01*
X1287002D01*
Y976578D01*
G37*
G36*
G01X1289352D02*
X1289210Y976178D01*
X1288460D01*
X1288317Y976578D01*
Y976778D01*
X1289352D01*
Y976578D01*
G37*
G36*
G01X1287142Y976978D02*
X1287284Y977378D01*
X1288034D01*
X1288177Y976978D01*
Y976778D01*
X1287142D01*
Y976978D01*
G37*
G36*
G01X1291702Y976578D02*
X1291560Y976178D01*
X1290810D01*
X1290667Y976578D01*
Y976778D01*
X1291702D01*
Y976578D01*
G37*
G36*
G01X1289492Y976978D02*
X1289634Y977378D01*
X1290384D01*
X1290527Y976978D01*
Y976778D01*
X1289492D01*
Y976978D01*
G37*
G36*
G01X1291842D02*
X1291984Y977378D01*
X1292734D01*
X1292877Y976978D01*
Y976778D01*
X1291842D01*
Y976978D01*
G37*
G36*
G01X1294052Y976578D02*
X1293910Y976178D01*
X1293160D01*
X1293017Y976578D01*
Y976778D01*
X1294052D01*
Y976578D01*
G37*
G36*
G01X1294192Y976978D02*
X1294334Y977378D01*
X1295084D01*
X1295227Y976978D01*
Y976778D01*
X1294192D01*
Y976978D01*
G37*
G36*
G01X1296402Y976578D02*
X1296260Y976178D01*
X1295510D01*
X1295367Y976578D01*
Y976778D01*
X1296402D01*
Y976578D01*
G37*
G36*
G01X1284652Y975378D02*
X1284510Y974978D01*
X1283760D01*
X1283617Y975378D01*
Y975578D01*
X1284652D01*
Y975378D01*
G37*
G36*
G01X1284792Y975778D02*
X1284934Y976178D01*
X1285684D01*
X1285827Y975778D01*
Y975578D01*
X1284792D01*
Y975778D01*
G37*
G36*
G01X1287002Y975378D02*
X1286860Y974978D01*
X1286110D01*
X1285967Y975378D01*
Y975578D01*
X1287002D01*
Y975378D01*
G37*
G36*
G01X1289352D02*
X1289210Y974978D01*
X1288460D01*
X1288317Y975378D01*
Y975578D01*
X1289352D01*
Y975378D01*
G37*
G36*
G01X1287142Y975778D02*
X1287284Y976178D01*
X1288034D01*
X1288177Y975778D01*
Y975578D01*
X1287142D01*
Y975778D01*
G37*
G36*
G01X1291702Y975378D02*
X1291560Y974978D01*
X1290810D01*
X1290667Y975378D01*
Y975578D01*
X1291702D01*
Y975378D01*
G37*
G36*
G01X1289492Y975778D02*
X1289634Y976178D01*
X1290384D01*
X1290527Y975778D01*
Y975578D01*
X1289492D01*
Y975778D01*
G37*
G36*
G01X1294052Y975378D02*
X1293910Y974978D01*
X1293160D01*
X1293017Y975378D01*
Y975578D01*
X1294052D01*
Y975378D01*
G37*
G36*
G01X1294192Y975778D02*
X1294334Y976178D01*
X1295084D01*
X1295227Y975778D01*
Y975578D01*
X1294192D01*
Y975778D01*
G37*
G36*
G01X1291842D02*
X1291984Y976178D01*
X1292734D01*
X1292877Y975778D01*
Y975578D01*
X1291842D01*
Y975778D01*
G37*
G36*
G01X1296402Y975378D02*
X1296260Y974978D01*
X1295510D01*
X1295367Y975378D01*
Y975578D01*
X1296402D01*
Y975378D01*
G37*
G36*
G01X1284652Y974178D02*
X1284510Y973778D01*
X1283760D01*
X1283617Y974178D01*
Y974378D01*
X1284652D01*
Y974178D01*
G37*
G36*
G01X1282442Y974578D02*
X1282584Y974978D01*
X1283334D01*
X1283477Y974578D01*
Y974378D01*
X1282442D01*
Y974578D01*
G37*
G36*
G01X1284792D02*
X1284934Y974978D01*
X1285684D01*
X1285827Y974578D01*
Y974378D01*
X1284792D01*
Y974578D01*
G37*
G36*
G01X1287002Y974178D02*
X1286860Y973778D01*
X1286110D01*
X1285967Y974178D01*
Y974378D01*
X1287002D01*
Y974178D01*
G37*
G36*
G01X1289352D02*
X1289210Y973778D01*
X1288460D01*
X1288317Y974178D01*
Y974378D01*
X1289352D01*
Y974178D01*
G37*
G36*
G01X1287142Y974578D02*
X1287284Y974978D01*
X1288034D01*
X1288177Y974578D01*
Y974378D01*
X1287142D01*
Y974578D01*
G37*
G36*
G01X1291702Y974178D02*
X1291560Y973778D01*
X1290810D01*
X1290667Y974178D01*
Y974378D01*
X1291702D01*
Y974178D01*
G37*
G36*
G01X1289492Y974578D02*
X1289634Y974978D01*
X1290384D01*
X1290527Y974578D01*
Y974378D01*
X1289492D01*
Y974578D01*
G37*
G36*
G01X1294052Y974178D02*
X1293910Y973778D01*
X1293160D01*
X1293017Y974178D01*
Y974378D01*
X1294052D01*
Y974178D01*
G37*
G36*
G01X1294192Y974578D02*
X1294334Y974978D01*
X1295084D01*
X1295227Y974578D01*
Y974378D01*
X1294192D01*
Y974578D01*
G37*
G36*
G01X1291842D02*
X1291984Y974978D01*
X1292734D01*
X1292877Y974578D01*
Y974378D01*
X1291842D01*
Y974578D01*
G37*
G36*
G01X1284652Y970578D02*
X1284510Y970178D01*
X1283760D01*
X1283617Y970578D01*
Y970778D01*
X1284652D01*
Y970578D01*
G37*
G36*
G01X1282442Y970978D02*
X1282584Y971378D01*
X1283334D01*
X1283477Y970978D01*
Y970778D01*
X1282442D01*
Y970978D01*
G37*
G36*
G01X1284792D02*
X1284934Y971378D01*
X1285684D01*
X1285827Y970978D01*
Y970778D01*
X1284792D01*
Y970978D01*
G37*
G36*
G01X1287002Y970578D02*
X1286860Y970178D01*
X1286110D01*
X1285967Y970578D01*
Y970778D01*
X1287002D01*
Y970578D01*
G37*
G36*
G01X1289352D02*
X1289210Y970178D01*
X1288460D01*
X1288317Y970578D01*
Y970778D01*
X1289352D01*
Y970578D01*
G37*
G36*
G01X1287142Y970978D02*
X1287284Y971378D01*
X1288034D01*
X1288177Y970978D01*
Y970778D01*
X1287142D01*
Y970978D01*
G37*
G36*
G01X1291702Y970578D02*
X1291560Y970178D01*
X1290810D01*
X1290667Y970578D01*
Y970778D01*
X1291702D01*
Y970578D01*
G37*
G36*
G01X1289492Y970978D02*
X1289634Y971378D01*
X1290384D01*
X1290527Y970978D01*
Y970778D01*
X1289492D01*
Y970978D01*
G37*
G36*
G01X1294052Y970578D02*
X1293910Y970178D01*
X1293160D01*
X1293017Y970578D01*
Y970778D01*
X1294052D01*
Y970578D01*
G37*
G36*
G01X1291842Y970978D02*
X1291984Y971378D01*
X1292734D01*
X1292877Y970978D01*
Y970778D01*
X1291842D01*
Y970978D01*
G37*
G36*
G01X1284652Y968178D02*
X1284510Y967778D01*
X1283760D01*
X1283617Y968178D01*
Y968378D01*
X1284652D01*
Y968178D01*
G37*
G36*
G01X1282442Y968578D02*
X1282584Y968978D01*
X1283334D01*
X1283477Y968578D01*
Y968378D01*
X1282442D01*
Y968578D01*
G37*
G36*
G01X1284792D02*
X1284934Y968978D01*
X1285684D01*
X1285827Y968578D01*
Y968378D01*
X1284792D01*
Y968578D01*
G37*
G36*
G01X1287002Y968178D02*
X1286860Y967778D01*
X1286110D01*
X1285967Y968178D01*
Y968378D01*
X1287002D01*
Y968178D01*
G37*
G36*
G01X1289352D02*
X1289210Y967778D01*
X1288460D01*
X1288317Y968178D01*
Y968378D01*
X1289352D01*
Y968178D01*
G37*
G36*
G01X1291702D02*
X1291560Y967778D01*
X1290810D01*
X1290667Y968178D01*
Y968378D01*
X1291702D01*
Y968178D01*
G37*
G36*
G01X1287142Y968578D02*
X1287284Y968978D01*
X1288034D01*
X1288177Y968578D01*
Y968378D01*
X1287142D01*
Y968578D01*
G37*
G36*
G01X1289492D02*
X1289634Y968978D01*
X1290384D01*
X1290527Y968578D01*
Y968378D01*
X1289492D01*
Y968578D01*
G37*
G36*
G01X1291842D02*
X1291984Y968978D01*
X1292734D01*
X1292877Y968578D01*
Y968378D01*
X1291842D01*
Y968578D01*
G37*
G36*
G01X1284652Y971778D02*
X1284510Y971378D01*
X1283760D01*
X1283617Y971778D01*
Y971978D01*
X1284652D01*
Y971778D01*
G37*
G36*
G01X1282442Y972178D02*
X1282584Y972578D01*
X1283334D01*
X1283477Y972178D01*
Y971978D01*
X1282442D01*
Y972178D01*
G37*
G36*
G01X1284792D02*
X1284934Y972578D01*
X1285684D01*
X1285827Y972178D01*
Y971978D01*
X1284792D01*
Y972178D01*
G37*
G36*
G01X1287002Y971778D02*
X1286860Y971378D01*
X1286110D01*
X1285967Y971778D01*
Y971978D01*
X1287002D01*
Y971778D01*
G37*
G36*
G01X1289352D02*
X1289210Y971378D01*
X1288460D01*
X1288317Y971778D01*
Y971978D01*
X1289352D01*
Y971778D01*
G37*
G36*
G01X1287142Y972178D02*
X1287284Y972578D01*
X1288034D01*
X1288177Y972178D01*
Y971978D01*
X1287142D01*
Y972178D01*
G37*
G36*
G01X1291702Y971778D02*
X1291560Y971378D01*
X1290810D01*
X1290667Y971778D01*
Y971978D01*
X1291702D01*
Y971778D01*
G37*
G36*
G01X1289492Y972178D02*
X1289634Y972578D01*
X1290384D01*
X1290527Y972178D01*
Y971978D01*
X1289492D01*
Y972178D01*
G37*
G36*
G01X1294052Y971778D02*
X1293910Y971378D01*
X1293160D01*
X1293017Y971778D01*
Y971978D01*
X1294052D01*
Y971778D01*
G37*
G36*
G01X1291842Y972178D02*
X1291984Y972578D01*
X1292734D01*
X1292877Y972178D01*
Y971978D01*
X1291842D01*
Y972178D01*
G37*
G36*
G01X1284792Y969778D02*
X1284934Y970178D01*
X1285684D01*
X1285827Y969778D01*
Y969578D01*
X1284792D01*
Y969778D01*
G37*
G36*
G01X1284652Y969378D02*
X1284510Y968978D01*
X1283760D01*
X1283617Y969378D01*
Y969578D01*
X1284652D01*
Y969378D01*
G37*
G36*
G01X1282442Y969778D02*
X1282584Y970178D01*
X1283334D01*
X1283477Y969778D01*
Y969578D01*
X1282442D01*
Y969778D01*
G37*
G36*
G01X1287142D02*
X1287284Y970178D01*
X1288034D01*
X1288177Y969778D01*
Y969578D01*
X1287142D01*
Y969778D01*
G37*
G36*
G01X1291702Y969378D02*
X1291560Y968978D01*
X1290810D01*
X1290667Y969378D01*
Y969578D01*
X1291702D01*
Y969378D01*
G37*
G36*
G01X1289492Y969778D02*
X1289634Y970178D01*
X1290384D01*
X1290527Y969778D01*
Y969578D01*
X1289492D01*
Y969778D01*
G37*
G36*
G01X1287002Y969378D02*
X1286860Y968978D01*
X1286110D01*
X1285967Y969378D01*
Y969578D01*
X1287002D01*
Y969378D01*
G37*
G36*
G01X1289352D02*
X1289210Y968978D01*
X1288460D01*
X1288317Y969378D01*
Y969578D01*
X1289352D01*
Y969378D01*
G37*
G36*
G01X1291842Y969778D02*
X1291984Y970178D01*
X1292734D01*
X1292877Y969778D01*
Y969578D01*
X1291842D01*
Y969778D01*
G37*
G36*
G01X1284652Y972978D02*
X1284510Y972578D01*
X1283760D01*
X1283617Y972978D01*
Y973178D01*
X1284652D01*
Y972978D01*
G37*
G36*
G01X1282442Y973378D02*
X1282584Y973778D01*
X1283334D01*
X1283477Y973378D01*
Y973178D01*
X1282442D01*
Y973378D01*
G37*
G36*
G01X1284792D02*
X1284934Y973778D01*
X1285684D01*
X1285827Y973378D01*
Y973178D01*
X1284792D01*
Y973378D01*
G37*
G36*
G01X1287002Y972978D02*
X1286860Y972578D01*
X1286110D01*
X1285967Y972978D01*
Y973178D01*
X1287002D01*
Y972978D01*
G37*
G36*
G01X1289352D02*
X1289210Y972578D01*
X1288460D01*
X1288317Y972978D01*
Y973178D01*
X1289352D01*
Y972978D01*
G37*
G36*
G01X1287142Y973378D02*
X1287284Y973778D01*
X1288034D01*
X1288177Y973378D01*
Y973178D01*
X1287142D01*
Y973378D01*
G37*
G36*
G01X1291702Y972978D02*
X1291560Y972578D01*
X1290810D01*
X1290667Y972978D01*
Y973178D01*
X1291702D01*
Y972978D01*
G37*
G36*
G01X1289492Y973378D02*
X1289634Y973778D01*
X1290384D01*
X1290527Y973378D01*
Y973178D01*
X1289492D01*
Y973378D01*
G37*
G36*
G01X1294052Y972978D02*
X1293910Y972578D01*
X1293160D01*
X1293017Y972978D01*
Y973178D01*
X1294052D01*
Y972978D01*
G37*
G36*
G01X1294192Y973378D02*
X1294334Y973778D01*
X1295084D01*
X1295227Y973378D01*
Y973178D01*
X1294192D01*
Y973378D01*
G37*
G36*
G01X1291842D02*
X1291984Y973778D01*
X1292734D01*
X1292877Y973378D01*
Y973178D01*
X1291842D01*
Y973378D01*
G37*
G36*
G01X1288306Y1013719D02*
X1288164Y1013319D01*
X1287414D01*
X1287271Y1013719D01*
Y1013919D01*
X1288306D01*
Y1013719D01*
G37*
G36*
G01X1286096Y1014119D02*
X1286238Y1014519D01*
X1286988D01*
X1287131Y1014119D01*
Y1013919D01*
X1286096D01*
Y1014119D01*
G37*
G36*
G01X1290656Y1013719D02*
X1290514Y1013319D01*
X1289764D01*
X1289621Y1013719D01*
Y1013919D01*
X1290656D01*
Y1013719D01*
G37*
G36*
G01X1288446Y1014119D02*
X1288588Y1014519D01*
X1289338D01*
X1289481Y1014119D01*
Y1013919D01*
X1288446D01*
Y1014119D01*
G37*
G36*
G01X1290796D02*
X1290938Y1014519D01*
X1291688D01*
X1291831Y1014119D01*
Y1013919D01*
X1290796D01*
Y1014119D01*
G37*
G36*
G01X1293006Y1013719D02*
X1292864Y1013319D01*
X1292114D01*
X1291971Y1013719D01*
Y1013919D01*
X1293006D01*
Y1013719D01*
G37*
G36*
G01X1295356D02*
X1295214Y1013319D01*
X1294464D01*
X1294321Y1013719D01*
Y1013919D01*
X1295356D01*
Y1013719D01*
G37*
G36*
G01X1293146Y1014119D02*
X1293288Y1014519D01*
X1294038D01*
X1294181Y1014119D01*
Y1013919D01*
X1293146D01*
Y1014119D01*
G37*
G36*
G01X1297706Y1013719D02*
X1297564Y1013319D01*
X1296814D01*
X1296671Y1013719D01*
Y1013919D01*
X1297706D01*
Y1013719D01*
G37*
G36*
G01X1295496Y1014119D02*
X1295638Y1014519D01*
X1296388D01*
X1296531Y1014119D01*
Y1013919D01*
X1295496D01*
Y1014119D01*
G37*
G36*
G01X1288306Y1012519D02*
X1288164Y1012119D01*
X1287414D01*
X1287271Y1012519D01*
Y1012719D01*
X1288306D01*
Y1012519D01*
G37*
G36*
G01X1286096Y1012919D02*
X1286238Y1013319D01*
X1286988D01*
X1287131Y1012919D01*
Y1012719D01*
X1286096D01*
Y1012919D01*
G37*
G36*
G01X1290656Y1012519D02*
X1290514Y1012119D01*
X1289764D01*
X1289621Y1012519D01*
Y1012719D01*
X1290656D01*
Y1012519D01*
G37*
G36*
G01X1288446Y1012919D02*
X1288588Y1013319D01*
X1289338D01*
X1289481Y1012919D01*
Y1012719D01*
X1288446D01*
Y1012919D01*
G37*
G36*
G01X1290796D02*
X1290938Y1013319D01*
X1291688D01*
X1291831Y1012919D01*
Y1012719D01*
X1290796D01*
Y1012919D01*
G37*
G36*
G01X1293006Y1012519D02*
X1292864Y1012119D01*
X1292114D01*
X1291971Y1012519D01*
Y1012719D01*
X1293006D01*
Y1012519D01*
G37*
G36*
G01X1295356D02*
X1295214Y1012119D01*
X1294464D01*
X1294321Y1012519D01*
Y1012719D01*
X1295356D01*
Y1012519D01*
G37*
G36*
G01X1293146Y1012919D02*
X1293288Y1013319D01*
X1294038D01*
X1294181Y1012919D01*
Y1012719D01*
X1293146D01*
Y1012919D01*
G37*
G36*
G01X1297706Y1012519D02*
X1297564Y1012119D01*
X1296814D01*
X1296671Y1012519D01*
Y1012719D01*
X1297706D01*
Y1012519D01*
G37*
G36*
G01X1295496Y1012919D02*
X1295638Y1013319D01*
X1296388D01*
X1296531Y1012919D01*
Y1012719D01*
X1295496D01*
Y1012919D01*
G37*
G36*
G01X1288306Y1011319D02*
X1288164Y1010919D01*
X1287414D01*
X1287271Y1011319D01*
Y1011519D01*
X1288306D01*
Y1011319D01*
G37*
G36*
G01X1290656D02*
X1290514Y1010919D01*
X1289764D01*
X1289621Y1011319D01*
Y1011519D01*
X1290656D01*
Y1011319D01*
G37*
G36*
G01X1286096Y1011719D02*
X1286238Y1012119D01*
X1286988D01*
X1287131Y1011719D01*
Y1011519D01*
X1286096D01*
Y1011719D01*
G37*
G36*
G01X1288446D02*
X1288588Y1012119D01*
X1289338D01*
X1289481Y1011719D01*
Y1011519D01*
X1288446D01*
Y1011719D01*
G37*
G36*
G01X1290796D02*
X1290938Y1012119D01*
X1291688D01*
X1291831Y1011719D01*
Y1011519D01*
X1290796D01*
Y1011719D01*
G37*
G36*
G01X1293006Y1011319D02*
X1292864Y1010919D01*
X1292114D01*
X1291971Y1011319D01*
Y1011519D01*
X1293006D01*
Y1011319D01*
G37*
G36*
G01X1295356D02*
X1295214Y1010919D01*
X1294464D01*
X1294321Y1011319D01*
Y1011519D01*
X1295356D01*
Y1011319D01*
G37*
G36*
G01X1293146Y1011719D02*
X1293288Y1012119D01*
X1294038D01*
X1294181Y1011719D01*
Y1011519D01*
X1293146D01*
Y1011719D01*
G37*
G36*
G01X1297706Y1011319D02*
X1297564Y1010919D01*
X1296814D01*
X1296671Y1011319D01*
Y1011519D01*
X1297706D01*
Y1011319D01*
G37*
G36*
G01X1295496Y1011719D02*
X1295638Y1012119D01*
X1296388D01*
X1296531Y1011719D01*
Y1011519D01*
X1295496D01*
Y1011719D01*
G37*
G36*
G01X1288306Y1010119D02*
X1288164Y1009719D01*
X1287414D01*
X1287271Y1010119D01*
Y1010319D01*
X1288306D01*
Y1010119D01*
G37*
G36*
G01X1285956D02*
X1285814Y1009719D01*
X1285064D01*
X1284921Y1010119D01*
Y1010319D01*
X1285956D01*
Y1010119D01*
G37*
G36*
G01X1286096Y1010519D02*
X1286238Y1010919D01*
X1286988D01*
X1287131Y1010519D01*
Y1010319D01*
X1286096D01*
Y1010519D01*
G37*
G36*
G01X1290656Y1010119D02*
X1290514Y1009719D01*
X1289764D01*
X1289621Y1010119D01*
Y1010319D01*
X1290656D01*
Y1010119D01*
G37*
G36*
G01X1288446Y1010519D02*
X1288588Y1010919D01*
X1289338D01*
X1289481Y1010519D01*
Y1010319D01*
X1288446D01*
Y1010519D01*
G37*
G36*
G01X1290796D02*
X1290938Y1010919D01*
X1291688D01*
X1291831Y1010519D01*
Y1010319D01*
X1290796D01*
Y1010519D01*
G37*
G36*
G01X1293006Y1010119D02*
X1292864Y1009719D01*
X1292114D01*
X1291971Y1010119D01*
Y1010319D01*
X1293006D01*
Y1010119D01*
G37*
G36*
G01X1295356D02*
X1295214Y1009719D01*
X1294464D01*
X1294321Y1010119D01*
Y1010319D01*
X1295356D01*
Y1010119D01*
G37*
G36*
G01X1293146Y1010519D02*
X1293288Y1010919D01*
X1294038D01*
X1294181Y1010519D01*
Y1010319D01*
X1293146D01*
Y1010519D01*
G37*
G36*
G01X1297706Y1010119D02*
X1297564Y1009719D01*
X1296814D01*
X1296671Y1010119D01*
Y1010319D01*
X1297706D01*
Y1010119D01*
G37*
G36*
G01X1295496Y1010519D02*
X1295638Y1010919D01*
X1296388D01*
X1296531Y1010519D01*
Y1010319D01*
X1295496D01*
Y1010519D01*
G37*
G36*
G01X1288306Y1008919D02*
X1288164Y1008519D01*
X1287414D01*
X1287271Y1008919D01*
Y1009119D01*
X1288306D01*
Y1008919D01*
G37*
G36*
G01X1285956D02*
X1285814Y1008519D01*
X1285064D01*
X1284921Y1008919D01*
Y1009119D01*
X1285956D01*
Y1008919D01*
G37*
G36*
G01X1286096Y1009319D02*
X1286238Y1009719D01*
X1286988D01*
X1287131Y1009319D01*
Y1009119D01*
X1286096D01*
Y1009319D01*
G37*
G36*
G01X1290656Y1008919D02*
X1290514Y1008519D01*
X1289764D01*
X1289621Y1008919D01*
Y1009119D01*
X1290656D01*
Y1008919D01*
G37*
G36*
G01X1288446Y1009319D02*
X1288588Y1009719D01*
X1289338D01*
X1289481Y1009319D01*
Y1009119D01*
X1288446D01*
Y1009319D01*
G37*
G36*
G01X1290796D02*
X1290938Y1009719D01*
X1291688D01*
X1291831Y1009319D01*
Y1009119D01*
X1290796D01*
Y1009319D01*
G37*
G36*
G01X1295356Y1008919D02*
X1295214Y1008519D01*
X1294464D01*
X1294321Y1008919D01*
Y1009119D01*
X1295356D01*
Y1008919D01*
G37*
G36*
G01X1293146Y1009319D02*
X1293288Y1009719D01*
X1294038D01*
X1294181Y1009319D01*
Y1009119D01*
X1293146D01*
Y1009319D01*
G37*
G36*
G01X1293006Y1008919D02*
X1292864Y1008519D01*
X1292114D01*
X1291971Y1008919D01*
Y1009119D01*
X1293006D01*
Y1008919D01*
G37*
G36*
G01X1297706D02*
X1297564Y1008519D01*
X1296814D01*
X1296671Y1008919D01*
Y1009119D01*
X1297706D01*
Y1008919D01*
G37*
G36*
G01X1295496Y1009319D02*
X1295638Y1009719D01*
X1296388D01*
X1296531Y1009319D01*
Y1009119D01*
X1295496D01*
Y1009319D01*
G37*
G36*
G01X1290796Y1017719D02*
X1290938Y1018119D01*
X1291688D01*
X1291831Y1017719D01*
Y1017519D01*
X1290796D01*
Y1017719D01*
G37*
G36*
G01X1288446D02*
X1288588Y1018119D01*
X1289338D01*
X1289481Y1017719D01*
Y1017519D01*
X1288446D01*
Y1017719D01*
G37*
G36*
G01X1290656Y1017319D02*
X1290514Y1016919D01*
X1289764D01*
X1289621Y1017319D01*
Y1017519D01*
X1290656D01*
Y1017319D01*
G37*
G36*
G01X1293146Y1017719D02*
X1293288Y1018119D01*
X1294038D01*
X1294181Y1017719D01*
Y1017519D01*
X1293146D01*
Y1017719D01*
G37*
G36*
G01X1295356Y1017319D02*
X1295214Y1016919D01*
X1294464D01*
X1294321Y1017319D01*
Y1017519D01*
X1295356D01*
Y1017319D01*
G37*
G36*
G01X1293006D02*
X1292864Y1016919D01*
X1292114D01*
X1291971Y1017319D01*
Y1017519D01*
X1293006D01*
Y1017319D01*
G37*
G36*
G01X1295496Y1017719D02*
X1295638Y1018119D01*
X1296388D01*
X1296531Y1017719D01*
Y1017519D01*
X1295496D01*
Y1017719D01*
G37*
G36*
G01X1297706Y1017319D02*
X1297564Y1016919D01*
X1296814D01*
X1296671Y1017319D01*
Y1017519D01*
X1297706D01*
Y1017319D01*
G37*
G36*
G01X1288306Y1016119D02*
X1288164Y1015719D01*
X1287414D01*
X1287271Y1016119D01*
Y1016319D01*
X1288306D01*
Y1016119D01*
G37*
G36*
G01X1290656D02*
X1290514Y1015719D01*
X1289764D01*
X1289621Y1016119D01*
Y1016319D01*
X1290656D01*
Y1016119D01*
G37*
G36*
G01X1290796Y1016519D02*
X1290938Y1016919D01*
X1291688D01*
X1291831Y1016519D01*
Y1016319D01*
X1290796D01*
Y1016519D01*
G37*
G36*
G01X1288446D02*
X1288588Y1016919D01*
X1289338D01*
X1289481Y1016519D01*
Y1016319D01*
X1288446D01*
Y1016519D01*
G37*
G36*
G01X1295356Y1016119D02*
X1295214Y1015719D01*
X1294464D01*
X1294321Y1016119D01*
Y1016319D01*
X1295356D01*
Y1016119D01*
G37*
G36*
G01X1293006D02*
X1292864Y1015719D01*
X1292114D01*
X1291971Y1016119D01*
Y1016319D01*
X1293006D01*
Y1016119D01*
G37*
G36*
G01X1293146Y1016519D02*
X1293288Y1016919D01*
X1294038D01*
X1294181Y1016519D01*
Y1016319D01*
X1293146D01*
Y1016519D01*
G37*
G36*
G01X1297706Y1016119D02*
X1297564Y1015719D01*
X1296814D01*
X1296671Y1016119D01*
Y1016319D01*
X1297706D01*
Y1016119D01*
G37*
G36*
G01X1295496Y1016519D02*
X1295638Y1016919D01*
X1296388D01*
X1296531Y1016519D01*
Y1016319D01*
X1295496D01*
Y1016519D01*
G37*
G36*
G01X1288306Y1014919D02*
X1288164Y1014519D01*
X1287414D01*
X1287271Y1014919D01*
Y1015119D01*
X1288306D01*
Y1014919D01*
G37*
G36*
G01X1290656D02*
X1290514Y1014519D01*
X1289764D01*
X1289621Y1014919D01*
Y1015119D01*
X1290656D01*
Y1014919D01*
G37*
G36*
G01X1290796Y1015319D02*
X1290938Y1015719D01*
X1291688D01*
X1291831Y1015319D01*
Y1015119D01*
X1290796D01*
Y1015319D01*
G37*
G36*
G01X1288446D02*
X1288588Y1015719D01*
X1289338D01*
X1289481Y1015319D01*
Y1015119D01*
X1288446D01*
Y1015319D01*
G37*
G36*
G01X1293006Y1014919D02*
X1292864Y1014519D01*
X1292114D01*
X1291971Y1014919D01*
Y1015119D01*
X1293006D01*
Y1014919D01*
G37*
G36*
G01X1295356D02*
X1295214Y1014519D01*
X1294464D01*
X1294321Y1014919D01*
Y1015119D01*
X1295356D01*
Y1014919D01*
G37*
G36*
G01X1293146Y1015319D02*
X1293288Y1015719D01*
X1294038D01*
X1294181Y1015319D01*
Y1015119D01*
X1293146D01*
Y1015319D01*
G37*
G36*
G01X1297706Y1014919D02*
X1297564Y1014519D01*
X1296814D01*
X1296671Y1014919D01*
Y1015119D01*
X1297706D01*
Y1014919D01*
G37*
G36*
G01X1295496Y1015319D02*
X1295638Y1015719D01*
X1296388D01*
X1296531Y1015319D01*
Y1015119D01*
X1295496D01*
Y1015319D01*
G37*
G36*
G01X1295560Y1029929D02*
X1295176Y1029747D01*
X1294646Y1030278D01*
X1294828Y1030661D01*
X1294969Y1030803D01*
X1295701Y1030071D01*
X1295560Y1029929D01*
G37*
G36*
G01X1295941Y1030113D02*
X1296325Y1030295D01*
X1296855Y1029765D01*
X1296673Y1029381D01*
X1296532Y1029240D01*
X1295800Y1029972D01*
X1295941Y1030113D01*
G37*
G36*
G01X1297221Y1028268D02*
X1296838Y1028086D01*
X1296307Y1028616D01*
X1296490Y1029000D01*
X1296631Y1029141D01*
X1297363Y1028409D01*
X1297221Y1028268D01*
G37*
G36*
G01X1298071Y1029117D02*
X1297687Y1028935D01*
X1297157Y1029466D01*
X1297339Y1029849D01*
X1297480Y1029991D01*
X1298212Y1029259D01*
X1298071Y1029117D01*
G37*
G36*
G01X1296791Y1030963D02*
X1297175Y1031145D01*
X1297705Y1030615D01*
X1297523Y1030231D01*
X1297381Y1030090D01*
X1296650Y1030821D01*
X1296791Y1030963D01*
G37*
G36*
G01X1296409Y1030779D02*
X1296026Y1030597D01*
X1295495Y1031127D01*
X1295677Y1031511D01*
X1295819Y1031652D01*
X1296551Y1030920D01*
X1296409Y1030779D01*
G37*
G36*
G01X1294710Y1029080D02*
X1294327Y1028898D01*
X1293796Y1029428D01*
X1293978Y1029812D01*
X1294120Y1029953D01*
X1294852Y1029221D01*
X1294710Y1029080D01*
G37*
G36*
G01X1293430Y1030926D02*
X1293814Y1031108D01*
X1294344Y1030577D01*
X1294162Y1030194D01*
X1294021Y1030052D01*
X1293289Y1030784D01*
X1293430Y1030926D01*
G37*
G36*
G01X1293048Y1030742D02*
X1292665Y1030560D01*
X1292135Y1031090D01*
X1292317Y1031474D01*
X1292458Y1031615D01*
X1293190Y1030883D01*
X1293048Y1030742D01*
G37*
G36*
G01X1296372Y1027418D02*
X1295988Y1027236D01*
X1295458Y1027767D01*
X1295640Y1028150D01*
X1295781Y1028292D01*
X1296513Y1027560D01*
X1296372Y1027418D01*
G37*
G36*
G01X1296754Y1027602D02*
X1297137Y1027784D01*
X1297668Y1027254D01*
X1297486Y1026870D01*
X1297344Y1026729D01*
X1296612Y1027461D01*
X1296754Y1027602D01*
G37*
G36*
G01X1295092Y1029264D02*
X1295476Y1029446D01*
X1296006Y1028916D01*
X1295824Y1028532D01*
X1295682Y1028391D01*
X1294951Y1029122D01*
X1295092Y1029264D01*
G37*
G36*
G01X1295356Y1022119D02*
X1295214Y1021719D01*
X1294464D01*
X1294321Y1022119D01*
Y1022319D01*
X1295356D01*
Y1022119D01*
G37*
G36*
G01X1295496Y1022519D02*
X1295638Y1022919D01*
X1296388D01*
X1296531Y1022519D01*
Y1022319D01*
X1295496D01*
Y1022519D01*
G37*
G36*
G01X1297706Y1022119D02*
X1297564Y1021719D01*
X1296814D01*
X1296671Y1022119D01*
Y1022319D01*
X1297706D01*
Y1022119D01*
G37*
G36*
G01X1290656Y1018519D02*
X1290514Y1018119D01*
X1289764D01*
X1289621Y1018519D01*
Y1018719D01*
X1290656D01*
Y1018519D01*
G37*
G36*
G01X1290796Y1018919D02*
X1290938Y1019319D01*
X1291688D01*
X1291831Y1018919D01*
Y1018719D01*
X1290796D01*
Y1018919D01*
G37*
G36*
G01X1288446D02*
X1288588Y1019319D01*
X1289338D01*
X1289481Y1018919D01*
Y1018719D01*
X1288446D01*
Y1018919D01*
G37*
G36*
G01X1293006Y1018519D02*
X1292864Y1018119D01*
X1292114D01*
X1291971Y1018519D01*
Y1018719D01*
X1293006D01*
Y1018519D01*
G37*
G36*
G01X1295356D02*
X1295214Y1018119D01*
X1294464D01*
X1294321Y1018519D01*
Y1018719D01*
X1295356D01*
Y1018519D01*
G37*
G36*
G01X1293146Y1018919D02*
X1293288Y1019319D01*
X1294038D01*
X1294181Y1018919D01*
Y1018719D01*
X1293146D01*
Y1018919D01*
G37*
G36*
G01X1297706Y1018519D02*
X1297564Y1018119D01*
X1296814D01*
X1296671Y1018519D01*
Y1018719D01*
X1297706D01*
Y1018519D01*
G37*
G36*
G01X1295496Y1018919D02*
X1295638Y1019319D01*
X1296388D01*
X1296531Y1018919D01*
Y1018719D01*
X1295496D01*
Y1018919D01*
G37*
G36*
G01X1295356Y1020919D02*
X1295214Y1020519D01*
X1294464D01*
X1294321Y1020919D01*
Y1021119D01*
X1295356D01*
Y1020919D01*
G37*
G36*
G01X1293006D02*
X1292864Y1020519D01*
X1292114D01*
X1291971Y1020919D01*
Y1021119D01*
X1293006D01*
Y1020919D01*
G37*
G36*
G01X1293146Y1021319D02*
X1293288Y1021719D01*
X1294038D01*
X1294181Y1021319D01*
Y1021119D01*
X1293146D01*
Y1021319D01*
G37*
G36*
G01X1297706Y1020919D02*
X1297564Y1020519D01*
X1296814D01*
X1296671Y1020919D01*
Y1021119D01*
X1297706D01*
Y1020919D01*
G37*
G36*
G01X1295496Y1021319D02*
X1295638Y1021719D01*
X1296388D01*
X1296531Y1021319D01*
Y1021119D01*
X1295496D01*
Y1021319D01*
G37*
G36*
G01X1290656Y1019719D02*
X1290514Y1019319D01*
X1289764D01*
X1289621Y1019719D01*
Y1019919D01*
X1290656D01*
Y1019719D01*
G37*
G36*
G01X1290796Y1020119D02*
X1290938Y1020519D01*
X1291688D01*
X1291831Y1020119D01*
Y1019919D01*
X1290796D01*
Y1020119D01*
G37*
G36*
G01X1293006Y1019719D02*
X1292864Y1019319D01*
X1292114D01*
X1291971Y1019719D01*
Y1019919D01*
X1293006D01*
Y1019719D01*
G37*
G36*
G01X1295356D02*
X1295214Y1019319D01*
X1294464D01*
X1294321Y1019719D01*
Y1019919D01*
X1295356D01*
Y1019719D01*
G37*
G36*
G01X1293146Y1020119D02*
X1293288Y1020519D01*
X1294038D01*
X1294181Y1020119D01*
Y1019919D01*
X1293146D01*
Y1020119D01*
G37*
G36*
G01X1297706Y1019719D02*
X1297564Y1019319D01*
X1296814D01*
X1296671Y1019719D01*
Y1019919D01*
X1297706D01*
Y1019719D01*
G37*
G36*
G01X1295496Y1020119D02*
X1295638Y1020519D01*
X1296388D01*
X1296531Y1020119D01*
Y1019919D01*
X1295496D01*
Y1020119D01*
G37*
G36*
G01X1297315Y1045157D02*
X1296931Y1044975D01*
X1296401Y1045506D01*
X1296583Y1045889D01*
X1296724Y1046031D01*
X1297456Y1045299D01*
X1297315Y1045157D01*
G37*
G36*
G01X1297697Y1045341D02*
X1298080Y1045523D01*
X1298611Y1044993D01*
X1298429Y1044609D01*
X1298287Y1044468D01*
X1297555Y1045200D01*
X1297697Y1045341D01*
G37*
G36*
G01X1295653Y1046819D02*
X1295270Y1046637D01*
X1294739Y1047167D01*
X1294921Y1047551D01*
X1295063Y1047692D01*
X1295795Y1046960D01*
X1295653Y1046819D01*
G37*
G36*
G01X1296035Y1047003D02*
X1296419Y1047185D01*
X1296949Y1046655D01*
X1296767Y1046271D01*
X1296625Y1046130D01*
X1295894Y1046861D01*
X1296035Y1047003D01*
G37*
G36*
G01X1293955Y1045121D02*
X1293571Y1044938D01*
X1293041Y1045469D01*
X1293223Y1045852D01*
X1293364Y1045994D01*
X1294096Y1045262D01*
X1293955Y1045121D01*
G37*
G36*
G01X1294336Y1045304D02*
X1294720Y1045486D01*
X1295250Y1044956D01*
X1295068Y1044573D01*
X1294927Y1044431D01*
X1294195Y1045163D01*
X1294336Y1045304D01*
G37*
G36*
G01X1292675Y1046966D02*
X1293058Y1047148D01*
X1293589Y1046618D01*
X1293407Y1046234D01*
X1293265Y1046093D01*
X1292533Y1046825D01*
X1292675Y1046966D01*
G37*
G36*
G01X1292293Y1046782D02*
X1291909Y1046600D01*
X1291379Y1047130D01*
X1291561Y1047514D01*
X1291702Y1047656D01*
X1292434Y1046924D01*
X1292293Y1046782D01*
G37*
G36*
G01X1297278Y1041797D02*
X1296894Y1041615D01*
X1296364Y1042145D01*
X1296546Y1042529D01*
X1296688Y1042670D01*
X1297419Y1041939D01*
X1297278Y1041797D01*
G37*
G36*
G01X1295616Y1043459D02*
X1295233Y1043277D01*
X1294702Y1043807D01*
X1294884Y1044191D01*
X1295026Y1044332D01*
X1295758Y1043600D01*
X1295616Y1043459D01*
G37*
G36*
G01X1295998Y1043643D02*
X1296382Y1043825D01*
X1296912Y1043294D01*
X1296730Y1042911D01*
X1296589Y1042769D01*
X1295857Y1043501D01*
X1295998Y1043643D01*
G37*
G36*
G01X1297660Y1041981D02*
X1298043Y1042163D01*
X1298574Y1041633D01*
X1298392Y1041249D01*
X1298250Y1041108D01*
X1297518Y1041840D01*
X1297660Y1041981D01*
G37*
G36*
G01X1294804Y1045970D02*
X1294421Y1045788D01*
X1293890Y1046318D01*
X1294072Y1046702D01*
X1294214Y1046843D01*
X1294946Y1046111D01*
X1294804Y1045970D01*
G37*
G36*
G01X1298128Y1042647D02*
X1297744Y1042465D01*
X1297214Y1042995D01*
X1297396Y1043379D01*
X1297537Y1043520D01*
X1298269Y1042788D01*
X1298128Y1042647D01*
G37*
G36*
G01X1296466Y1044308D02*
X1296082Y1044126D01*
X1295552Y1044657D01*
X1295734Y1045040D01*
X1295875Y1045182D01*
X1296607Y1044450D01*
X1296466Y1044308D01*
G37*
G36*
G01X1295186Y1046154D02*
X1295570Y1046336D01*
X1296100Y1045806D01*
X1295918Y1045422D01*
X1295776Y1045281D01*
X1295045Y1046012D01*
X1295186Y1046154D01*
G37*
G36*
G01X1296848Y1044492D02*
X1297231Y1044674D01*
X1297762Y1044144D01*
X1297580Y1043760D01*
X1297438Y1043619D01*
X1296706Y1044351D01*
X1296848Y1044492D01*
G37*
G36*
G01X1291444Y1045933D02*
X1291060Y1045751D01*
X1290530Y1046281D01*
X1290712Y1046665D01*
X1290853Y1046807D01*
X1291585Y1046075D01*
X1291444Y1045933D01*
G37*
G36*
G01X1290164Y1047779D02*
X1290548Y1047961D01*
X1291078Y1047431D01*
X1290896Y1047047D01*
X1290754Y1046906D01*
X1290023Y1047637D01*
X1290164Y1047779D01*
G37*
G36*
G01X1293106Y1044272D02*
X1292722Y1044089D01*
X1292192Y1044620D01*
X1292374Y1045003D01*
X1292515Y1045145D01*
X1293247Y1044413D01*
X1293106Y1044272D01*
G37*
G36*
G01X1293487Y1044455D02*
X1293871Y1044637D01*
X1294401Y1044107D01*
X1294219Y1043724D01*
X1294078Y1043582D01*
X1293346Y1044314D01*
X1293487Y1044455D01*
G37*
G36*
G01X1294767Y1042610D02*
X1294384Y1042428D01*
X1293853Y1042958D01*
X1294035Y1043342D01*
X1294177Y1043483D01*
X1294909Y1042751D01*
X1294767Y1042610D01*
G37*
G36*
G01X1291826Y1046117D02*
X1292209Y1046299D01*
X1292740Y1045769D01*
X1292558Y1045385D01*
X1292416Y1045244D01*
X1291684Y1045976D01*
X1291826Y1046117D01*
G37*
G36*
G01X1298091Y1039286D02*
X1297707Y1039104D01*
X1297177Y1039635D01*
X1297359Y1040018D01*
X1297500Y1040160D01*
X1298232Y1039428D01*
X1298091Y1039286D01*
G37*
G36*
G01X1296811Y1041132D02*
X1297194Y1041314D01*
X1297725Y1040784D01*
X1297543Y1040400D01*
X1297401Y1040259D01*
X1296669Y1040991D01*
X1296811Y1041132D01*
G37*
G36*
G01X1295149Y1042794D02*
X1295533Y1042976D01*
X1296063Y1042445D01*
X1295881Y1042062D01*
X1295740Y1041920D01*
X1295008Y1042652D01*
X1295149Y1042794D01*
G37*
G36*
G01X1296429Y1040948D02*
X1296045Y1040766D01*
X1295515Y1041296D01*
X1295697Y1041680D01*
X1295839Y1041821D01*
X1296570Y1041090D01*
X1296429Y1040948D01*
G37*
G36*
G01X1283965Y1044922D02*
X1283581Y1044740D01*
X1283051Y1045270D01*
X1283233Y1045654D01*
X1283375Y1045795D01*
X1284106Y1045064D01*
X1283965Y1044922D01*
G37*
G36*
G01X1282685Y1046768D02*
X1283069Y1046950D01*
X1283599Y1046419D01*
X1283417Y1046036D01*
X1283276Y1045894D01*
X1282544Y1046626D01*
X1282685Y1046768D01*
G37*
G36*
G01X1284347Y1045106D02*
X1284730Y1045288D01*
X1285261Y1044758D01*
X1285079Y1044374D01*
X1284937Y1044233D01*
X1284205Y1044965D01*
X1284347Y1045106D01*
G37*
G36*
G01X1285627Y1043260D02*
X1285243Y1043078D01*
X1284713Y1043609D01*
X1284895Y1043992D01*
X1285036Y1044134D01*
X1285768Y1043402D01*
X1285627Y1043260D01*
G37*
G36*
G01X1290994Y1038459D02*
X1291377Y1038641D01*
X1291908Y1038111D01*
X1291726Y1037727D01*
X1291584Y1037586D01*
X1290852Y1038318D01*
X1290994Y1038459D01*
G37*
G36*
G01X1290612Y1038275D02*
X1290228Y1038093D01*
X1289698Y1038624D01*
X1289880Y1039007D01*
X1290021Y1039149D01*
X1290753Y1038417D01*
X1290612Y1038275D01*
G37*
G36*
G01X1289332Y1040121D02*
X1289716Y1040303D01*
X1290246Y1039773D01*
X1290064Y1039389D01*
X1289922Y1039248D01*
X1289191Y1039979D01*
X1289332Y1040121D01*
G37*
G36*
G01X1287288Y1041599D02*
X1286905Y1041417D01*
X1286375Y1041947D01*
X1286557Y1042331D01*
X1286698Y1042472D01*
X1287430Y1041740D01*
X1287288Y1041599D01*
G37*
G36*
G01X1288950Y1039937D02*
X1288567Y1039755D01*
X1288036Y1040285D01*
X1288218Y1040669D01*
X1288360Y1040810D01*
X1289092Y1040078D01*
X1288950Y1039937D01*
G37*
G36*
G01X1286009Y1043444D02*
X1286392Y1043626D01*
X1286923Y1043096D01*
X1286740Y1042712D01*
X1286599Y1042571D01*
X1285867Y1043303D01*
X1286009Y1043444D01*
G37*
G36*
G01X1287670Y1041783D02*
X1288054Y1041965D01*
X1288584Y1041434D01*
X1288402Y1041051D01*
X1288261Y1040909D01*
X1287529Y1041641D01*
X1287670Y1041783D01*
G37*
G36*
G01X1294317Y1035136D02*
X1294701Y1035318D01*
X1295231Y1034787D01*
X1295049Y1034404D01*
X1294908Y1034262D01*
X1294176Y1034994D01*
X1294317Y1035136D01*
G37*
G36*
G01X1297640Y1031812D02*
X1298024Y1031994D01*
X1298554Y1031464D01*
X1298372Y1031080D01*
X1298231Y1030939D01*
X1297499Y1031671D01*
X1297640Y1031812D01*
G37*
G36*
G01X1295597Y1033290D02*
X1295213Y1033108D01*
X1294683Y1033638D01*
X1294865Y1034022D01*
X1295007Y1034163D01*
X1295738Y1033432D01*
X1295597Y1033290D01*
G37*
G36*
G01X1297259Y1031628D02*
X1296875Y1031446D01*
X1296345Y1031977D01*
X1296527Y1032360D01*
X1296668Y1032502D01*
X1297400Y1031770D01*
X1297259Y1031628D01*
G37*
G36*
G01X1295979Y1033474D02*
X1296362Y1033656D01*
X1296893Y1033126D01*
X1296711Y1032742D01*
X1296569Y1032601D01*
X1295837Y1033333D01*
X1295979Y1033474D01*
G37*
G36*
G01X1293935Y1034952D02*
X1293552Y1034770D01*
X1293021Y1035300D01*
X1293203Y1035684D01*
X1293345Y1035825D01*
X1294077Y1035093D01*
X1293935Y1034952D01*
G37*
G36*
G01X1292655Y1036797D02*
X1293039Y1036980D01*
X1293569Y1036449D01*
X1293387Y1036066D01*
X1293246Y1035924D01*
X1292514Y1036656D01*
X1292655Y1036797D01*
G37*
G36*
G01X1292274Y1036614D02*
X1291890Y1036432D01*
X1291360Y1036962D01*
X1291542Y1037345D01*
X1291683Y1037487D01*
X1292415Y1036755D01*
X1292274Y1036614D01*
G37*
G36*
G01X1282648Y1043407D02*
X1283031Y1043589D01*
X1283562Y1043059D01*
X1283380Y1042675D01*
X1283238Y1042534D01*
X1282506Y1043266D01*
X1282648Y1043407D01*
G37*
G36*
G01X1284310Y1041745D02*
X1284693Y1041927D01*
X1285224Y1041397D01*
X1285041Y1041013D01*
X1284900Y1040872D01*
X1284168Y1041604D01*
X1284310Y1041745D01*
G37*
G36*
G01X1283928Y1041561D02*
X1283544Y1041379D01*
X1283014Y1041910D01*
X1283196Y1042293D01*
X1283337Y1042435D01*
X1284069Y1041703D01*
X1283928Y1041561D01*
G37*
G36*
G01X1285589Y1039900D02*
X1285206Y1039718D01*
X1284676Y1040248D01*
X1284858Y1040632D01*
X1284999Y1040773D01*
X1285731Y1040041D01*
X1285589Y1039900D01*
G37*
G36*
G01X1290956Y1035098D02*
X1291340Y1035281D01*
X1291870Y1034750D01*
X1291688Y1034367D01*
X1291547Y1034225D01*
X1290815Y1034957D01*
X1290956Y1035098D01*
G37*
G36*
G01X1290575Y1034915D02*
X1290191Y1034733D01*
X1289661Y1035263D01*
X1289843Y1035646D01*
X1289984Y1035788D01*
X1290716Y1035056D01*
X1290575Y1034915D01*
G37*
G36*
G01X1288913Y1036576D02*
X1288529Y1036394D01*
X1287999Y1036925D01*
X1288181Y1037308D01*
X1288322Y1037450D01*
X1289054Y1036718D01*
X1288913Y1036576D01*
G37*
G36*
G01X1285971Y1040084D02*
X1286355Y1040266D01*
X1286885Y1039735D01*
X1286703Y1039352D01*
X1286562Y1039210D01*
X1285830Y1039942D01*
X1285971Y1040084D01*
G37*
G36*
G01X1287251Y1038238D02*
X1286868Y1038056D01*
X1286337Y1038586D01*
X1286519Y1038970D01*
X1286661Y1039111D01*
X1287393Y1038379D01*
X1287251Y1038238D01*
G37*
G36*
G01X1289295Y1036760D02*
X1289678Y1036942D01*
X1290209Y1036412D01*
X1290027Y1036028D01*
X1289885Y1035887D01*
X1289153Y1036619D01*
X1289295Y1036760D01*
G37*
G36*
G01X1287633Y1038422D02*
X1288017Y1038604D01*
X1288547Y1038074D01*
X1288365Y1037690D01*
X1288223Y1037549D01*
X1287492Y1038280D01*
X1287633Y1038422D01*
G37*
G36*
G01X1294280Y1031775D02*
X1294663Y1031957D01*
X1295194Y1031427D01*
X1295012Y1031043D01*
X1294870Y1030902D01*
X1294138Y1031634D01*
X1294280Y1031775D01*
G37*
G36*
G01X1292618Y1033437D02*
X1293002Y1033619D01*
X1293532Y1033088D01*
X1293350Y1032705D01*
X1293209Y1032563D01*
X1292477Y1033295D01*
X1292618Y1033437D01*
G37*
G36*
G01X1293898Y1031591D02*
X1293514Y1031409D01*
X1292984Y1031939D01*
X1293166Y1032323D01*
X1293308Y1032464D01*
X1294039Y1031733D01*
X1293898Y1031591D01*
G37*
G36*
G01X1292236Y1033253D02*
X1291853Y1033071D01*
X1291322Y1033601D01*
X1291504Y1033985D01*
X1291646Y1034126D01*
X1292378Y1033394D01*
X1292236Y1033253D01*
G37*
G36*
G01X1281836Y1045918D02*
X1282219Y1046100D01*
X1282750Y1045570D01*
X1282568Y1045186D01*
X1282426Y1045045D01*
X1281694Y1045777D01*
X1281836Y1045918D01*
G37*
G36*
G01X1283497Y1044256D02*
X1283881Y1044439D01*
X1284411Y1043908D01*
X1284229Y1043525D01*
X1284088Y1043383D01*
X1283356Y1044115D01*
X1283497Y1044256D01*
G37*
G36*
G01X1283116Y1044073D02*
X1282732Y1043891D01*
X1282202Y1044421D01*
X1282384Y1044804D01*
X1282525Y1044946D01*
X1283257Y1044214D01*
X1283116Y1044073D01*
G37*
G36*
G01X1284777Y1042411D02*
X1284394Y1042229D01*
X1283863Y1042759D01*
X1284045Y1043143D01*
X1284187Y1043284D01*
X1284919Y1042552D01*
X1284777Y1042411D01*
G37*
G36*
G01X1291424Y1035764D02*
X1291040Y1035582D01*
X1290510Y1036112D01*
X1290692Y1036496D01*
X1290834Y1036637D01*
X1291565Y1035906D01*
X1291424Y1035764D01*
G37*
G36*
G01X1289762Y1037426D02*
X1289379Y1037244D01*
X1288848Y1037774D01*
X1289031Y1038158D01*
X1289172Y1038299D01*
X1289904Y1037567D01*
X1289762Y1037426D01*
G37*
G36*
G01X1288482Y1039271D02*
X1288866Y1039453D01*
X1289396Y1038923D01*
X1289214Y1038539D01*
X1289073Y1038398D01*
X1288341Y1039130D01*
X1288482Y1039271D01*
G37*
G36*
G01X1285159Y1042595D02*
X1285543Y1042777D01*
X1286073Y1042247D01*
X1285891Y1041863D01*
X1285750Y1041721D01*
X1285018Y1042453D01*
X1285159Y1042595D01*
G37*
G36*
G01X1286821Y1040933D02*
X1287204Y1041115D01*
X1287735Y1040585D01*
X1287553Y1040201D01*
X1287411Y1040060D01*
X1286679Y1040792D01*
X1286821Y1040933D01*
G37*
G36*
G01X1288101Y1039088D02*
X1287717Y1038905D01*
X1287187Y1039436D01*
X1287369Y1039819D01*
X1287510Y1039961D01*
X1288242Y1039229D01*
X1288101Y1039088D01*
G37*
G36*
G01X1286439Y1040749D02*
X1286055Y1040567D01*
X1285525Y1041097D01*
X1285707Y1041481D01*
X1285849Y1041622D01*
X1286580Y1040891D01*
X1286439Y1040749D01*
G37*
G36*
G01X1290144Y1037610D02*
X1290528Y1037792D01*
X1291058Y1037261D01*
X1290876Y1036878D01*
X1290735Y1036736D01*
X1290003Y1037468D01*
X1290144Y1037610D01*
G37*
G36*
G01X1293086Y1034102D02*
X1292702Y1033920D01*
X1292172Y1034451D01*
X1292354Y1034834D01*
X1292495Y1034976D01*
X1293227Y1034244D01*
X1293086Y1034102D01*
G37*
G36*
G01X1293468Y1034286D02*
X1293851Y1034468D01*
X1294382Y1033938D01*
X1294199Y1033554D01*
X1294058Y1033413D01*
X1293326Y1034145D01*
X1293468Y1034286D01*
G37*
G36*
G01X1294747Y1032441D02*
X1294364Y1032259D01*
X1293834Y1032789D01*
X1294016Y1033173D01*
X1294157Y1033314D01*
X1294889Y1032582D01*
X1294747Y1032441D01*
G37*
G36*
G01X1295129Y1032625D02*
X1295513Y1032807D01*
X1296043Y1032276D01*
X1295861Y1031893D01*
X1295720Y1031751D01*
X1294988Y1032483D01*
X1295129Y1032625D01*
G37*
G36*
G01X1291806Y1035948D02*
X1292190Y1036130D01*
X1292720Y1035600D01*
X1292538Y1035216D01*
X1292396Y1035075D01*
X1291664Y1035807D01*
X1291806Y1035948D01*
G37*
G36*
G01X1289725Y1034065D02*
X1289341Y1033883D01*
X1288811Y1034413D01*
X1288993Y1034797D01*
X1289135Y1034938D01*
X1289866Y1034207D01*
X1289725Y1034065D01*
G37*
G36*
G01X1291387Y1032403D02*
X1291003Y1032221D01*
X1290473Y1032752D01*
X1290655Y1033135D01*
X1290796Y1033277D01*
X1291528Y1032545D01*
X1291387Y1032403D01*
G37*
G36*
G01X1290107Y1034249D02*
X1290491Y1034431D01*
X1291021Y1033901D01*
X1290839Y1033517D01*
X1290697Y1033376D01*
X1289965Y1034108D01*
X1290107Y1034249D01*
G37*
G36*
G01X1285122Y1039234D02*
X1285505Y1039416D01*
X1286036Y1038886D01*
X1285854Y1038502D01*
X1285712Y1038361D01*
X1284980Y1039093D01*
X1285122Y1039234D01*
G37*
G36*
G01X1284740Y1039050D02*
X1284356Y1038868D01*
X1283826Y1039398D01*
X1284008Y1039782D01*
X1284150Y1039923D01*
X1284881Y1039192D01*
X1284740Y1039050D01*
G37*
G36*
G01X1283078Y1040712D02*
X1282695Y1040530D01*
X1282164Y1041060D01*
X1282346Y1041444D01*
X1282488Y1041585D01*
X1283220Y1040853D01*
X1283078Y1040712D01*
G37*
G36*
G01X1283460Y1040896D02*
X1283844Y1041078D01*
X1284374Y1040548D01*
X1284192Y1040164D01*
X1284051Y1040022D01*
X1283319Y1040754D01*
X1283460Y1040896D01*
G37*
G36*
G01X1281798Y1042557D02*
X1282182Y1042740D01*
X1282712Y1042209D01*
X1282530Y1041826D01*
X1282389Y1041684D01*
X1281657Y1042416D01*
X1281798Y1042557D01*
G37*
G36*
G01X1286402Y1037389D02*
X1286018Y1037206D01*
X1285488Y1037737D01*
X1285670Y1038120D01*
X1285811Y1038262D01*
X1286543Y1037530D01*
X1286402Y1037389D01*
G37*
G36*
G01X1288063Y1035727D02*
X1287680Y1035545D01*
X1287149Y1036075D01*
X1287332Y1036459D01*
X1287473Y1036600D01*
X1288205Y1035868D01*
X1288063Y1035727D01*
G37*
G36*
G01X1286783Y1037572D02*
X1287167Y1037754D01*
X1287697Y1037224D01*
X1287515Y1036840D01*
X1287374Y1036699D01*
X1286642Y1037431D01*
X1286783Y1037572D01*
G37*
G36*
G01X1288445Y1035911D02*
X1288829Y1036093D01*
X1289359Y1035562D01*
X1289177Y1035179D01*
X1289036Y1035037D01*
X1288304Y1035769D01*
X1288445Y1035911D01*
G37*
G36*
G01X1291769Y1032587D02*
X1292152Y1032769D01*
X1292683Y1032239D01*
X1292500Y1031855D01*
X1292359Y1031714D01*
X1291627Y1032446D01*
X1291769Y1032587D01*
G37*
G36*
G01X1282360Y1060113D02*
X1281976Y1059931D01*
X1281446Y1060461D01*
X1281628Y1060845D01*
X1281769Y1060986D01*
X1282501Y1060254D01*
X1282360Y1060113D01*
G37*
G36*
G01X1284021Y1058451D02*
X1283638Y1058269D01*
X1283107Y1058799D01*
X1283289Y1059183D01*
X1283431Y1059324D01*
X1284163Y1058592D01*
X1284021Y1058451D01*
G37*
G36*
G01X1282741Y1060297D02*
X1283125Y1060479D01*
X1283655Y1059948D01*
X1283473Y1059565D01*
X1283332Y1059423D01*
X1282600Y1060155D01*
X1282741Y1060297D01*
G37*
G36*
G01X1285683Y1056789D02*
X1285299Y1056607D01*
X1284769Y1057138D01*
X1284951Y1057521D01*
X1285092Y1057663D01*
X1285824Y1056931D01*
X1285683Y1056789D01*
G37*
G36*
G01X1284403Y1058635D02*
X1284787Y1058817D01*
X1285317Y1058287D01*
X1285135Y1057903D01*
X1284993Y1057762D01*
X1284262Y1058493D01*
X1284403Y1058635D01*
G37*
G36*
G01X1291050Y1051988D02*
X1291433Y1052170D01*
X1291964Y1051640D01*
X1291782Y1051256D01*
X1291640Y1051115D01*
X1290908Y1051847D01*
X1291050Y1051988D01*
G37*
G36*
G01X1289388Y1053650D02*
X1289772Y1053832D01*
X1290302Y1053301D01*
X1290120Y1052918D01*
X1289979Y1052776D01*
X1289247Y1053508D01*
X1289388Y1053650D01*
G37*
G36*
G01X1287345Y1055128D02*
X1286961Y1054945D01*
X1286431Y1055476D01*
X1286613Y1055859D01*
X1286754Y1056001D01*
X1287486Y1055269D01*
X1287345Y1055128D01*
G37*
G36*
G01X1289006Y1053466D02*
X1288623Y1053284D01*
X1288092Y1053814D01*
X1288274Y1054198D01*
X1288416Y1054339D01*
X1289148Y1053607D01*
X1289006Y1053466D01*
G37*
G36*
G01X1286065Y1056973D02*
X1286448Y1057155D01*
X1286979Y1056625D01*
X1286797Y1056241D01*
X1286655Y1056100D01*
X1285923Y1056832D01*
X1286065Y1056973D01*
G37*
G36*
G01X1287726Y1055311D02*
X1288110Y1055493D01*
X1288640Y1054963D01*
X1288458Y1054580D01*
X1288317Y1054438D01*
X1287585Y1055170D01*
X1287726Y1055311D01*
G37*
G36*
G01X1290668Y1051804D02*
X1290284Y1051622D01*
X1289754Y1052152D01*
X1289936Y1052536D01*
X1290078Y1052677D01*
X1290809Y1051946D01*
X1290668Y1051804D01*
G37*
G36*
G01X1292712Y1050326D02*
X1293095Y1050508D01*
X1293625Y1049978D01*
X1293443Y1049594D01*
X1293302Y1049453D01*
X1292570Y1050185D01*
X1292712Y1050326D01*
G37*
G36*
G01X1292330Y1050142D02*
X1291946Y1049960D01*
X1291416Y1050491D01*
X1291598Y1050874D01*
X1291739Y1051016D01*
X1292471Y1050284D01*
X1292330Y1050142D01*
G37*
G36*
G01X1293991Y1048481D02*
X1293608Y1048299D01*
X1293077Y1048829D01*
X1293260Y1049213D01*
X1293401Y1049354D01*
X1294133Y1048622D01*
X1293991Y1048481D01*
G37*
G36*
G01X1294373Y1048665D02*
X1294757Y1048847D01*
X1295287Y1048316D01*
X1295105Y1047933D01*
X1294964Y1047791D01*
X1294232Y1048523D01*
X1294373Y1048665D01*
G37*
G36*
G01X1283984Y1055091D02*
X1283601Y1054909D01*
X1283070Y1055439D01*
X1283253Y1055823D01*
X1283394Y1055964D01*
X1284126Y1055232D01*
X1283984Y1055091D01*
G37*
G36*
G01X1282705Y1056936D02*
X1283088Y1057118D01*
X1283618Y1056588D01*
X1283436Y1056204D01*
X1283295Y1056063D01*
X1282563Y1056795D01*
X1282705Y1056936D01*
G37*
G36*
G01X1285646Y1053429D02*
X1285262Y1053247D01*
X1284732Y1053777D01*
X1284914Y1054161D01*
X1285056Y1054302D01*
X1285788Y1053570D01*
X1285646Y1053429D01*
G37*
G36*
G01X1284366Y1055275D02*
X1284750Y1055457D01*
X1285280Y1054926D01*
X1285098Y1054543D01*
X1284957Y1054401D01*
X1284225Y1055133D01*
X1284366Y1055275D01*
G37*
G36*
G01X1291013Y1048628D02*
X1291397Y1048810D01*
X1291927Y1048280D01*
X1291745Y1047896D01*
X1291603Y1047755D01*
X1290872Y1048486D01*
X1291013Y1048628D01*
G37*
G36*
G01X1290631Y1048444D02*
X1290248Y1048262D01*
X1289717Y1048792D01*
X1289899Y1049176D01*
X1290041Y1049317D01*
X1290773Y1048585D01*
X1290631Y1048444D01*
G37*
G36*
G01X1289351Y1050289D02*
X1289735Y1050472D01*
X1290265Y1049941D01*
X1290083Y1049558D01*
X1289942Y1049416D01*
X1289210Y1050148D01*
X1289351Y1050289D01*
G37*
G36*
G01X1287690Y1051951D02*
X1288073Y1052133D01*
X1288604Y1051603D01*
X1288421Y1051219D01*
X1288280Y1051078D01*
X1287548Y1051810D01*
X1287690Y1051951D01*
G37*
G36*
G01X1288970Y1050106D02*
X1288586Y1049924D01*
X1288056Y1050454D01*
X1288238Y1050838D01*
X1288379Y1050979D01*
X1289111Y1050247D01*
X1288970Y1050106D01*
G37*
G36*
G01X1287308Y1051767D02*
X1286924Y1051585D01*
X1286394Y1052116D01*
X1286576Y1052499D01*
X1286717Y1052641D01*
X1287449Y1051909D01*
X1287308Y1051767D01*
G37*
G36*
G01X1286028Y1053613D02*
X1286412Y1053795D01*
X1286942Y1053265D01*
X1286760Y1052881D01*
X1286618Y1052740D01*
X1285887Y1053471D01*
X1286028Y1053613D01*
G37*
G36*
G01X1283172Y1057602D02*
X1282789Y1057420D01*
X1282258Y1057950D01*
X1282440Y1058334D01*
X1282582Y1058475D01*
X1283314Y1057743D01*
X1283172Y1057602D01*
G37*
G36*
G01X1283554Y1057786D02*
X1283938Y1057968D01*
X1284468Y1057438D01*
X1284286Y1057054D01*
X1284144Y1056913D01*
X1283413Y1057644D01*
X1283554Y1057786D01*
G37*
G36*
G01X1281892Y1059448D02*
X1282276Y1059630D01*
X1282806Y1059099D01*
X1282624Y1058716D01*
X1282483Y1058574D01*
X1281751Y1059306D01*
X1281892Y1059448D01*
G37*
G36*
G01X1284834Y1055940D02*
X1284450Y1055758D01*
X1283920Y1056289D01*
X1284102Y1056672D01*
X1284243Y1056814D01*
X1284975Y1056082D01*
X1284834Y1055940D01*
G37*
G36*
G01X1291481Y1049293D02*
X1291097Y1049111D01*
X1290567Y1049642D01*
X1290749Y1050025D01*
X1290890Y1050167D01*
X1291622Y1049435D01*
X1291481Y1049293D01*
G37*
G36*
G01X1289819Y1050955D02*
X1289435Y1050773D01*
X1288905Y1051303D01*
X1289087Y1051687D01*
X1289229Y1051828D01*
X1289960Y1051097D01*
X1289819Y1050955D01*
G37*
G36*
G01X1290201Y1051139D02*
X1290584Y1051321D01*
X1291115Y1050791D01*
X1290933Y1050407D01*
X1290791Y1050266D01*
X1290059Y1050998D01*
X1290201Y1051139D01*
G37*
G36*
G01X1288157Y1052617D02*
X1287774Y1052435D01*
X1287243Y1052965D01*
X1287425Y1053349D01*
X1287567Y1053490D01*
X1288299Y1052758D01*
X1288157Y1052617D01*
G37*
G36*
G01X1285216Y1056124D02*
X1285599Y1056306D01*
X1286130Y1055776D01*
X1285948Y1055392D01*
X1285806Y1055251D01*
X1285074Y1055983D01*
X1285216Y1056124D01*
G37*
G36*
G01X1286877Y1054462D02*
X1287261Y1054644D01*
X1287791Y1054114D01*
X1287609Y1053731D01*
X1287468Y1053589D01*
X1286736Y1054321D01*
X1286877Y1054462D01*
G37*
G36*
G01X1288539Y1052801D02*
X1288923Y1052983D01*
X1289453Y1052452D01*
X1289271Y1052069D01*
X1289130Y1051927D01*
X1288398Y1052659D01*
X1288539Y1052801D01*
G37*
G36*
G01X1286496Y1054279D02*
X1286112Y1054096D01*
X1285582Y1054627D01*
X1285764Y1055010D01*
X1285905Y1055152D01*
X1286637Y1054420D01*
X1286496Y1054279D01*
G37*
G36*
G01X1293524Y1047816D02*
X1293908Y1047998D01*
X1294438Y1047467D01*
X1294256Y1047084D01*
X1294115Y1046942D01*
X1293383Y1047674D01*
X1293524Y1047816D01*
G37*
G36*
G01X1291863Y1049477D02*
X1292246Y1049659D01*
X1292776Y1049129D01*
X1292594Y1048745D01*
X1292453Y1048604D01*
X1291721Y1049336D01*
X1291863Y1049477D01*
G37*
G36*
G01X1293142Y1047632D02*
X1292759Y1047450D01*
X1292228Y1047980D01*
X1292411Y1048364D01*
X1292552Y1048505D01*
X1293284Y1047773D01*
X1293142Y1047632D01*
G37*
G36*
G01X1281856Y1056087D02*
X1282239Y1056269D01*
X1282769Y1055739D01*
X1282587Y1055355D01*
X1282446Y1055214D01*
X1281714Y1055946D01*
X1281856Y1056087D01*
G37*
G36*
G01X1283517Y1054426D02*
X1283901Y1054608D01*
X1284431Y1054077D01*
X1284249Y1053694D01*
X1284108Y1053552D01*
X1283376Y1054284D01*
X1283517Y1054426D01*
G37*
G36*
G01X1283135Y1054242D02*
X1282752Y1054060D01*
X1282221Y1054590D01*
X1282404Y1054974D01*
X1282545Y1055115D01*
X1283277Y1054383D01*
X1283135Y1054242D01*
G37*
G36*
G01X1284797Y1052580D02*
X1284413Y1052398D01*
X1283883Y1052928D01*
X1284065Y1053312D01*
X1284207Y1053453D01*
X1284939Y1052721D01*
X1284797Y1052580D01*
G37*
G36*
G01X1286459Y1050918D02*
X1286075Y1050736D01*
X1285545Y1051267D01*
X1285727Y1051650D01*
X1285868Y1051792D01*
X1286600Y1051060D01*
X1286459Y1050918D01*
G37*
G36*
G01X1286841Y1051102D02*
X1287224Y1051284D01*
X1287755Y1050754D01*
X1287572Y1050370D01*
X1287431Y1050229D01*
X1286699Y1050961D01*
X1286841Y1051102D01*
G37*
G36*
G01X1288502Y1049440D02*
X1288886Y1049623D01*
X1289416Y1049092D01*
X1289234Y1048709D01*
X1289093Y1048567D01*
X1288361Y1049299D01*
X1288502Y1049440D01*
G37*
G36*
G01X1289782Y1047595D02*
X1289399Y1047413D01*
X1288868Y1047943D01*
X1289050Y1048327D01*
X1289192Y1048468D01*
X1289924Y1047736D01*
X1289782Y1047595D01*
G37*
G36*
G01X1288121Y1049257D02*
X1287737Y1049075D01*
X1287207Y1049605D01*
X1287389Y1049989D01*
X1287530Y1050130D01*
X1288262Y1049398D01*
X1288121Y1049257D01*
G37*
G36*
G01X1285179Y1052764D02*
X1285563Y1052946D01*
X1286093Y1052416D01*
X1285911Y1052032D01*
X1285769Y1051891D01*
X1285038Y1052622D01*
X1285179Y1052764D01*
G37*
G36*
G01X1293462Y1063347D02*
X1293079Y1063165D01*
X1292548Y1063695D01*
X1292730Y1064079D01*
X1292872Y1064220D01*
X1293604Y1063488D01*
X1293462Y1063347D01*
G37*
G36*
G01X1293844Y1063531D02*
X1294228Y1063713D01*
X1294758Y1063183D01*
X1294576Y1062799D01*
X1294434Y1062658D01*
X1293703Y1063389D01*
X1293844Y1063531D01*
G37*
G36*
G01X1295124Y1061685D02*
X1294740Y1061503D01*
X1294210Y1062033D01*
X1294392Y1062417D01*
X1294533Y1062559D01*
X1295265Y1061827D01*
X1295124Y1061685D01*
G37*
G36*
G01X1297167Y1060207D02*
X1297551Y1060389D01*
X1298081Y1059859D01*
X1297899Y1059476D01*
X1297758Y1059334D01*
X1297026Y1060066D01*
X1297167Y1060207D01*
G37*
G36*
G01X1296786Y1060024D02*
X1296402Y1059841D01*
X1295872Y1060372D01*
X1296054Y1060755D01*
X1296195Y1060897D01*
X1296927Y1060165D01*
X1296786Y1060024D01*
G37*
G36*
G01X1298447Y1058362D02*
X1298064Y1058180D01*
X1297533Y1058710D01*
X1297715Y1059094D01*
X1297857Y1059235D01*
X1298589Y1058503D01*
X1298447Y1058362D01*
G37*
G36*
G01X1295506Y1061869D02*
X1295889Y1062051D01*
X1296420Y1061521D01*
X1296238Y1061137D01*
X1296096Y1060996D01*
X1295364Y1061728D01*
X1295506Y1061869D01*
G37*
G36*
G01X1291763Y1061647D02*
X1291379Y1061465D01*
X1290849Y1061996D01*
X1291031Y1062379D01*
X1291172Y1062521D01*
X1291904Y1061789D01*
X1291763Y1061647D01*
G37*
G36*
G01X1290101Y1063309D02*
X1289717Y1063127D01*
X1289187Y1063657D01*
X1289369Y1064041D01*
X1289511Y1064182D01*
X1290242Y1063451D01*
X1290101Y1063309D01*
G37*
G36*
G01X1290483Y1063493D02*
X1290866Y1063675D01*
X1291397Y1063145D01*
X1291215Y1062761D01*
X1291073Y1062620D01*
X1290341Y1063352D01*
X1290483Y1063493D01*
G37*
G36*
G01X1295086Y1058324D02*
X1294703Y1058142D01*
X1294172Y1058672D01*
X1294354Y1059056D01*
X1294496Y1059197D01*
X1295228Y1058465D01*
X1295086Y1058324D01*
G37*
G36*
G01X1293424Y1059986D02*
X1293041Y1059804D01*
X1292510Y1060334D01*
X1292693Y1060718D01*
X1292834Y1060859D01*
X1293566Y1060127D01*
X1293424Y1059986D01*
G37*
G36*
G01X1293806Y1060170D02*
X1294190Y1060352D01*
X1294720Y1059821D01*
X1294538Y1059438D01*
X1294397Y1059296D01*
X1293665Y1060028D01*
X1293806Y1060170D01*
G37*
G36*
G01X1292145Y1061831D02*
X1292528Y1062013D01*
X1293058Y1061483D01*
X1292876Y1061099D01*
X1292735Y1060958D01*
X1292003Y1061690D01*
X1292145Y1061831D01*
G37*
G36*
G01X1298410Y1055001D02*
X1298026Y1054819D01*
X1297496Y1055349D01*
X1297678Y1055733D01*
X1297819Y1055874D01*
X1298551Y1055142D01*
X1298410Y1055001D01*
G37*
G36*
G01X1297130Y1056846D02*
X1297513Y1057028D01*
X1298044Y1056498D01*
X1297862Y1056114D01*
X1297720Y1055973D01*
X1296988Y1056705D01*
X1297130Y1056846D01*
G37*
G36*
G01X1296748Y1056662D02*
X1296364Y1056480D01*
X1295834Y1057011D01*
X1296016Y1057394D01*
X1296157Y1057536D01*
X1296889Y1056804D01*
X1296748Y1056662D01*
G37*
G36*
G01X1295468Y1058508D02*
X1295852Y1058690D01*
X1296382Y1058160D01*
X1296200Y1057776D01*
X1296058Y1057635D01*
X1295327Y1058366D01*
X1295468Y1058508D01*
G37*
G36*
G01X1294275Y1060836D02*
X1293891Y1060654D01*
X1293361Y1061184D01*
X1293543Y1061568D01*
X1293684Y1061710D01*
X1294416Y1060978D01*
X1294275Y1060836D01*
G37*
G36*
G01X1292995Y1062682D02*
X1293379Y1062864D01*
X1293909Y1062334D01*
X1293727Y1061950D01*
X1293585Y1061809D01*
X1292854Y1062540D01*
X1292995Y1062682D01*
G37*
G36*
G01X1292613Y1062498D02*
X1292230Y1062316D01*
X1291699Y1062846D01*
X1291881Y1063230D01*
X1292023Y1063371D01*
X1292755Y1062639D01*
X1292613Y1062498D01*
G37*
G36*
G01X1294657Y1061020D02*
X1295040Y1061202D01*
X1295571Y1060672D01*
X1295389Y1060288D01*
X1295247Y1060147D01*
X1294515Y1060879D01*
X1294657Y1061020D01*
G37*
G36*
G01X1297598Y1057513D02*
X1297215Y1057331D01*
X1296684Y1057861D01*
X1296866Y1058245D01*
X1297008Y1058386D01*
X1297740Y1057654D01*
X1297598Y1057513D01*
G37*
G36*
G01X1295937Y1059175D02*
X1295553Y1058992D01*
X1295023Y1059523D01*
X1295205Y1059906D01*
X1295346Y1060048D01*
X1296078Y1059316D01*
X1295937Y1059175D01*
G37*
G36*
G01X1296318Y1059358D02*
X1296702Y1059540D01*
X1297232Y1059010D01*
X1297050Y1058627D01*
X1296909Y1058485D01*
X1296177Y1059217D01*
X1296318Y1059358D01*
G37*
G36*
G01X1289252Y1062460D02*
X1288868Y1062278D01*
X1288338Y1062808D01*
X1288520Y1063192D01*
X1288661Y1063333D01*
X1289393Y1062601D01*
X1289252Y1062460D01*
G37*
G36*
G01X1289633Y1062643D02*
X1290017Y1062826D01*
X1290547Y1062295D01*
X1290365Y1061912D01*
X1290224Y1061770D01*
X1289492Y1062502D01*
X1289633Y1062643D01*
G37*
G36*
G01X1290913Y1060798D02*
X1290530Y1060616D01*
X1289999Y1061146D01*
X1290181Y1061530D01*
X1290323Y1061671D01*
X1291055Y1060939D01*
X1290913Y1060798D01*
G37*
G36*
G01X1291295Y1060982D02*
X1291679Y1061164D01*
X1292209Y1060634D01*
X1292027Y1060250D01*
X1291885Y1060109D01*
X1291154Y1060840D01*
X1291295Y1060982D01*
G37*
G36*
G01X1292575Y1059136D02*
X1292191Y1058954D01*
X1291661Y1059484D01*
X1291843Y1059868D01*
X1291984Y1060010D01*
X1292716Y1059278D01*
X1292575Y1059136D01*
G37*
G36*
G01X1292957Y1059320D02*
X1293340Y1059502D01*
X1293871Y1058972D01*
X1293689Y1058588D01*
X1293547Y1058447D01*
X1292815Y1059179D01*
X1292957Y1059320D01*
G37*
G36*
G01X1294237Y1057475D02*
X1293853Y1057292D01*
X1293323Y1057823D01*
X1293505Y1058206D01*
X1293646Y1058348D01*
X1294378Y1057616D01*
X1294237Y1057475D01*
G37*
G36*
G01X1294618Y1057658D02*
X1295002Y1057840D01*
X1295532Y1057310D01*
X1295350Y1056927D01*
X1295209Y1056785D01*
X1294477Y1057517D01*
X1294618Y1057658D01*
G37*
G36*
G01X1295898Y1055813D02*
X1295515Y1055631D01*
X1294984Y1056161D01*
X1295166Y1056545D01*
X1295308Y1056686D01*
X1296040Y1055954D01*
X1295898Y1055813D01*
G37*
G36*
G01X1296280Y1055997D02*
X1296664Y1056179D01*
X1297194Y1055648D01*
X1297012Y1055265D01*
X1296871Y1055123D01*
X1296139Y1055855D01*
X1296280Y1055997D01*
G37*
G36*
G01X1297560Y1054151D02*
X1297176Y1053969D01*
X1296646Y1054499D01*
X1296828Y1054883D01*
X1296970Y1055024D01*
X1297701Y1054293D01*
X1297560Y1054151D01*
G37*
G36*
G01X1297444Y1078712D02*
X1297828Y1078895D01*
X1298358Y1078364D01*
X1298176Y1077981D01*
X1298035Y1077839D01*
X1297303Y1078571D01*
X1297444Y1078712D01*
G37*
G36*
G01X1297063Y1078529D02*
X1296679Y1078346D01*
X1296149Y1078877D01*
X1296331Y1079260D01*
X1296472Y1079402D01*
X1297204Y1078670D01*
X1297063Y1078529D01*
G37*
G36*
G01X1297912Y1079378D02*
X1297528Y1079196D01*
X1296998Y1079726D01*
X1297180Y1080110D01*
X1297321Y1080251D01*
X1298053Y1079519D01*
X1297912Y1079378D01*
G37*
G36*
G01X1294551Y1079341D02*
X1294168Y1079159D01*
X1293638Y1079689D01*
X1293820Y1080072D01*
X1293961Y1080214D01*
X1294693Y1079482D01*
X1294551Y1079341D01*
G37*
G36*
G01X1297875Y1076017D02*
X1297492Y1075835D01*
X1296961Y1076366D01*
X1297143Y1076749D01*
X1297285Y1076891D01*
X1298017Y1076159D01*
X1297875Y1076017D01*
G37*
G36*
G01X1294933Y1079524D02*
X1295317Y1079707D01*
X1295847Y1079176D01*
X1295665Y1078793D01*
X1295524Y1078651D01*
X1294792Y1079383D01*
X1294933Y1079524D01*
G37*
G36*
G01X1296595Y1077863D02*
X1296979Y1078045D01*
X1297509Y1077515D01*
X1297327Y1077131D01*
X1297186Y1076990D01*
X1296454Y1077721D01*
X1296595Y1077863D01*
G37*
G36*
G01X1296213Y1077679D02*
X1295830Y1077497D01*
X1295299Y1078027D01*
X1295481Y1078411D01*
X1295623Y1078552D01*
X1296355Y1077820D01*
X1296213Y1077679D01*
G37*
G36*
G01X1291049Y1079916D02*
X1291433Y1080098D01*
X1291963Y1079568D01*
X1291781Y1079184D01*
X1291639Y1079043D01*
X1290908Y1079774D01*
X1291049Y1079916D01*
G37*
G36*
G01X1294372Y1076592D02*
X1294756Y1076774D01*
X1295286Y1076244D01*
X1295104Y1075861D01*
X1294963Y1075719D01*
X1294231Y1076451D01*
X1294372Y1076592D01*
G37*
G36*
G01X1293991Y1076409D02*
X1293607Y1076226D01*
X1293077Y1076757D01*
X1293259Y1077140D01*
X1293400Y1077282D01*
X1294132Y1076550D01*
X1293991Y1076409D01*
G37*
G36*
G01X1292711Y1078254D02*
X1293094Y1078436D01*
X1293625Y1077906D01*
X1293443Y1077522D01*
X1293301Y1077381D01*
X1292569Y1078113D01*
X1292711Y1078254D01*
G37*
G36*
G01X1292329Y1078070D02*
X1291945Y1077888D01*
X1291415Y1078419D01*
X1291597Y1078802D01*
X1291738Y1078944D01*
X1292470Y1078212D01*
X1292329Y1078070D01*
G37*
G36*
G01X1297696Y1073269D02*
X1298079Y1073451D01*
X1298610Y1072921D01*
X1298428Y1072537D01*
X1298286Y1072396D01*
X1297554Y1073128D01*
X1297696Y1073269D01*
G37*
G36*
G01X1295652Y1074747D02*
X1295269Y1074565D01*
X1294738Y1075095D01*
X1294920Y1075479D01*
X1295062Y1075620D01*
X1295794Y1074888D01*
X1295652Y1074747D01*
G37*
G36*
G01X1297314Y1073085D02*
X1296930Y1072903D01*
X1296400Y1073433D01*
X1296582Y1073817D01*
X1296724Y1073958D01*
X1297455Y1073227D01*
X1297314Y1073085D01*
G37*
G36*
G01X1296034Y1074931D02*
X1296418Y1075113D01*
X1296948Y1074582D01*
X1296766Y1074199D01*
X1296625Y1074057D01*
X1295893Y1074789D01*
X1296034Y1074931D01*
G37*
G36*
G01X1291013Y1076556D02*
X1291396Y1076738D01*
X1291927Y1076208D01*
X1291745Y1075824D01*
X1291603Y1075683D01*
X1290871Y1076415D01*
X1291013Y1076556D01*
G37*
G36*
G01X1290631Y1076372D02*
X1290247Y1076190D01*
X1289717Y1076721D01*
X1289899Y1077104D01*
X1290040Y1077246D01*
X1290772Y1076514D01*
X1290631Y1076372D01*
G37*
G36*
G01X1289351Y1078218D02*
X1289735Y1078400D01*
X1290265Y1077870D01*
X1290083Y1077486D01*
X1289941Y1077345D01*
X1289210Y1078076D01*
X1289351Y1078218D01*
G37*
G36*
G01X1288969Y1078034D02*
X1288586Y1077852D01*
X1288055Y1078382D01*
X1288237Y1078766D01*
X1288379Y1078907D01*
X1289111Y1078175D01*
X1288969Y1078034D01*
G37*
G36*
G01X1287689Y1079880D02*
X1288073Y1080062D01*
X1288603Y1079531D01*
X1288421Y1079148D01*
X1288280Y1079006D01*
X1287548Y1079738D01*
X1287689Y1079880D01*
G37*
G36*
G01X1294336Y1073233D02*
X1294720Y1073415D01*
X1295250Y1072884D01*
X1295068Y1072501D01*
X1294927Y1072359D01*
X1294195Y1073091D01*
X1294336Y1073233D01*
G37*
G36*
G01X1293954Y1073049D02*
X1293571Y1072867D01*
X1293040Y1073397D01*
X1293222Y1073781D01*
X1293364Y1073922D01*
X1294096Y1073190D01*
X1293954Y1073049D01*
G37*
G36*
G01X1292674Y1074894D02*
X1293058Y1075076D01*
X1293588Y1074546D01*
X1293406Y1074163D01*
X1293265Y1074021D01*
X1292533Y1074753D01*
X1292674Y1074894D01*
G37*
G36*
G01X1292293Y1074711D02*
X1291909Y1074528D01*
X1291379Y1075059D01*
X1291561Y1075442D01*
X1291702Y1075584D01*
X1292434Y1074852D01*
X1292293Y1074711D01*
G37*
G36*
G01X1297660Y1069909D02*
X1298043Y1070091D01*
X1298573Y1069561D01*
X1298391Y1069177D01*
X1298250Y1069036D01*
X1297518Y1069768D01*
X1297660Y1069909D01*
G37*
G36*
G01X1295616Y1071387D02*
X1295232Y1071205D01*
X1294702Y1071735D01*
X1294884Y1072119D01*
X1295026Y1072260D01*
X1295757Y1071529D01*
X1295616Y1071387D01*
G37*
G36*
G01X1297278Y1069725D02*
X1296894Y1069543D01*
X1296364Y1070074D01*
X1296546Y1070457D01*
X1296687Y1070599D01*
X1297419Y1069867D01*
X1297278Y1069725D01*
G37*
G36*
G01X1295998Y1071571D02*
X1296381Y1071753D01*
X1296912Y1071223D01*
X1296730Y1070839D01*
X1296588Y1070698D01*
X1295856Y1071430D01*
X1295998Y1071571D01*
G37*
G36*
G01X1289818Y1078883D02*
X1289435Y1078701D01*
X1288904Y1079231D01*
X1289086Y1079615D01*
X1289228Y1079756D01*
X1289960Y1079024D01*
X1289818Y1078883D01*
G37*
G36*
G01X1290200Y1079067D02*
X1290584Y1079249D01*
X1291114Y1078719D01*
X1290932Y1078335D01*
X1290790Y1078194D01*
X1290059Y1078925D01*
X1290200Y1079067D01*
G37*
G36*
G01X1291480Y1077221D02*
X1291096Y1077039D01*
X1290566Y1077570D01*
X1290748Y1077953D01*
X1290889Y1078095D01*
X1291621Y1077363D01*
X1291480Y1077221D01*
G37*
G36*
G01X1293142Y1075560D02*
X1292758Y1075377D01*
X1292228Y1075908D01*
X1292410Y1076291D01*
X1292551Y1076433D01*
X1293283Y1075701D01*
X1293142Y1075560D01*
G37*
G36*
G01X1291862Y1077405D02*
X1292245Y1077587D01*
X1292776Y1077057D01*
X1292594Y1076673D01*
X1292452Y1076532D01*
X1291720Y1077264D01*
X1291862Y1077405D01*
G37*
G36*
G01X1294803Y1073898D02*
X1294420Y1073716D01*
X1293889Y1074246D01*
X1294071Y1074630D01*
X1294213Y1074771D01*
X1294945Y1074039D01*
X1294803Y1073898D01*
G37*
G36*
G01X1293523Y1075743D02*
X1293907Y1075925D01*
X1294437Y1075395D01*
X1294255Y1075012D01*
X1294114Y1074870D01*
X1293382Y1075602D01*
X1293523Y1075743D01*
G37*
G36*
G01X1296465Y1072236D02*
X1296081Y1072054D01*
X1295551Y1072584D01*
X1295733Y1072968D01*
X1295875Y1073109D01*
X1296606Y1072378D01*
X1296465Y1072236D01*
G37*
G36*
G01X1295185Y1074082D02*
X1295569Y1074264D01*
X1296099Y1073733D01*
X1295917Y1073350D01*
X1295776Y1073208D01*
X1295044Y1073940D01*
X1295185Y1074082D01*
G37*
G36*
G01X1296847Y1072420D02*
X1297230Y1072602D01*
X1297761Y1072072D01*
X1297579Y1071688D01*
X1297437Y1071547D01*
X1296705Y1072279D01*
X1296847Y1072420D01*
G37*
G36*
G01X1298127Y1070574D02*
X1297743Y1070392D01*
X1297213Y1070923D01*
X1297395Y1071306D01*
X1297536Y1071448D01*
X1298268Y1070716D01*
X1298127Y1070574D01*
G37*
G36*
G01X1288119Y1077184D02*
X1287736Y1077002D01*
X1287205Y1077532D01*
X1287387Y1077916D01*
X1287529Y1078057D01*
X1288261Y1077325D01*
X1288119Y1077184D01*
G37*
G36*
G01X1286839Y1079030D02*
X1287223Y1079212D01*
X1287753Y1078681D01*
X1287571Y1078298D01*
X1287430Y1078156D01*
X1286698Y1078888D01*
X1286839Y1079030D01*
G37*
G36*
G01X1288501Y1077368D02*
X1288885Y1077550D01*
X1289415Y1077020D01*
X1289233Y1076636D01*
X1289091Y1076495D01*
X1288360Y1077226D01*
X1288501Y1077368D01*
G37*
G36*
G01X1286458Y1078846D02*
X1286074Y1078664D01*
X1285544Y1079194D01*
X1285726Y1079578D01*
X1285867Y1079719D01*
X1286599Y1078987D01*
X1286458Y1078846D01*
G37*
G36*
G01X1289781Y1075522D02*
X1289397Y1075340D01*
X1288867Y1075871D01*
X1289049Y1076254D01*
X1289190Y1076396D01*
X1289922Y1075664D01*
X1289781Y1075522D01*
G37*
G36*
G01X1291443Y1073861D02*
X1291059Y1073678D01*
X1290529Y1074209D01*
X1290711Y1074592D01*
X1290852Y1074734D01*
X1291584Y1074002D01*
X1291443Y1073861D01*
G37*
G36*
G01X1290163Y1075706D02*
X1290546Y1075888D01*
X1291077Y1075358D01*
X1290895Y1074974D01*
X1290753Y1074833D01*
X1290021Y1075565D01*
X1290163Y1075706D01*
G37*
G36*
G01X1291824Y1074044D02*
X1292208Y1074226D01*
X1292738Y1073696D01*
X1292556Y1073313D01*
X1292415Y1073171D01*
X1291683Y1073903D01*
X1291824Y1074044D01*
G37*
G36*
G01X1293104Y1072199D02*
X1292721Y1072017D01*
X1292190Y1072547D01*
X1292372Y1072931D01*
X1292514Y1073072D01*
X1293246Y1072340D01*
X1293104Y1072199D01*
G37*
G36*
G01X1294766Y1070537D02*
X1294382Y1070355D01*
X1293852Y1070885D01*
X1294034Y1071269D01*
X1294176Y1071410D01*
X1294907Y1070679D01*
X1294766Y1070537D01*
G37*
G36*
G01X1293486Y1072383D02*
X1293870Y1072565D01*
X1294400Y1072034D01*
X1294218Y1071651D01*
X1294077Y1071509D01*
X1293345Y1072241D01*
X1293486Y1072383D01*
G37*
G36*
G01X1298089Y1067214D02*
X1297706Y1067032D01*
X1297175Y1067562D01*
X1297358Y1067946D01*
X1297499Y1068087D01*
X1298231Y1067355D01*
X1298089Y1067214D01*
G37*
G36*
G01X1296428Y1068875D02*
X1296044Y1068693D01*
X1295514Y1069224D01*
X1295696Y1069607D01*
X1295837Y1069749D01*
X1296569Y1069017D01*
X1296428Y1068875D01*
G37*
G36*
G01X1295148Y1070721D02*
X1295531Y1070903D01*
X1296062Y1070373D01*
X1295880Y1069989D01*
X1295738Y1069848D01*
X1295006Y1070580D01*
X1295148Y1070721D01*
G37*
G36*
G01X1296810Y1069059D02*
X1297193Y1069241D01*
X1297723Y1068711D01*
X1297541Y1068327D01*
X1297400Y1068186D01*
X1296668Y1068918D01*
X1296810Y1069059D01*
G37*
G36*
G01X1291801Y1065009D02*
X1291417Y1064827D01*
X1290887Y1065357D01*
X1291069Y1065741D01*
X1291210Y1065882D01*
X1291942Y1065150D01*
X1291801Y1065009D01*
G37*
G36*
G01X1290521Y1066854D02*
X1290904Y1067036D01*
X1291435Y1066506D01*
X1291252Y1066122D01*
X1291111Y1065981D01*
X1290379Y1066713D01*
X1290521Y1066854D01*
G37*
G36*
G01X1283874Y1073501D02*
X1284257Y1073683D01*
X1284788Y1073153D01*
X1284606Y1072769D01*
X1284464Y1072628D01*
X1283732Y1073360D01*
X1283874Y1073501D01*
G37*
G36*
G01X1283492Y1073317D02*
X1283108Y1073135D01*
X1282578Y1073665D01*
X1282760Y1074049D01*
X1282902Y1074190D01*
X1283633Y1073459D01*
X1283492Y1073317D01*
G37*
G36*
G01X1282212Y1075163D02*
X1282596Y1075345D01*
X1283126Y1074814D01*
X1282944Y1074431D01*
X1282803Y1074289D01*
X1282071Y1075021D01*
X1282212Y1075163D01*
G37*
G36*
G01X1285154Y1071655D02*
X1284770Y1071473D01*
X1284240Y1072004D01*
X1284422Y1072387D01*
X1284563Y1072529D01*
X1285295Y1071797D01*
X1285154Y1071655D01*
G37*
G36*
G01X1290139Y1066670D02*
X1289755Y1066488D01*
X1289225Y1067019D01*
X1289407Y1067402D01*
X1289548Y1067544D01*
X1290280Y1066812D01*
X1290139Y1066670D01*
G37*
G36*
G01X1288859Y1068516D02*
X1289243Y1068698D01*
X1289773Y1068168D01*
X1289591Y1067784D01*
X1289449Y1067643D01*
X1288718Y1068374D01*
X1288859Y1068516D01*
G37*
G36*
G01X1288477Y1068332D02*
X1288093Y1068150D01*
X1287563Y1068680D01*
X1287745Y1069064D01*
X1287887Y1069205D01*
X1288619Y1068473D01*
X1288477Y1068332D01*
G37*
G36*
G01X1286815Y1069994D02*
X1286432Y1069812D01*
X1285901Y1070342D01*
X1286084Y1070726D01*
X1286225Y1070867D01*
X1286957Y1070135D01*
X1286815Y1069994D01*
G37*
G36*
G01X1285536Y1071839D02*
X1285919Y1072021D01*
X1286449Y1071491D01*
X1286267Y1071107D01*
X1286126Y1070966D01*
X1285394Y1071698D01*
X1285536Y1071839D01*
G37*
G36*
G01X1287197Y1070178D02*
X1287581Y1070360D01*
X1288111Y1069829D01*
X1287929Y1069446D01*
X1287788Y1069304D01*
X1287056Y1070036D01*
X1287197Y1070178D01*
G37*
G36*
G01X1292182Y1065192D02*
X1292566Y1065375D01*
X1293096Y1064844D01*
X1292914Y1064461D01*
X1292773Y1064319D01*
X1292041Y1065051D01*
X1292182Y1065192D01*
G37*
G36*
G01X1288821Y1065155D02*
X1289205Y1065337D01*
X1289735Y1064806D01*
X1289553Y1064423D01*
X1289412Y1064281D01*
X1288680Y1065013D01*
X1288821Y1065155D01*
G37*
G36*
G01X1288439Y1064971D02*
X1288056Y1064789D01*
X1287525Y1065319D01*
X1287707Y1065703D01*
X1287849Y1065844D01*
X1288581Y1065112D01*
X1288439Y1064971D01*
G37*
G36*
G01X1287159Y1066816D02*
X1287543Y1066998D01*
X1288073Y1066468D01*
X1287891Y1066085D01*
X1287750Y1065943D01*
X1287018Y1066675D01*
X1287159Y1066816D01*
G37*
G36*
G01X1285116Y1068294D02*
X1284732Y1068112D01*
X1284202Y1068643D01*
X1284384Y1069026D01*
X1284525Y1069168D01*
X1285257Y1068436D01*
X1285116Y1068294D01*
G37*
G36*
G01X1283454Y1069956D02*
X1283071Y1069774D01*
X1282540Y1070304D01*
X1282722Y1070688D01*
X1282864Y1070829D01*
X1283596Y1070097D01*
X1283454Y1069956D01*
G37*
G36*
G01X1282174Y1071802D02*
X1282558Y1071984D01*
X1283088Y1071453D01*
X1282906Y1071070D01*
X1282765Y1070928D01*
X1282033Y1071660D01*
X1282174Y1071802D01*
G37*
G36*
G01X1283836Y1070140D02*
X1284220Y1070322D01*
X1284750Y1069792D01*
X1284568Y1069408D01*
X1284426Y1069267D01*
X1283695Y1069998D01*
X1283836Y1070140D01*
G37*
G36*
G01X1286778Y1066633D02*
X1286394Y1066450D01*
X1285864Y1066981D01*
X1286046Y1067364D01*
X1286187Y1067506D01*
X1286919Y1066774D01*
X1286778Y1066633D01*
G37*
G36*
G01X1285498Y1068478D02*
X1285881Y1068660D01*
X1286412Y1068130D01*
X1286230Y1067746D01*
X1286088Y1067605D01*
X1285356Y1068337D01*
X1285498Y1068478D01*
G37*
G36*
G01X1290952Y1064160D02*
X1290568Y1063978D01*
X1290038Y1064508D01*
X1290220Y1064892D01*
X1290361Y1065033D01*
X1291093Y1064301D01*
X1290952Y1064160D01*
G37*
G36*
G01X1289290Y1065821D02*
X1288906Y1065639D01*
X1288376Y1066170D01*
X1288558Y1066553D01*
X1288699Y1066695D01*
X1289431Y1065963D01*
X1289290Y1065821D01*
G37*
G36*
G01X1289672Y1066005D02*
X1290055Y1066187D01*
X1290586Y1065657D01*
X1290403Y1065273D01*
X1290262Y1065132D01*
X1289530Y1065864D01*
X1289672Y1066005D01*
G37*
G36*
G01X1282643Y1072468D02*
X1282259Y1072286D01*
X1281729Y1072816D01*
X1281911Y1073200D01*
X1282053Y1073341D01*
X1282784Y1072610D01*
X1282643Y1072468D01*
G37*
G36*
G01X1283025Y1072652D02*
X1283408Y1072834D01*
X1283939Y1072304D01*
X1283757Y1071920D01*
X1283615Y1071779D01*
X1282883Y1072511D01*
X1283025Y1072652D01*
G37*
G36*
G01X1284305Y1070806D02*
X1283921Y1070624D01*
X1283391Y1071155D01*
X1283573Y1071538D01*
X1283714Y1071680D01*
X1284446Y1070948D01*
X1284305Y1070806D01*
G37*
G36*
G01X1284687Y1070990D02*
X1285070Y1071172D01*
X1285600Y1070642D01*
X1285418Y1070258D01*
X1285277Y1070117D01*
X1284545Y1070849D01*
X1284687Y1070990D01*
G37*
G36*
G01X1287628Y1067483D02*
X1287244Y1067301D01*
X1286714Y1067831D01*
X1286896Y1068215D01*
X1287038Y1068356D01*
X1287770Y1067624D01*
X1287628Y1067483D01*
G37*
G36*
G01X1288010Y1067667D02*
X1288394Y1067849D01*
X1288924Y1067319D01*
X1288742Y1066935D01*
X1288600Y1066794D01*
X1287869Y1067525D01*
X1288010Y1067667D01*
G37*
G36*
G01X1286348Y1069329D02*
X1286732Y1069511D01*
X1287262Y1068980D01*
X1287080Y1068597D01*
X1286939Y1068455D01*
X1286207Y1069187D01*
X1286348Y1069329D01*
G37*
G36*
G01X1285966Y1069145D02*
X1285583Y1068963D01*
X1285052Y1069493D01*
X1285235Y1069877D01*
X1285376Y1070018D01*
X1286108Y1069286D01*
X1285966Y1069145D01*
G37*
G36*
G01X1291333Y1064343D02*
X1291717Y1064526D01*
X1292247Y1063995D01*
X1292065Y1063612D01*
X1291924Y1063470D01*
X1291192Y1064202D01*
X1291333Y1064343D01*
G37*
G36*
G01X1285928Y1065783D02*
X1285544Y1065601D01*
X1285014Y1066131D01*
X1285196Y1066515D01*
X1285338Y1066656D01*
X1286070Y1065924D01*
X1285928Y1065783D01*
G37*
G36*
G01X1286310Y1065967D02*
X1286694Y1066149D01*
X1287224Y1065619D01*
X1287042Y1065235D01*
X1286900Y1065094D01*
X1286169Y1065825D01*
X1286310Y1065967D01*
G37*
G36*
G01X1287590Y1064121D02*
X1287206Y1063939D01*
X1286676Y1064470D01*
X1286858Y1064853D01*
X1286999Y1064995D01*
X1287731Y1064263D01*
X1287590Y1064121D01*
G37*
G36*
G01X1287972Y1064305D02*
X1288355Y1064487D01*
X1288886Y1063957D01*
X1288703Y1063573D01*
X1288562Y1063432D01*
X1287830Y1064164D01*
X1287972Y1064305D01*
G37*
G36*
G01X1284266Y1067445D02*
X1283883Y1067263D01*
X1283352Y1067793D01*
X1283535Y1068177D01*
X1283676Y1068318D01*
X1284408Y1067586D01*
X1284266Y1067445D01*
G37*
G36*
G01X1284648Y1067629D02*
X1285032Y1067811D01*
X1285562Y1067280D01*
X1285380Y1066897D01*
X1285239Y1066755D01*
X1284507Y1067487D01*
X1284648Y1067629D01*
G37*
G36*
G01X1282605Y1069106D02*
X1282221Y1068924D01*
X1281691Y1069455D01*
X1281873Y1069838D01*
X1282014Y1069980D01*
X1282746Y1069248D01*
X1282605Y1069106D01*
G37*
G36*
G01X1282987Y1069290D02*
X1283370Y1069472D01*
X1283900Y1068942D01*
X1283718Y1068558D01*
X1283577Y1068417D01*
X1282845Y1069149D01*
X1282987Y1069290D01*
G37*
G36*
G01X1298317Y1090881D02*
X1297934Y1090699D01*
X1297403Y1091229D01*
X1297585Y1091613D01*
X1297727Y1091754D01*
X1298459Y1091022D01*
X1298317Y1090881D01*
G37*
G36*
G01X1295910Y1094958D02*
X1296330Y1095021D01*
X1296685Y1094360D01*
X1296399Y1094046D01*
X1296223Y1093951D01*
X1295734Y1094863D01*
X1295910Y1094958D01*
G37*
G36*
G01X1296966Y1095535D02*
X1297385Y1095598D01*
X1297739Y1094937D01*
X1297454Y1094622D01*
X1297278Y1094528D01*
X1296789Y1095440D01*
X1296966Y1095535D01*
G37*
G36*
G01X1297844Y1090209D02*
X1298227Y1090391D01*
X1298758Y1089861D01*
X1298575Y1089477D01*
X1298434Y1089336D01*
X1297702Y1090068D01*
X1297844Y1090209D01*
G37*
G36*
G01X1297462Y1090025D02*
X1297078Y1089843D01*
X1296548Y1090374D01*
X1296730Y1090757D01*
X1296871Y1090899D01*
X1297603Y1090167D01*
X1297462Y1090025D01*
G37*
G36*
G01X1294433Y1094325D02*
X1294013Y1094261D01*
X1293659Y1094923D01*
X1293944Y1095237D01*
X1294120Y1095331D01*
X1294609Y1094419D01*
X1294433Y1094325D01*
G37*
G36*
G01X1294851Y1094390D02*
X1295271Y1094453D01*
X1295625Y1093792D01*
X1295340Y1093478D01*
X1295164Y1093383D01*
X1294675Y1094296D01*
X1294851Y1094390D01*
G37*
G36*
G01X1295542Y1092253D02*
X1295122Y1092190D01*
X1294768Y1092851D01*
X1295054Y1093165D01*
X1295230Y1093260D01*
X1295719Y1092348D01*
X1295542Y1092253D01*
G37*
G36*
G01X1290245Y1089414D02*
X1289825Y1089351D01*
X1289472Y1090012D01*
X1289757Y1090327D01*
X1289934Y1090421D01*
X1290422Y1089509D01*
X1290245Y1089414D01*
G37*
G36*
G01X1289137Y1091486D02*
X1288717Y1091423D01*
X1288363Y1092084D01*
X1288649Y1092399D01*
X1288825Y1092493D01*
X1289313Y1091581D01*
X1289137Y1091486D01*
G37*
G36*
G01X1289556Y1091551D02*
X1289975Y1091615D01*
X1290329Y1090953D01*
X1290044Y1090639D01*
X1289867Y1090545D01*
X1289379Y1091457D01*
X1289556Y1091551D01*
G37*
G36*
G01X1287543Y1095502D02*
X1287123Y1095564D01*
X1286976Y1096299D01*
X1287340Y1096517D01*
X1287536Y1096557D01*
X1287739Y1095542D01*
X1287543Y1095502D01*
G37*
G36*
G01X1294160Y1085399D02*
X1294544Y1085581D01*
X1295074Y1085050D01*
X1294892Y1084667D01*
X1294750Y1084525D01*
X1294019Y1085257D01*
X1294160Y1085399D01*
G37*
G36*
G01X1297102Y1081892D02*
X1296718Y1081710D01*
X1296188Y1082240D01*
X1296370Y1082623D01*
X1296511Y1082765D01*
X1297243Y1082033D01*
X1297102Y1081892D01*
G37*
G36*
G01X1295822Y1083737D02*
X1296205Y1083919D01*
X1296736Y1083389D01*
X1296554Y1083005D01*
X1296412Y1082864D01*
X1295680Y1083596D01*
X1295822Y1083737D01*
G37*
G36*
G01X1295440Y1083553D02*
X1295056Y1083371D01*
X1294526Y1083901D01*
X1294708Y1084285D01*
X1294850Y1084426D01*
X1295581Y1083695D01*
X1295440Y1083553D01*
G37*
G36*
G01X1297484Y1082076D02*
X1297867Y1082258D01*
X1298398Y1081727D01*
X1298216Y1081344D01*
X1298074Y1081202D01*
X1297342Y1081934D01*
X1297484Y1082076D01*
G37*
G36*
G01X1293778Y1085215D02*
X1293395Y1085033D01*
X1292864Y1085563D01*
X1293046Y1085946D01*
X1293188Y1086088D01*
X1293920Y1085356D01*
X1293778Y1085215D01*
G37*
G36*
G01X1292498Y1087060D02*
X1292882Y1087242D01*
X1293412Y1086712D01*
X1293230Y1086328D01*
X1293089Y1086187D01*
X1292357Y1086919D01*
X1292498Y1087060D01*
G37*
G36*
G01X1285187Y1095032D02*
X1284767Y1095094D01*
X1284620Y1095829D01*
X1284984Y1096047D01*
X1285180Y1096086D01*
X1285383Y1095071D01*
X1285187Y1095032D01*
G37*
G36*
G01X1290797Y1085358D02*
X1291180Y1085541D01*
X1291711Y1085010D01*
X1291529Y1084627D01*
X1291387Y1084485D01*
X1290655Y1085217D01*
X1290797Y1085358D01*
G37*
G36*
G01X1290415Y1085174D02*
X1290031Y1084992D01*
X1289501Y1085523D01*
X1289683Y1085906D01*
X1289824Y1086048D01*
X1290556Y1085316D01*
X1290415Y1085174D01*
G37*
G36*
G01X1288546Y1088346D02*
X1288966Y1088409D01*
X1289320Y1087748D01*
X1289035Y1087434D01*
X1288858Y1087339D01*
X1288370Y1088252D01*
X1288546Y1088346D01*
G37*
G36*
G01X1288128Y1088281D02*
X1287708Y1088218D01*
X1287354Y1088879D01*
X1287639Y1089193D01*
X1287815Y1089288D01*
X1288304Y1088375D01*
X1288128Y1088281D01*
G37*
G36*
G01X1287437Y1090418D02*
X1287857Y1090481D01*
X1288211Y1089820D01*
X1287926Y1089506D01*
X1287749Y1089411D01*
X1287261Y1090324D01*
X1287437Y1090418D01*
G37*
G36*
G01X1287019Y1090353D02*
X1286599Y1090290D01*
X1286245Y1090951D01*
X1286530Y1091265D01*
X1286707Y1091360D01*
X1287195Y1090447D01*
X1287019Y1090353D01*
G37*
G36*
G01X1286329Y1092490D02*
X1286749Y1092553D01*
X1287102Y1091892D01*
X1286817Y1091578D01*
X1286641Y1091483D01*
X1286152Y1092396D01*
X1286329Y1092490D01*
G37*
G36*
G01X1285606Y1094973D02*
X1286027Y1094912D01*
X1286173Y1094176D01*
X1285809Y1093958D01*
X1285613Y1093919D01*
X1285410Y1094934D01*
X1285606Y1094973D01*
G37*
G36*
G01X1294121Y1082035D02*
X1294504Y1082218D01*
X1295035Y1081687D01*
X1294853Y1081304D01*
X1294711Y1081162D01*
X1293979Y1081894D01*
X1294121Y1082035D01*
G37*
G36*
G01X1292459Y1083697D02*
X1292842Y1083879D01*
X1293373Y1083349D01*
X1293191Y1082965D01*
X1293049Y1082824D01*
X1292317Y1083555D01*
X1292459Y1083697D01*
G37*
G36*
G01X1293739Y1081851D02*
X1293355Y1081669D01*
X1292825Y1082200D01*
X1293007Y1082583D01*
X1293148Y1082725D01*
X1293880Y1081993D01*
X1293739Y1081851D01*
G37*
G36*
G01X1292077Y1083513D02*
X1291693Y1083331D01*
X1291163Y1083861D01*
X1291345Y1084245D01*
X1291486Y1084386D01*
X1292218Y1083654D01*
X1292077Y1083513D01*
G37*
G36*
G01X1295401Y1080190D02*
X1295017Y1080008D01*
X1294487Y1080538D01*
X1294669Y1080922D01*
X1294810Y1081063D01*
X1295542Y1080331D01*
X1295401Y1080190D01*
G37*
G36*
G01X1295783Y1080374D02*
X1296166Y1080556D01*
X1296696Y1080026D01*
X1296514Y1079642D01*
X1296373Y1079501D01*
X1295641Y1080232D01*
X1295783Y1080374D01*
G37*
G36*
G01X1286784Y1095209D02*
X1287205Y1095147D01*
X1287352Y1094412D01*
X1286987Y1094194D01*
X1286791Y1094154D01*
X1286588Y1095169D01*
X1286784Y1095209D01*
G37*
G36*
G01X1286366Y1095267D02*
X1285946Y1095329D01*
X1285799Y1096064D01*
X1286163Y1096282D01*
X1286359Y1096322D01*
X1286562Y1095307D01*
X1286366Y1095267D01*
G37*
G36*
G01X1288496Y1090985D02*
X1288916Y1091048D01*
X1289270Y1090386D01*
X1288985Y1090072D01*
X1288808Y1089978D01*
X1288320Y1090890D01*
X1288496Y1090985D01*
G37*
G36*
G01X1287388Y1093057D02*
X1287808Y1093120D01*
X1288162Y1092459D01*
X1287876Y1092144D01*
X1287700Y1092050D01*
X1287212Y1092963D01*
X1287388Y1093057D01*
G37*
G36*
G01X1289605Y1088913D02*
X1290025Y1088976D01*
X1290379Y1088314D01*
X1290093Y1088000D01*
X1289917Y1087906D01*
X1289429Y1088818D01*
X1289605Y1088913D01*
G37*
G36*
G01X1289186Y1088847D02*
X1288766Y1088784D01*
X1288412Y1089446D01*
X1288698Y1089760D01*
X1288874Y1089854D01*
X1289363Y1088942D01*
X1289186Y1088847D01*
G37*
G36*
G01X1288078Y1090920D02*
X1287658Y1090856D01*
X1287304Y1091518D01*
X1287589Y1091832D01*
X1287766Y1091926D01*
X1288254Y1091014D01*
X1288078Y1090920D01*
G37*
G36*
G01X1291264Y1086024D02*
X1290881Y1085842D01*
X1290350Y1086372D01*
X1290532Y1086756D01*
X1290674Y1086897D01*
X1291406Y1086166D01*
X1291264Y1086024D01*
G37*
G36*
G01X1294588Y1082701D02*
X1294205Y1082519D01*
X1293674Y1083049D01*
X1293856Y1083433D01*
X1293998Y1083574D01*
X1294730Y1082842D01*
X1294588Y1082701D01*
G37*
G36*
G01X1292926Y1084363D02*
X1292543Y1084180D01*
X1292012Y1084711D01*
X1292194Y1085094D01*
X1292336Y1085236D01*
X1293068Y1084504D01*
X1292926Y1084363D01*
G37*
G36*
G01X1293308Y1084546D02*
X1293692Y1084729D01*
X1294222Y1084198D01*
X1294040Y1083815D01*
X1293899Y1083673D01*
X1293167Y1084405D01*
X1293308Y1084546D01*
G37*
G36*
G01X1294970Y1082885D02*
X1295354Y1083067D01*
X1295884Y1082537D01*
X1295702Y1082153D01*
X1295560Y1082012D01*
X1294829Y1082743D01*
X1294970Y1082885D01*
G37*
G36*
G01X1296632Y1081223D02*
X1297015Y1081406D01*
X1297546Y1080875D01*
X1297364Y1080492D01*
X1297222Y1080350D01*
X1296490Y1081082D01*
X1296632Y1081223D01*
G37*
G36*
G01X1296250Y1081040D02*
X1295866Y1080857D01*
X1295336Y1081388D01*
X1295518Y1081771D01*
X1295659Y1081913D01*
X1296391Y1081181D01*
X1296250Y1081040D01*
G37*
G36*
G01X1291646Y1086208D02*
X1292030Y1086390D01*
X1292560Y1085860D01*
X1292378Y1085476D01*
X1292237Y1085335D01*
X1291505Y1086067D01*
X1291646Y1086208D01*
G37*
G36*
G01X1284009Y1094797D02*
X1283589Y1094859D01*
X1283442Y1095594D01*
X1283806Y1095812D01*
X1284003Y1095851D01*
X1284205Y1094836D01*
X1284009Y1094797D01*
G37*
G36*
G01X1284429Y1094738D02*
X1284849Y1094677D01*
X1284996Y1093941D01*
X1284631Y1093723D01*
X1284435Y1093684D01*
X1284232Y1094699D01*
X1284429Y1094738D01*
G37*
G36*
G01X1289566Y1084325D02*
X1289182Y1084143D01*
X1288652Y1084674D01*
X1288834Y1085057D01*
X1288976Y1085199D01*
X1289707Y1084467D01*
X1289566Y1084325D01*
G37*
G36*
G01X1289948Y1084509D02*
X1290331Y1084691D01*
X1290862Y1084161D01*
X1290680Y1083777D01*
X1290538Y1083636D01*
X1289806Y1084368D01*
X1289948Y1084509D01*
G37*
G36*
G01X1291228Y1082664D02*
X1290844Y1082482D01*
X1290314Y1083012D01*
X1290496Y1083396D01*
X1290637Y1083537D01*
X1291369Y1082805D01*
X1291228Y1082664D01*
G37*
G36*
G01X1286379Y1089852D02*
X1286799Y1089915D01*
X1287152Y1089254D01*
X1286867Y1088939D01*
X1286691Y1088845D01*
X1286202Y1089757D01*
X1286379Y1089852D01*
G37*
G36*
G01X1287488Y1087780D02*
X1287908Y1087843D01*
X1288261Y1087182D01*
X1287976Y1086867D01*
X1287800Y1086773D01*
X1287311Y1087685D01*
X1287488Y1087780D01*
G37*
G36*
G01X1287069Y1087714D02*
X1286649Y1087651D01*
X1286295Y1088313D01*
X1286580Y1088627D01*
X1286757Y1088721D01*
X1287245Y1087809D01*
X1287069Y1087714D01*
G37*
G36*
G01X1285270Y1091923D02*
X1285689Y1091987D01*
X1286043Y1091325D01*
X1285758Y1091011D01*
X1285582Y1090917D01*
X1285093Y1091829D01*
X1285270Y1091923D01*
G37*
G36*
G01X1285960Y1089786D02*
X1285540Y1089723D01*
X1285186Y1090384D01*
X1285471Y1090699D01*
X1285648Y1090793D01*
X1286136Y1089881D01*
X1285960Y1089786D01*
G37*
G36*
G01X1293271Y1081186D02*
X1293655Y1081368D01*
X1294185Y1080838D01*
X1294003Y1080454D01*
X1293862Y1080313D01*
X1293130Y1081045D01*
X1293271Y1081186D01*
G37*
G36*
G01X1292890Y1081002D02*
X1292506Y1080820D01*
X1291976Y1081350D01*
X1292158Y1081734D01*
X1292299Y1081875D01*
X1293031Y1081144D01*
X1292890Y1081002D01*
G37*
G36*
G01X1291610Y1082848D02*
X1291993Y1083030D01*
X1292524Y1082499D01*
X1292342Y1082116D01*
X1292200Y1081974D01*
X1291468Y1082706D01*
X1291610Y1082848D01*
G37*
G36*
G01X1282057Y1094306D02*
X1282477Y1094244D01*
X1282623Y1093508D01*
X1282258Y1093291D01*
X1282062Y1093252D01*
X1281860Y1094267D01*
X1282057Y1094306D01*
G37*
G36*
G01X1283928Y1088596D02*
X1283508Y1088533D01*
X1283155Y1089194D01*
X1283440Y1089509D01*
X1283617Y1089603D01*
X1284104Y1088690D01*
X1283928Y1088596D01*
G37*
G36*
G01X1283239Y1090733D02*
X1283659Y1090796D01*
X1284013Y1090135D01*
X1283727Y1089821D01*
X1283551Y1089726D01*
X1283063Y1090639D01*
X1283239Y1090733D01*
G37*
G36*
G01X1285036Y1086523D02*
X1284616Y1086460D01*
X1284262Y1087122D01*
X1284548Y1087436D01*
X1284724Y1087530D01*
X1285212Y1086617D01*
X1285036Y1086523D01*
G37*
G36*
G01X1284347Y1088661D02*
X1284767Y1088724D01*
X1285120Y1088062D01*
X1284835Y1087748D01*
X1284658Y1087654D01*
X1284170Y1088567D01*
X1284347Y1088661D01*
G37*
G36*
G01X1290667Y1079732D02*
X1290284Y1079550D01*
X1289753Y1080080D01*
X1289935Y1080464D01*
X1290077Y1080605D01*
X1290809Y1079873D01*
X1290667Y1079732D01*
G37*
G36*
G01X1289387Y1081578D02*
X1289771Y1081760D01*
X1290301Y1081229D01*
X1290119Y1080846D01*
X1289978Y1080704D01*
X1289246Y1081436D01*
X1289387Y1081578D01*
G37*
G36*
G01X1289006Y1081394D02*
X1288622Y1081212D01*
X1288092Y1081742D01*
X1288274Y1082126D01*
X1288415Y1082267D01*
X1289147Y1081535D01*
X1289006Y1081394D01*
G37*
G36*
G01X1287726Y1083239D02*
X1288109Y1083421D01*
X1288640Y1082891D01*
X1288457Y1082507D01*
X1288316Y1082366D01*
X1287584Y1083098D01*
X1287726Y1083239D01*
G37*
G36*
G01X1285454Y1086588D02*
X1285874Y1086651D01*
X1286228Y1085990D01*
X1285942Y1085675D01*
X1285766Y1085581D01*
X1285278Y1086494D01*
X1285454Y1086588D01*
G37*
G36*
G01X1285646Y1081357D02*
X1285262Y1081175D01*
X1284732Y1081706D01*
X1284914Y1082089D01*
X1285055Y1082231D01*
X1285787Y1081499D01*
X1285646Y1081357D01*
G37*
G36*
G01X1283337Y1085457D02*
X1283757Y1085520D01*
X1284111Y1084858D01*
X1283825Y1084544D01*
X1283649Y1084450D01*
X1283161Y1085363D01*
X1283337Y1085457D01*
G37*
G36*
G01X1284026Y1083319D02*
X1283606Y1083256D01*
X1283253Y1083918D01*
X1283538Y1084232D01*
X1283715Y1084326D01*
X1284202Y1083413D01*
X1284026Y1083319D01*
G37*
G36*
G01X1282229Y1087529D02*
X1282649Y1087592D01*
X1283003Y1086931D01*
X1282717Y1086617D01*
X1282541Y1086522D01*
X1282053Y1087435D01*
X1282229Y1087529D01*
G37*
G36*
G01X1282918Y1085392D02*
X1282498Y1085329D01*
X1282145Y1085990D01*
X1282430Y1086305D01*
X1282607Y1086399D01*
X1283095Y1085486D01*
X1282918Y1085392D01*
G37*
G36*
G01X1287308Y1079696D02*
X1286924Y1079514D01*
X1286394Y1080044D01*
X1286576Y1080428D01*
X1286717Y1080569D01*
X1287449Y1079837D01*
X1287308Y1079696D01*
G37*
G36*
G01X1286028Y1081541D02*
X1286411Y1081723D01*
X1286942Y1081193D01*
X1286759Y1080809D01*
X1286618Y1080668D01*
X1285886Y1081400D01*
X1286028Y1081541D01*
G37*
G36*
G01X1284396Y1086023D02*
X1284816Y1086085D01*
X1285169Y1085424D01*
X1284884Y1085110D01*
X1284707Y1085015D01*
X1284219Y1085928D01*
X1284396Y1086023D01*
G37*
G36*
G01X1285086Y1083885D02*
X1284666Y1083822D01*
X1284312Y1084483D01*
X1284598Y1084798D01*
X1284774Y1084892D01*
X1285262Y1083979D01*
X1285086Y1083885D01*
G37*
G36*
G01X1283287Y1088095D02*
X1283707Y1088158D01*
X1284061Y1087497D01*
X1283775Y1087182D01*
X1283599Y1087088D01*
X1283111Y1088001D01*
X1283287Y1088095D01*
G37*
G36*
G01X1283977Y1085957D02*
X1283557Y1085895D01*
X1283204Y1086556D01*
X1283489Y1086870D01*
X1283666Y1086965D01*
X1284153Y1086052D01*
X1283977Y1085957D01*
G37*
G36*
G01X1282870Y1088030D02*
X1282450Y1087967D01*
X1282097Y1088629D01*
X1282383Y1088943D01*
X1282559Y1089037D01*
X1283047Y1088124D01*
X1282870Y1088030D01*
G37*
G36*
G01X1282181Y1090168D02*
X1282600Y1090231D01*
X1282954Y1089569D01*
X1282668Y1089255D01*
X1282492Y1089161D01*
X1282004Y1090073D01*
X1282181Y1090168D01*
G37*
G36*
G01X1288157Y1080545D02*
X1287773Y1080363D01*
X1287243Y1080893D01*
X1287425Y1081277D01*
X1287566Y1081418D01*
X1288298Y1080686D01*
X1288157Y1080545D01*
G37*
G36*
G01X1286877Y1082390D02*
X1287260Y1082572D01*
X1287791Y1082042D01*
X1287608Y1081658D01*
X1287467Y1081517D01*
X1286735Y1082249D01*
X1286877Y1082390D01*
G37*
G36*
G01X1288538Y1080729D02*
X1288922Y1080911D01*
X1289452Y1080380D01*
X1289270Y1079997D01*
X1289129Y1079855D01*
X1288397Y1080587D01*
X1288538Y1080729D01*
G37*
G36*
G01X1284796Y1080507D02*
X1284412Y1080325D01*
X1283882Y1080856D01*
X1284064Y1081239D01*
X1284205Y1081381D01*
X1284937Y1080649D01*
X1284796Y1080507D01*
G37*
G36*
G01X1285178Y1080691D02*
X1285561Y1080873D01*
X1286092Y1080343D01*
X1285909Y1079959D01*
X1285768Y1079818D01*
X1285036Y1080550D01*
X1285178Y1080691D01*
G37*
G36*
G01X1282967Y1082753D02*
X1282547Y1082690D01*
X1282193Y1083352D01*
X1282479Y1083666D01*
X1282655Y1083760D01*
X1283143Y1082847D01*
X1282967Y1082753D01*
G37*
G36*
G01X1282278Y1084891D02*
X1282698Y1084954D01*
X1283051Y1084292D01*
X1282766Y1083978D01*
X1282589Y1083884D01*
X1282101Y1084796D01*
X1282278Y1084891D01*
G37*
G36*
G01X1296244Y1101007D02*
X1295824Y1101068D01*
X1295677Y1101804D01*
X1296042Y1102022D01*
X1296238Y1102061D01*
X1296441Y1101046D01*
X1296244Y1101007D01*
G37*
G36*
G01X1296705Y1098702D02*
X1296285Y1098764D01*
X1296138Y1099499D01*
X1296502Y1099717D01*
X1296698Y1099757D01*
X1296901Y1098742D01*
X1296705Y1098702D01*
G37*
G36*
G01X1296664Y1100948D02*
X1297084Y1100887D01*
X1297231Y1100151D01*
X1296867Y1099933D01*
X1296671Y1099894D01*
X1296468Y1100909D01*
X1296664Y1100948D01*
G37*
G36*
G01X1295282Y1107861D02*
X1295702Y1107800D01*
X1295849Y1107064D01*
X1295485Y1106846D01*
X1295289Y1106807D01*
X1295086Y1107822D01*
X1295282Y1107861D01*
G37*
G36*
G01X1295323Y1105616D02*
X1294903Y1105677D01*
X1294756Y1106412D01*
X1295120Y1106630D01*
X1295316Y1106670D01*
X1295519Y1105655D01*
X1295323Y1105616D01*
G37*
G36*
G01X1295784Y1103311D02*
X1295364Y1103372D01*
X1295217Y1104108D01*
X1295581Y1104326D01*
X1295777Y1104365D01*
X1295980Y1103350D01*
X1295784Y1103311D01*
G37*
G36*
G01X1296203Y1103252D02*
X1296624Y1103191D01*
X1296771Y1102456D01*
X1296406Y1102237D01*
X1296210Y1102198D01*
X1296007Y1103213D01*
X1296203Y1103252D01*
G37*
G36*
G01X1295743Y1105557D02*
X1296163Y1105495D01*
X1296310Y1104760D01*
X1295946Y1104542D01*
X1295749Y1104503D01*
X1295547Y1105518D01*
X1295743Y1105557D01*
G37*
G36*
G01X1294570Y1110590D02*
X1294170Y1110733D01*
Y1111483D01*
X1294570Y1111625D01*
X1294770D01*
Y1110590D01*
X1294570D01*
G37*
G36*
G01X1294970Y1112800D02*
X1295370Y1112658D01*
Y1111908D01*
X1294970Y1111765D01*
X1294770D01*
Y1112800D01*
X1294970D01*
G37*
G36*
G01X1294309Y1100477D02*
X1294729Y1100416D01*
X1294876Y1099680D01*
X1294512Y1099462D01*
X1294316Y1099423D01*
X1294113Y1100438D01*
X1294309Y1100477D01*
G37*
G36*
G01X1294350Y1098232D02*
X1293930Y1098293D01*
X1293783Y1099028D01*
X1294147Y1099246D01*
X1294343Y1099286D01*
X1294546Y1098271D01*
X1294350Y1098232D01*
G37*
G36*
G01X1293889Y1100536D02*
X1293469Y1100597D01*
X1293322Y1101333D01*
X1293687Y1101551D01*
X1293883Y1101590D01*
X1294085Y1100575D01*
X1293889Y1100536D01*
G37*
G36*
G01X1294770Y1098173D02*
X1295190Y1098111D01*
X1295337Y1097376D01*
X1294973Y1097158D01*
X1294776Y1097118D01*
X1294574Y1098133D01*
X1294770Y1098173D01*
G37*
G36*
G01X1293848Y1102781D02*
X1294269Y1102720D01*
X1294416Y1101985D01*
X1294051Y1101767D01*
X1293855Y1101727D01*
X1293652Y1102742D01*
X1293848Y1102781D01*
G37*
G36*
G01X1292927Y1107390D02*
X1293347Y1107329D01*
X1293494Y1106593D01*
X1293130Y1106375D01*
X1292934Y1106336D01*
X1292731Y1107351D01*
X1292927Y1107390D01*
G37*
G36*
G01X1292968Y1105145D02*
X1292548Y1105206D01*
X1292401Y1105942D01*
X1292765Y1106160D01*
X1292961Y1106199D01*
X1293164Y1105184D01*
X1292968Y1105145D01*
G37*
G36*
G01X1293388Y1105086D02*
X1293808Y1105025D01*
X1293955Y1104289D01*
X1293591Y1104071D01*
X1293395Y1104032D01*
X1293192Y1105047D01*
X1293388Y1105086D01*
G37*
G36*
G01X1293429Y1102840D02*
X1293009Y1102902D01*
X1292862Y1103637D01*
X1293226Y1103855D01*
X1293422Y1103894D01*
X1293625Y1102880D01*
X1293429Y1102840D01*
G37*
G36*
G01X1292570Y1112800D02*
X1292970Y1112658D01*
Y1111908D01*
X1292570Y1111765D01*
X1292370D01*
Y1112800D01*
X1292570D01*
G37*
G36*
G01X1292170Y1110590D02*
X1291770Y1110733D01*
Y1111483D01*
X1292170Y1111625D01*
X1292370D01*
Y1110590D01*
X1292170D01*
G37*
G36*
G01X1295947Y1098408D02*
X1296367Y1098347D01*
X1296514Y1097611D01*
X1296150Y1097393D01*
X1295954Y1097354D01*
X1295751Y1098369D01*
X1295947Y1098408D01*
G37*
G36*
G01X1295067Y1100771D02*
X1294647Y1100833D01*
X1294500Y1101568D01*
X1294864Y1101786D01*
X1295060Y1101825D01*
X1295263Y1100811D01*
X1295067Y1100771D01*
G37*
G36*
G01X1295486Y1100712D02*
X1295907Y1100651D01*
X1296054Y1099916D01*
X1295689Y1099698D01*
X1295493Y1099658D01*
X1295290Y1100673D01*
X1295486Y1100712D01*
G37*
G36*
G01X1295528Y1098467D02*
X1295107Y1098528D01*
X1294960Y1099264D01*
X1295325Y1099482D01*
X1295521Y1099521D01*
X1295724Y1098506D01*
X1295528Y1098467D01*
G37*
G36*
G01X1294104Y1107626D02*
X1294524Y1107564D01*
X1294671Y1106829D01*
X1294307Y1106611D01*
X1294111Y1106572D01*
X1293908Y1107586D01*
X1294104Y1107626D01*
G37*
G36*
G01X1294145Y1105380D02*
X1293725Y1105441D01*
X1293578Y1106177D01*
X1293942Y1106395D01*
X1294138Y1106434D01*
X1294341Y1105419D01*
X1294145Y1105380D01*
G37*
G36*
G01X1294565Y1105321D02*
X1294985Y1105260D01*
X1295132Y1104524D01*
X1294768Y1104306D01*
X1294572Y1104267D01*
X1294369Y1105282D01*
X1294565Y1105321D01*
G37*
G36*
G01X1294606Y1103076D02*
X1294186Y1103137D01*
X1294039Y1103873D01*
X1294403Y1104091D01*
X1294599Y1104130D01*
X1294802Y1103115D01*
X1294606Y1103076D01*
G37*
G36*
G01X1295026Y1103017D02*
X1295446Y1102956D01*
X1295593Y1102220D01*
X1295229Y1102002D01*
X1295033Y1101963D01*
X1294830Y1102978D01*
X1295026Y1103017D01*
G37*
G36*
G01X1293770Y1112800D02*
X1294170Y1112658D01*
Y1111908D01*
X1293770Y1111765D01*
X1293570D01*
Y1112800D01*
X1293770D01*
G37*
G36*
G01X1293370Y1110590D02*
X1292970Y1110733D01*
Y1111483D01*
X1293370Y1111625D01*
X1293570D01*
Y1110590D01*
X1293370D01*
G37*
G36*
G01X1290970D02*
X1290570Y1110733D01*
Y1111483D01*
X1290970Y1111625D01*
X1291170D01*
Y1110590D01*
X1290970D01*
G37*
G36*
G01X1293590Y1097937D02*
X1294010Y1097875D01*
X1294157Y1097140D01*
X1293793Y1096922D01*
X1293597Y1096883D01*
X1293394Y1097898D01*
X1293590Y1097937D01*
G37*
G36*
G01X1293130Y1100241D02*
X1293550Y1100180D01*
X1293697Y1099444D01*
X1293332Y1099226D01*
X1293136Y1099187D01*
X1292933Y1100202D01*
X1293130Y1100241D01*
G37*
G36*
G01X1293170Y1097996D02*
X1292750Y1098057D01*
X1292603Y1098792D01*
X1292967Y1099011D01*
X1293164Y1099050D01*
X1293366Y1098035D01*
X1293170Y1097996D01*
G37*
G36*
G01X1292710Y1100300D02*
X1292290Y1100362D01*
X1292143Y1101097D01*
X1292507Y1101315D01*
X1292703Y1101354D01*
X1292906Y1100339D01*
X1292710Y1100300D01*
G37*
G36*
G01X1291749Y1107155D02*
X1292169Y1107093D01*
X1292316Y1106358D01*
X1291951Y1106140D01*
X1291755Y1106100D01*
X1291552Y1107115D01*
X1291749Y1107155D01*
G37*
G36*
G01X1291789Y1104909D02*
X1291369Y1104970D01*
X1291222Y1105706D01*
X1291587Y1105924D01*
X1291783Y1105963D01*
X1291985Y1104948D01*
X1291789Y1104909D01*
G37*
G36*
G01X1292250Y1102605D02*
X1291829Y1102666D01*
X1291683Y1103401D01*
X1292047Y1103620D01*
X1292243Y1103659D01*
X1292446Y1102644D01*
X1292250Y1102605D01*
G37*
G36*
G01X1292669Y1102546D02*
X1293089Y1102484D01*
X1293236Y1101749D01*
X1292872Y1101531D01*
X1292676Y1101492D01*
X1292473Y1102506D01*
X1292669Y1102546D01*
G37*
G36*
G01X1292209Y1104850D02*
X1292629Y1104789D01*
X1292776Y1104053D01*
X1292412Y1103835D01*
X1292216Y1103796D01*
X1292013Y1104811D01*
X1292209Y1104850D01*
G37*
G36*
G01X1291370Y1112800D02*
X1291770Y1112658D01*
Y1111908D01*
X1291370Y1111765D01*
X1291170D01*
Y1112800D01*
X1291370D01*
G37*
G36*
G01X1284970Y1111076D02*
X1284570Y1111219D01*
Y1111969D01*
X1284970Y1112111D01*
X1285170D01*
Y1111076D01*
X1284970D01*
G37*
G36*
G01X1286582Y1102357D02*
X1287002Y1102296D01*
X1287149Y1101560D01*
X1286784Y1101342D01*
X1286588Y1101303D01*
X1286385Y1102318D01*
X1286582Y1102357D01*
G37*
G36*
G01X1287084Y1097807D02*
X1286663Y1097868D01*
X1286517Y1098604D01*
X1286881Y1098822D01*
X1287077Y1098861D01*
X1287280Y1097846D01*
X1287084Y1097807D01*
G37*
G36*
G01X1286622Y1100111D02*
X1286202Y1100173D01*
X1286055Y1100908D01*
X1286419Y1101126D01*
X1286616Y1101165D01*
X1286818Y1100151D01*
X1286622Y1100111D01*
G37*
G36*
G01X1287502Y1097748D02*
X1287922Y1097687D01*
X1288069Y1096951D01*
X1287705Y1096733D01*
X1287509Y1096694D01*
X1287306Y1097709D01*
X1287502Y1097748D01*
G37*
G36*
G01X1287042Y1100052D02*
X1287462Y1099991D01*
X1287609Y1099256D01*
X1287245Y1099037D01*
X1287049Y1098998D01*
X1286846Y1100013D01*
X1287042Y1100052D01*
G37*
G36*
G01X1285703Y1104720D02*
X1285282Y1104782D01*
X1285135Y1105517D01*
X1285500Y1105735D01*
X1285696Y1105774D01*
X1285899Y1104759D01*
X1285703Y1104720D01*
G37*
G36*
G01X1286162Y1102416D02*
X1285742Y1102477D01*
X1285595Y1103213D01*
X1285959Y1103431D01*
X1286155Y1103470D01*
X1286358Y1102455D01*
X1286162Y1102416D01*
G37*
G36*
G01X1286121Y1104661D02*
X1286541Y1104600D01*
X1286688Y1103865D01*
X1286324Y1103646D01*
X1286128Y1103607D01*
X1285925Y1104622D01*
X1286121Y1104661D01*
G37*
G36*
G01X1285370Y1110936D02*
X1285770Y1110793D01*
Y1110043D01*
X1285370Y1109901D01*
X1285170D01*
Y1110936D01*
X1285370D01*
G37*
G36*
G01X1284266Y1099641D02*
X1283846Y1099703D01*
X1283700Y1100438D01*
X1284064Y1100656D01*
X1284260Y1100695D01*
X1284463Y1099680D01*
X1284266Y1099641D01*
G37*
G36*
G01X1284686Y1099582D02*
X1285106Y1099521D01*
X1285253Y1098785D01*
X1284889Y1098567D01*
X1284693Y1098528D01*
X1284490Y1099543D01*
X1284686Y1099582D01*
G37*
G36*
G01X1284226Y1101887D02*
X1284646Y1101825D01*
X1284793Y1101090D01*
X1284429Y1100872D01*
X1284233Y1100833D01*
X1284030Y1101848D01*
X1284226Y1101887D01*
G37*
G36*
G01X1284727Y1097337D02*
X1284306Y1097398D01*
X1284160Y1098134D01*
X1284524Y1098352D01*
X1284720Y1098391D01*
X1284923Y1097376D01*
X1284727Y1097337D01*
G37*
G36*
G01X1283306Y1106496D02*
X1283726Y1106434D01*
X1283873Y1105699D01*
X1283509Y1105481D01*
X1283312Y1105442D01*
X1283110Y1106457D01*
X1283306Y1106496D01*
G37*
G36*
G01X1283347Y1104250D02*
X1282927Y1104312D01*
X1282780Y1105047D01*
X1283145Y1105265D01*
X1283341Y1105304D01*
X1283543Y1104289D01*
X1283347Y1104250D01*
G37*
G36*
G01X1283806Y1101946D02*
X1283386Y1102007D01*
X1283239Y1102743D01*
X1283604Y1102961D01*
X1283800Y1103000D01*
X1284003Y1101985D01*
X1283806Y1101946D01*
G37*
G36*
G01X1283766Y1104191D02*
X1284186Y1104130D01*
X1284333Y1103394D01*
X1283969Y1103176D01*
X1283773Y1103137D01*
X1283570Y1104152D01*
X1283766Y1104191D01*
G37*
G36*
G01X1282570Y1111076D02*
X1282170Y1111219D01*
Y1111969D01*
X1282570Y1112111D01*
X1282770D01*
Y1111076D01*
X1282570D01*
G37*
G36*
G01Y1108726D02*
X1282170Y1108869D01*
Y1109619D01*
X1282570Y1109761D01*
X1282770D01*
Y1108726D01*
X1282570D01*
G37*
G36*
G01X1282970Y1110936D02*
X1283370Y1110793D01*
Y1110043D01*
X1282970Y1109901D01*
X1282770D01*
Y1110936D01*
X1282970D01*
G37*
G36*
G01X1285146Y1097278D02*
X1285566Y1097216D01*
X1285713Y1096481D01*
X1285349Y1096263D01*
X1285153Y1096224D01*
X1284950Y1097239D01*
X1285146Y1097278D01*
G37*
G36*
G01X1285445Y1099876D02*
X1285025Y1099938D01*
X1284878Y1100673D01*
X1285242Y1100891D01*
X1285438Y1100931D01*
X1285641Y1099916D01*
X1285445Y1099876D01*
G37*
G36*
G01X1283770Y1111076D02*
X1283370Y1111219D01*
Y1111969D01*
X1283770Y1112111D01*
X1283970D01*
Y1111076D01*
X1283770D01*
G37*
G36*
G01X1284170Y1110936D02*
X1284570Y1110793D01*
Y1110043D01*
X1284170Y1109901D01*
X1283970D01*
Y1110936D01*
X1284170D01*
G37*
G36*
G01X1284484Y1106731D02*
X1284904Y1106670D01*
X1285051Y1105934D01*
X1284686Y1105716D01*
X1284490Y1105677D01*
X1284288Y1106692D01*
X1284484Y1106731D01*
G37*
G36*
G01X1284524Y1104485D02*
X1284104Y1104547D01*
X1283957Y1105282D01*
X1284322Y1105500D01*
X1284518Y1105539D01*
X1284720Y1104525D01*
X1284524Y1104485D01*
G37*
G36*
G01X1284985Y1102181D02*
X1284564Y1102242D01*
X1284418Y1102978D01*
X1284782Y1103196D01*
X1284978Y1103235D01*
X1285181Y1102220D01*
X1284985Y1102181D01*
G37*
G36*
G01X1284944Y1104426D02*
X1285364Y1104365D01*
X1285511Y1103630D01*
X1285147Y1103411D01*
X1284951Y1103372D01*
X1284748Y1104387D01*
X1284944Y1104426D01*
G37*
G36*
G01X1285403Y1102122D02*
X1285824Y1102061D01*
X1285970Y1101325D01*
X1285606Y1101107D01*
X1285410Y1101068D01*
X1285207Y1102083D01*
X1285403Y1102122D01*
G37*
G36*
G01X1285905Y1097572D02*
X1285485Y1097633D01*
X1285338Y1098369D01*
X1285703Y1098587D01*
X1285899Y1098626D01*
X1286101Y1097611D01*
X1285905Y1097572D01*
G37*
G36*
G01X1286325Y1097513D02*
X1286745Y1097452D01*
X1286892Y1096716D01*
X1286528Y1096498D01*
X1286332Y1096459D01*
X1286129Y1097474D01*
X1286325Y1097513D01*
G37*
G36*
G01X1285865Y1099817D02*
X1286285Y1099756D01*
X1286432Y1099021D01*
X1286067Y1098803D01*
X1285871Y1098763D01*
X1285669Y1099778D01*
X1285865Y1099817D01*
G37*
G36*
G01X1283969Y1097043D02*
X1284389Y1096981D01*
X1284536Y1096246D01*
X1284171Y1096028D01*
X1283975Y1095989D01*
X1283773Y1097004D01*
X1283969Y1097043D01*
G37*
G36*
G01X1283509Y1099347D02*
X1283929Y1099286D01*
X1284076Y1098550D01*
X1283711Y1098332D01*
X1283515Y1098293D01*
X1283313Y1099308D01*
X1283509Y1099347D01*
G37*
G36*
G01X1283049Y1101652D02*
X1283469Y1101590D01*
X1283616Y1100855D01*
X1283251Y1100637D01*
X1283055Y1100598D01*
X1282853Y1101613D01*
X1283049Y1101652D01*
G37*
G36*
G01X1283549Y1097102D02*
X1283129Y1097163D01*
X1282982Y1097899D01*
X1283346Y1098117D01*
X1283543Y1098156D01*
X1283745Y1097141D01*
X1283549Y1097102D01*
G37*
G36*
G01X1283089Y1099406D02*
X1282669Y1099468D01*
X1282522Y1100203D01*
X1282887Y1100421D01*
X1283083Y1100460D01*
X1283285Y1099445D01*
X1283089Y1099406D01*
G37*
G36*
G01X1281770Y1110936D02*
X1282170Y1110793D01*
Y1110043D01*
X1281770Y1109901D01*
X1281570D01*
Y1110936D01*
X1281770D01*
G37*
G36*
G01X1282629Y1101711D02*
X1282209Y1101772D01*
X1282062Y1102508D01*
X1282427Y1102726D01*
X1282623Y1102765D01*
X1282825Y1101750D01*
X1282629Y1101711D01*
G37*
G36*
G01X1282129Y1106261D02*
X1282549Y1106199D01*
X1282696Y1105464D01*
X1282332Y1105246D01*
X1282135Y1105207D01*
X1281933Y1106222D01*
X1282129Y1106261D01*
G37*
G36*
G01X1282589Y1103956D02*
X1283009Y1103895D01*
X1283156Y1103159D01*
X1282791Y1102941D01*
X1282595Y1102902D01*
X1282393Y1103917D01*
X1282589Y1103956D01*
G37*
G36*
G01X1282169Y1104015D02*
X1281749Y1104077D01*
X1281602Y1104812D01*
X1281967Y1105030D01*
X1282163Y1105070D01*
X1282365Y1104055D01*
X1282169Y1104015D01*
G37*
G36*
G01X1297100Y1108357D02*
X1296680Y1108418D01*
X1296533Y1109154D01*
X1296898Y1109372D01*
X1297094Y1109411D01*
X1297296Y1108396D01*
X1297100Y1108357D01*
G37*
G36*
G01X1297520Y1108298D02*
X1297940Y1108237D01*
X1298087Y1107501D01*
X1297723Y1107283D01*
X1297527Y1107244D01*
X1297324Y1108259D01*
X1297520Y1108298D01*
G37*
G36*
G01X1298021Y1103748D02*
X1297601Y1103809D01*
X1297454Y1104545D01*
X1297818Y1104763D01*
X1298014Y1104802D01*
X1298217Y1103787D01*
X1298021Y1103748D01*
G37*
G36*
G01X1297561Y1106053D02*
X1297140Y1106114D01*
X1296994Y1106849D01*
X1297358Y1107067D01*
X1297554Y1107107D01*
X1297757Y1106092D01*
X1297561Y1106053D01*
G37*
G36*
G01X1294570Y1117640D02*
X1294170Y1117783D01*
Y1118533D01*
X1294570Y1118675D01*
X1294770D01*
Y1117640D01*
X1294570D01*
G37*
G36*
G01Y1112940D02*
X1294170Y1113083D01*
Y1113833D01*
X1294570Y1113975D01*
X1294770D01*
Y1112940D01*
X1294570D01*
G37*
G36*
G01Y1115290D02*
X1294170Y1115433D01*
Y1116183D01*
X1294570Y1116325D01*
X1294770D01*
Y1115290D01*
X1294570D01*
G37*
G36*
G01X1294970Y1115150D02*
X1295370Y1115008D01*
Y1114258D01*
X1294970Y1114115D01*
X1294770D01*
Y1115150D01*
X1294970D01*
G37*
G36*
G01Y1117500D02*
X1295370Y1117358D01*
Y1116608D01*
X1294970Y1116465D01*
X1294770D01*
Y1117500D01*
X1294970D01*
G37*
G36*
G01X1294570Y1124690D02*
X1294170Y1124833D01*
Y1125583D01*
X1294570Y1125725D01*
X1294770D01*
Y1124690D01*
X1294570D01*
G37*
G36*
G01Y1119990D02*
X1294170Y1120133D01*
Y1120883D01*
X1294570Y1121025D01*
X1294770D01*
Y1119990D01*
X1294570D01*
G37*
G36*
G01Y1122340D02*
X1294170Y1122483D01*
Y1123233D01*
X1294570Y1123375D01*
X1294770D01*
Y1122340D01*
X1294570D01*
G37*
G36*
G01Y1127040D02*
X1294170Y1127183D01*
Y1127933D01*
X1294570Y1128075D01*
X1294770D01*
Y1127040D01*
X1294570D01*
G37*
G36*
G01X1294970Y1119850D02*
X1295370Y1119708D01*
Y1118958D01*
X1294970Y1118815D01*
X1294770D01*
Y1119850D01*
X1294970D01*
G37*
G36*
G01Y1122200D02*
X1295370Y1122058D01*
Y1121308D01*
X1294970Y1121165D01*
X1294770D01*
Y1122200D01*
X1294970D01*
G37*
G36*
G01Y1124550D02*
X1295370Y1124408D01*
Y1123658D01*
X1294970Y1123515D01*
X1294770D01*
Y1124550D01*
X1294970D01*
G37*
G36*
G01Y1126900D02*
X1295370Y1126758D01*
Y1126008D01*
X1294970Y1125865D01*
X1294770D01*
Y1126900D01*
X1294970D01*
G37*
G36*
G01Y1129250D02*
X1295370Y1129108D01*
Y1128358D01*
X1294970Y1128215D01*
X1294770D01*
Y1129250D01*
X1294970D01*
G37*
G36*
G01X1292570Y1115150D02*
X1292970Y1115008D01*
Y1114258D01*
X1292570Y1114115D01*
X1292370D01*
Y1115150D01*
X1292570D01*
G37*
G36*
G01Y1117500D02*
X1292970Y1117358D01*
Y1116608D01*
X1292570Y1116465D01*
X1292370D01*
Y1117500D01*
X1292570D01*
G37*
G36*
G01X1292170Y1117640D02*
X1291770Y1117783D01*
Y1118533D01*
X1292170Y1118675D01*
X1292370D01*
Y1117640D01*
X1292170D01*
G37*
G36*
G01Y1112940D02*
X1291770Y1113083D01*
Y1113833D01*
X1292170Y1113975D01*
X1292370D01*
Y1112940D01*
X1292170D01*
G37*
G36*
G01Y1115290D02*
X1291770Y1115433D01*
Y1116183D01*
X1292170Y1116325D01*
X1292370D01*
Y1115290D01*
X1292170D01*
G37*
G36*
G01X1292570Y1119850D02*
X1292970Y1119708D01*
Y1118958D01*
X1292570Y1118815D01*
X1292370D01*
Y1119850D01*
X1292570D01*
G37*
G36*
G01Y1122200D02*
X1292970Y1122058D01*
Y1121308D01*
X1292570Y1121165D01*
X1292370D01*
Y1122200D01*
X1292570D01*
G37*
G36*
G01Y1124550D02*
X1292970Y1124408D01*
Y1123658D01*
X1292570Y1123515D01*
X1292370D01*
Y1124550D01*
X1292570D01*
G37*
G36*
G01X1292170Y1124690D02*
X1291770Y1124833D01*
Y1125583D01*
X1292170Y1125725D01*
X1292370D01*
Y1124690D01*
X1292170D01*
G37*
G36*
G01Y1119990D02*
X1291770Y1120133D01*
Y1120883D01*
X1292170Y1121025D01*
X1292370D01*
Y1119990D01*
X1292170D01*
G37*
G36*
G01Y1122340D02*
X1291770Y1122483D01*
Y1123233D01*
X1292170Y1123375D01*
X1292370D01*
Y1122340D01*
X1292170D01*
G37*
G36*
G01X1292570Y1126900D02*
X1292970Y1126758D01*
Y1126008D01*
X1292570Y1125865D01*
X1292370D01*
Y1126900D01*
X1292570D01*
G37*
G36*
G01X1292170Y1127040D02*
X1291770Y1127183D01*
Y1127933D01*
X1292170Y1128075D01*
X1292370D01*
Y1127040D01*
X1292170D01*
G37*
G36*
G01X1292570Y1129250D02*
X1292970Y1129108D01*
Y1128358D01*
X1292570Y1128215D01*
X1292370D01*
Y1129250D01*
X1292570D01*
G37*
G36*
G01X1293370Y1115290D02*
X1292970Y1115433D01*
Y1116183D01*
X1293370Y1116325D01*
X1293570D01*
Y1115290D01*
X1293370D01*
G37*
G36*
G01Y1117640D02*
X1292970Y1117783D01*
Y1118533D01*
X1293370Y1118675D01*
X1293570D01*
Y1117640D01*
X1293370D01*
G37*
G36*
G01X1293770Y1115150D02*
X1294170Y1115008D01*
Y1114258D01*
X1293770Y1114115D01*
X1293570D01*
Y1115150D01*
X1293770D01*
G37*
G36*
G01Y1117500D02*
X1294170Y1117358D01*
Y1116608D01*
X1293770Y1116465D01*
X1293570D01*
Y1117500D01*
X1293770D01*
G37*
G36*
G01X1293370Y1112940D02*
X1292970Y1113083D01*
Y1113833D01*
X1293370Y1113975D01*
X1293570D01*
Y1112940D01*
X1293370D01*
G37*
G36*
G01X1293770Y1126900D02*
X1294170Y1126758D01*
Y1126008D01*
X1293770Y1125865D01*
X1293570D01*
Y1126900D01*
X1293770D01*
G37*
G36*
G01X1293370Y1124690D02*
X1292970Y1124833D01*
Y1125583D01*
X1293370Y1125725D01*
X1293570D01*
Y1124690D01*
X1293370D01*
G37*
G36*
G01X1293770Y1119850D02*
X1294170Y1119708D01*
Y1118958D01*
X1293770Y1118815D01*
X1293570D01*
Y1119850D01*
X1293770D01*
G37*
G36*
G01Y1122200D02*
X1294170Y1122058D01*
Y1121308D01*
X1293770Y1121165D01*
X1293570D01*
Y1122200D01*
X1293770D01*
G37*
G36*
G01Y1124550D02*
X1294170Y1124408D01*
Y1123658D01*
X1293770Y1123515D01*
X1293570D01*
Y1124550D01*
X1293770D01*
G37*
G36*
G01X1293370Y1119990D02*
X1292970Y1120133D01*
Y1120883D01*
X1293370Y1121025D01*
X1293570D01*
Y1119990D01*
X1293370D01*
G37*
G36*
G01Y1122340D02*
X1292970Y1122483D01*
Y1123233D01*
X1293370Y1123375D01*
X1293570D01*
Y1122340D01*
X1293370D01*
G37*
G36*
G01Y1127040D02*
X1292970Y1127183D01*
Y1127933D01*
X1293370Y1128075D01*
X1293570D01*
Y1127040D01*
X1293370D01*
G37*
G36*
G01X1293770Y1129250D02*
X1294170Y1129108D01*
Y1128358D01*
X1293770Y1128215D01*
X1293570D01*
Y1129250D01*
X1293770D01*
G37*
G36*
G01X1290970Y1117640D02*
X1290570Y1117783D01*
Y1118533D01*
X1290970Y1118675D01*
X1291170D01*
Y1117640D01*
X1290970D01*
G37*
G36*
G01Y1112940D02*
X1290570Y1113083D01*
Y1113833D01*
X1290970Y1113975D01*
X1291170D01*
Y1112940D01*
X1290970D01*
G37*
G36*
G01Y1115290D02*
X1290570Y1115433D01*
Y1116183D01*
X1290970Y1116325D01*
X1291170D01*
Y1115290D01*
X1290970D01*
G37*
G36*
G01Y1119990D02*
X1290570Y1120133D01*
Y1120883D01*
X1290970Y1121025D01*
X1291170D01*
Y1119990D01*
X1290970D01*
G37*
G36*
G01Y1122340D02*
X1290570Y1122483D01*
Y1123233D01*
X1290970Y1123375D01*
X1291170D01*
Y1122340D01*
X1290970D01*
G37*
G36*
G01Y1127040D02*
X1290570Y1127183D01*
Y1127933D01*
X1290970Y1128075D01*
X1291170D01*
Y1127040D01*
X1290970D01*
G37*
G36*
G01Y1124690D02*
X1290570Y1124833D01*
Y1125583D01*
X1290970Y1125725D01*
X1291170D01*
Y1124690D01*
X1290970D01*
G37*
G36*
G01X1291370Y1115150D02*
X1291770Y1115008D01*
Y1114258D01*
X1291370Y1114115D01*
X1291170D01*
Y1115150D01*
X1291370D01*
G37*
G36*
G01Y1117500D02*
X1291770Y1117358D01*
Y1116608D01*
X1291370Y1116465D01*
X1291170D01*
Y1117500D01*
X1291370D01*
G37*
G36*
G01Y1119850D02*
X1291770Y1119708D01*
Y1118958D01*
X1291370Y1118815D01*
X1291170D01*
Y1119850D01*
X1291370D01*
G37*
G36*
G01Y1122200D02*
X1291770Y1122058D01*
Y1121308D01*
X1291370Y1121165D01*
X1291170D01*
Y1122200D01*
X1291370D01*
G37*
G36*
G01Y1124550D02*
X1291770Y1124408D01*
Y1123658D01*
X1291370Y1123515D01*
X1291170D01*
Y1124550D01*
X1291370D01*
G37*
G36*
G01Y1126900D02*
X1291770Y1126758D01*
Y1126008D01*
X1291370Y1125865D01*
X1291170D01*
Y1126900D01*
X1291370D01*
G37*
G36*
G01Y1129250D02*
X1291770Y1129108D01*
Y1128358D01*
X1291370Y1128215D01*
X1291170D01*
Y1129250D01*
X1291370D01*
G37*
G36*
G01X1284970Y1113426D02*
X1284570Y1113569D01*
Y1114319D01*
X1284970Y1114461D01*
X1285170D01*
Y1113426D01*
X1284970D01*
G37*
G36*
G01Y1115776D02*
X1284570Y1115919D01*
Y1116669D01*
X1284970Y1116811D01*
X1285170D01*
Y1115776D01*
X1284970D01*
G37*
G36*
G01Y1118126D02*
X1284570Y1118269D01*
Y1119019D01*
X1284970Y1119161D01*
X1285170D01*
Y1118126D01*
X1284970D01*
G37*
G36*
G01Y1125176D02*
X1284570Y1125319D01*
Y1126069D01*
X1284970Y1126211D01*
X1285170D01*
Y1125176D01*
X1284970D01*
G37*
G36*
G01Y1122826D02*
X1284570Y1122969D01*
Y1123719D01*
X1284970Y1123861D01*
X1285170D01*
Y1122826D01*
X1284970D01*
G37*
G36*
G01Y1120476D02*
X1284570Y1120619D01*
Y1121369D01*
X1284970Y1121511D01*
X1285170D01*
Y1120476D01*
X1284970D01*
G37*
G36*
G01X1285370Y1113286D02*
X1285770Y1113143D01*
Y1112393D01*
X1285370Y1112251D01*
X1285170D01*
Y1113286D01*
X1285370D01*
G37*
G36*
G01Y1115636D02*
X1285770Y1115493D01*
Y1114743D01*
X1285370Y1114601D01*
X1285170D01*
Y1115636D01*
X1285370D01*
G37*
G36*
G01Y1117986D02*
X1285770Y1117843D01*
Y1117093D01*
X1285370Y1116951D01*
X1285170D01*
Y1117986D01*
X1285370D01*
G37*
G36*
G01Y1127386D02*
X1285770Y1127243D01*
Y1126493D01*
X1285370Y1126351D01*
X1285170D01*
Y1127386D01*
X1285370D01*
G37*
G36*
G01Y1125036D02*
X1285770Y1124893D01*
Y1124143D01*
X1285370Y1124001D01*
X1285170D01*
Y1125036D01*
X1285370D01*
G37*
G36*
G01Y1122686D02*
X1285770Y1122543D01*
Y1121793D01*
X1285370Y1121651D01*
X1285170D01*
Y1122686D01*
X1285370D01*
G37*
G36*
G01Y1120336D02*
X1285770Y1120193D01*
Y1119443D01*
X1285370Y1119301D01*
X1285170D01*
Y1120336D01*
X1285370D01*
G37*
G36*
G01X1284970Y1127526D02*
X1284570Y1127669D01*
Y1128419D01*
X1284970Y1128561D01*
X1285170D01*
Y1127526D01*
X1284970D01*
G37*
G36*
G01X1282570Y1113426D02*
X1282170Y1113569D01*
Y1114319D01*
X1282570Y1114461D01*
X1282770D01*
Y1113426D01*
X1282570D01*
G37*
G36*
G01Y1115776D02*
X1282170Y1115919D01*
Y1116669D01*
X1282570Y1116811D01*
X1282770D01*
Y1115776D01*
X1282570D01*
G37*
G36*
G01X1282970Y1113286D02*
X1283370Y1113143D01*
Y1112393D01*
X1282970Y1112251D01*
X1282770D01*
Y1113286D01*
X1282970D01*
G37*
G36*
G01Y1115636D02*
X1283370Y1115493D01*
Y1114743D01*
X1282970Y1114601D01*
X1282770D01*
Y1115636D01*
X1282970D01*
G37*
G36*
G01Y1117986D02*
X1283370Y1117843D01*
Y1117093D01*
X1282970Y1116951D01*
X1282770D01*
Y1117986D01*
X1282970D01*
G37*
G36*
G01X1282570Y1118126D02*
X1282170Y1118269D01*
Y1119019D01*
X1282570Y1119161D01*
X1282770D01*
Y1118126D01*
X1282570D01*
G37*
G36*
G01X1282970Y1122686D02*
X1283370Y1122543D01*
Y1121793D01*
X1282970Y1121651D01*
X1282770D01*
Y1122686D01*
X1282970D01*
G37*
G36*
G01X1282570Y1120476D02*
X1282170Y1120619D01*
Y1121369D01*
X1282570Y1121511D01*
X1282770D01*
Y1120476D01*
X1282570D01*
G37*
G36*
G01X1282970Y1120336D02*
X1283370Y1120193D01*
Y1119443D01*
X1282970Y1119301D01*
X1282770D01*
Y1120336D01*
X1282970D01*
G37*
G36*
G01X1283770Y1113426D02*
X1283370Y1113569D01*
Y1114319D01*
X1283770Y1114461D01*
X1283970D01*
Y1113426D01*
X1283770D01*
G37*
G36*
G01Y1115776D02*
X1283370Y1115919D01*
Y1116669D01*
X1283770Y1116811D01*
X1283970D01*
Y1115776D01*
X1283770D01*
G37*
G36*
G01X1284170Y1113286D02*
X1284570Y1113143D01*
Y1112393D01*
X1284170Y1112251D01*
X1283970D01*
Y1113286D01*
X1284170D01*
G37*
G36*
G01Y1115636D02*
X1284570Y1115493D01*
Y1114743D01*
X1284170Y1114601D01*
X1283970D01*
Y1115636D01*
X1284170D01*
G37*
G36*
G01Y1117986D02*
X1284570Y1117843D01*
Y1117093D01*
X1284170Y1116951D01*
X1283970D01*
Y1117986D01*
X1284170D01*
G37*
G36*
G01X1283770Y1118126D02*
X1283370Y1118269D01*
Y1119019D01*
X1283770Y1119161D01*
X1283970D01*
Y1118126D01*
X1283770D01*
G37*
G36*
G01X1284170Y1127386D02*
X1284570Y1127243D01*
Y1126493D01*
X1284170Y1126351D01*
X1283970D01*
Y1127386D01*
X1284170D01*
G37*
G36*
G01X1283770Y1125176D02*
X1283370Y1125319D01*
Y1126069D01*
X1283770Y1126211D01*
X1283970D01*
Y1125176D01*
X1283770D01*
G37*
G36*
G01Y1120476D02*
X1283370Y1120619D01*
Y1121369D01*
X1283770Y1121511D01*
X1283970D01*
Y1120476D01*
X1283770D01*
G37*
G36*
G01Y1122826D02*
X1283370Y1122969D01*
Y1123719D01*
X1283770Y1123861D01*
X1283970D01*
Y1122826D01*
X1283770D01*
G37*
G36*
G01X1284170Y1120336D02*
X1284570Y1120193D01*
Y1119443D01*
X1284170Y1119301D01*
X1283970D01*
Y1120336D01*
X1284170D01*
G37*
G36*
G01Y1125036D02*
X1284570Y1124893D01*
Y1124143D01*
X1284170Y1124001D01*
X1283970D01*
Y1125036D01*
X1284170D01*
G37*
G36*
G01Y1122686D02*
X1284570Y1122543D01*
Y1121793D01*
X1284170Y1121651D01*
X1283970D01*
Y1122686D01*
X1284170D01*
G37*
G36*
G01X1281770Y1117986D02*
X1282170Y1117843D01*
Y1117093D01*
X1281770Y1116951D01*
X1281570D01*
Y1117986D01*
X1281770D01*
G37*
G36*
G01Y1113286D02*
X1282170Y1113143D01*
Y1112393D01*
X1281770Y1112251D01*
X1281570D01*
Y1113286D01*
X1281770D01*
G37*
G36*
G01Y1115636D02*
X1282170Y1115493D01*
Y1114743D01*
X1281770Y1114601D01*
X1281570D01*
Y1115636D01*
X1281770D01*
G37*
G36*
G01Y1122686D02*
X1282170Y1122543D01*
Y1121793D01*
X1281770Y1121651D01*
X1281570D01*
Y1122686D01*
X1281770D01*
G37*
G36*
G01Y1120336D02*
X1282170Y1120193D01*
Y1119443D01*
X1281770Y1119301D01*
X1281570D01*
Y1120336D01*
X1281770D01*
G37*
G36*
G01X1297970Y1113525D02*
X1297570Y1113668D01*
Y1114418D01*
X1297970Y1114560D01*
X1298170D01*
Y1113525D01*
X1297970D01*
G37*
G36*
G01Y1115875D02*
X1297570Y1116018D01*
Y1116768D01*
X1297970Y1116910D01*
X1298170D01*
Y1115875D01*
X1297970D01*
G37*
G36*
G01Y1125275D02*
X1297570Y1125418D01*
Y1126168D01*
X1297970Y1126310D01*
X1298170D01*
Y1125275D01*
X1297970D01*
G37*
G36*
G01Y1118225D02*
X1297570Y1118368D01*
Y1119118D01*
X1297970Y1119260D01*
X1298170D01*
Y1118225D01*
X1297970D01*
G37*
G36*
G01Y1120575D02*
X1297570Y1120718D01*
Y1121468D01*
X1297970Y1121610D01*
X1298170D01*
Y1120575D01*
X1297970D01*
G37*
G36*
G01Y1122925D02*
X1297570Y1123068D01*
Y1123818D01*
X1297970Y1123960D01*
X1298170D01*
Y1122925D01*
X1297970D01*
G37*
G36*
G01Y1127625D02*
X1297570Y1127768D01*
Y1128518D01*
X1297970Y1128660D01*
X1298170D01*
Y1127625D01*
X1297970D01*
G37*
G36*
G01X1297170Y1118085D02*
X1297570Y1117943D01*
Y1117193D01*
X1297170Y1117050D01*
X1296970D01*
Y1118085D01*
X1297170D01*
G37*
G36*
G01X1296770Y1113525D02*
X1296370Y1113668D01*
Y1114418D01*
X1296770Y1114560D01*
X1296970D01*
Y1113525D01*
X1296770D01*
G37*
G36*
G01Y1115875D02*
X1296370Y1116018D01*
Y1116768D01*
X1296770Y1116910D01*
X1296970D01*
Y1115875D01*
X1296770D01*
G37*
G36*
G01X1297170Y1113385D02*
X1297570Y1113243D01*
Y1112493D01*
X1297170Y1112350D01*
X1296970D01*
Y1113385D01*
X1297170D01*
G37*
G36*
G01Y1115735D02*
X1297570Y1115593D01*
Y1114843D01*
X1297170Y1114700D01*
X1296970D01*
Y1115735D01*
X1297170D01*
G37*
G36*
G01X1296770Y1118225D02*
X1296370Y1118368D01*
Y1119118D01*
X1296770Y1119260D01*
X1296970D01*
Y1118225D01*
X1296770D01*
G37*
G36*
G01X1297170Y1120435D02*
X1297570Y1120293D01*
Y1119543D01*
X1297170Y1119400D01*
X1296970D01*
Y1120435D01*
X1297170D01*
G37*
G36*
G01Y1122785D02*
X1297570Y1122643D01*
Y1121893D01*
X1297170Y1121750D01*
X1296970D01*
Y1122785D01*
X1297170D01*
G37*
G36*
G01Y1125135D02*
X1297570Y1124993D01*
Y1124243D01*
X1297170Y1124100D01*
X1296970D01*
Y1125135D01*
X1297170D01*
G37*
G36*
G01X1296770Y1120575D02*
X1296370Y1120718D01*
Y1121468D01*
X1296770Y1121610D01*
X1296970D01*
Y1120575D01*
X1296770D01*
G37*
G36*
G01Y1122925D02*
X1296370Y1123068D01*
Y1123818D01*
X1296770Y1123960D01*
X1296970D01*
Y1122925D01*
X1296770D01*
G37*
G36*
G01X1297170Y1127485D02*
X1297570Y1127343D01*
Y1126593D01*
X1297170Y1126450D01*
X1296970D01*
Y1127485D01*
X1297170D01*
G37*
G36*
G01X1296770Y1125275D02*
X1296370Y1125418D01*
Y1126168D01*
X1296770Y1126310D01*
X1296970D01*
Y1125275D01*
X1296770D01*
G37*
G36*
G01Y1127625D02*
X1296370Y1127768D01*
Y1128518D01*
X1296770Y1128660D01*
X1296970D01*
Y1127625D01*
X1296770D01*
G37*
G36*
G01X1294570Y1129390D02*
X1294170Y1129533D01*
Y1130283D01*
X1294570Y1130425D01*
X1294770D01*
Y1129390D01*
X1294570D01*
G37*
G36*
G01Y1131740D02*
X1294170Y1131883D01*
Y1132633D01*
X1294570Y1132775D01*
X1294770D01*
Y1131740D01*
X1294570D01*
G37*
G36*
G01Y1134090D02*
X1294170Y1134233D01*
Y1134983D01*
X1294570Y1135125D01*
X1294770D01*
Y1134090D01*
X1294570D01*
G37*
G36*
G01X1294970Y1133950D02*
X1295370Y1133808D01*
Y1133058D01*
X1294970Y1132915D01*
X1294770D01*
Y1133950D01*
X1294970D01*
G37*
G36*
G01Y1131600D02*
X1295370Y1131458D01*
Y1130708D01*
X1294970Y1130565D01*
X1294770D01*
Y1131600D01*
X1294970D01*
G37*
G36*
G01X1294570Y1138790D02*
X1294170Y1138933D01*
Y1139683D01*
X1294570Y1139825D01*
X1294770D01*
Y1138790D01*
X1294570D01*
G37*
G36*
G01Y1136440D02*
X1294170Y1136583D01*
Y1137333D01*
X1294570Y1137475D01*
X1294770D01*
Y1136440D01*
X1294570D01*
G37*
G36*
G01X1294970Y1138650D02*
X1295370Y1138508D01*
Y1137758D01*
X1294970Y1137615D01*
X1294770D01*
Y1138650D01*
X1294970D01*
G37*
G36*
G01Y1136300D02*
X1295370Y1136158D01*
Y1135408D01*
X1294970Y1135265D01*
X1294770D01*
Y1136300D01*
X1294970D01*
G37*
G36*
G01X1292570Y1133950D02*
X1292970Y1133808D01*
Y1133058D01*
X1292570Y1132915D01*
X1292370D01*
Y1133950D01*
X1292570D01*
G37*
G36*
G01Y1131600D02*
X1292970Y1131458D01*
Y1130708D01*
X1292570Y1130565D01*
X1292370D01*
Y1131600D01*
X1292570D01*
G37*
G36*
G01X1292170Y1134090D02*
X1291770Y1134233D01*
Y1134983D01*
X1292170Y1135125D01*
X1292370D01*
Y1134090D01*
X1292170D01*
G37*
G36*
G01Y1129390D02*
X1291770Y1129533D01*
Y1130283D01*
X1292170Y1130425D01*
X1292370D01*
Y1129390D01*
X1292170D01*
G37*
G36*
G01Y1131740D02*
X1291770Y1131883D01*
Y1132633D01*
X1292170Y1132775D01*
X1292370D01*
Y1131740D01*
X1292170D01*
G37*
G36*
G01X1292570Y1136300D02*
X1292970Y1136158D01*
Y1135408D01*
X1292570Y1135265D01*
X1292370D01*
Y1136300D01*
X1292570D01*
G37*
G36*
G01Y1138650D02*
X1292970Y1138508D01*
Y1137758D01*
X1292570Y1137615D01*
X1292370D01*
Y1138650D01*
X1292570D01*
G37*
G36*
G01X1292170Y1138790D02*
X1291770Y1138933D01*
Y1139683D01*
X1292170Y1139825D01*
X1292370D01*
Y1138790D01*
X1292170D01*
G37*
G36*
G01Y1136440D02*
X1291770Y1136583D01*
Y1137333D01*
X1292170Y1137475D01*
X1292370D01*
Y1136440D01*
X1292170D01*
G37*
G36*
G01X1293770Y1131600D02*
X1294170Y1131458D01*
Y1130708D01*
X1293770Y1130565D01*
X1293570D01*
Y1131600D01*
X1293770D01*
G37*
G36*
G01Y1133950D02*
X1294170Y1133808D01*
Y1133058D01*
X1293770Y1132915D01*
X1293570D01*
Y1133950D01*
X1293770D01*
G37*
G36*
G01X1293370Y1129390D02*
X1292970Y1129533D01*
Y1130283D01*
X1293370Y1130425D01*
X1293570D01*
Y1129390D01*
X1293370D01*
G37*
G36*
G01Y1131740D02*
X1292970Y1131883D01*
Y1132633D01*
X1293370Y1132775D01*
X1293570D01*
Y1131740D01*
X1293370D01*
G37*
G36*
G01Y1134090D02*
X1292970Y1134233D01*
Y1134983D01*
X1293370Y1135125D01*
X1293570D01*
Y1134090D01*
X1293370D01*
G37*
G36*
G01Y1136440D02*
X1292970Y1136583D01*
Y1137333D01*
X1293370Y1137475D01*
X1293570D01*
Y1136440D01*
X1293370D01*
G37*
G36*
G01X1293770Y1136300D02*
X1294170Y1136158D01*
Y1135408D01*
X1293770Y1135265D01*
X1293570D01*
Y1136300D01*
X1293770D01*
G37*
G36*
G01Y1138650D02*
X1294170Y1138508D01*
Y1137758D01*
X1293770Y1137615D01*
X1293570D01*
Y1138650D01*
X1293770D01*
G37*
G36*
G01X1293370Y1138790D02*
X1292970Y1138933D01*
Y1139683D01*
X1293370Y1139825D01*
X1293570D01*
Y1138790D01*
X1293370D01*
G37*
G36*
G01X1290970Y1129390D02*
X1290570Y1129533D01*
Y1130283D01*
X1290970Y1130425D01*
X1291170D01*
Y1129390D01*
X1290970D01*
G37*
G36*
G01Y1131740D02*
X1290570Y1131883D01*
Y1132633D01*
X1290970Y1132775D01*
X1291170D01*
Y1131740D01*
X1290970D01*
G37*
G36*
G01Y1134090D02*
X1290570Y1134233D01*
Y1134983D01*
X1290970Y1135125D01*
X1291170D01*
Y1134090D01*
X1290970D01*
G37*
G36*
G01Y1136440D02*
X1290570Y1136583D01*
Y1137333D01*
X1290970Y1137475D01*
X1291170D01*
Y1136440D01*
X1290970D01*
G37*
G36*
G01X1291370Y1133950D02*
X1291770Y1133808D01*
Y1133058D01*
X1291370Y1132915D01*
X1291170D01*
Y1133950D01*
X1291370D01*
G37*
G36*
G01Y1131600D02*
X1291770Y1131458D01*
Y1130708D01*
X1291370Y1130565D01*
X1291170D01*
Y1131600D01*
X1291370D01*
G37*
G36*
G01Y1136300D02*
X1291770Y1136158D01*
Y1135408D01*
X1291370Y1135265D01*
X1291170D01*
Y1136300D01*
X1291370D01*
G37*
G36*
G01X1284970Y1129876D02*
X1284570Y1130019D01*
Y1130769D01*
X1284970Y1130911D01*
X1285170D01*
Y1129876D01*
X1284970D01*
G37*
G36*
G01X1285370Y1129736D02*
X1285770Y1129593D01*
Y1128843D01*
X1285370Y1128701D01*
X1285170D01*
Y1129736D01*
X1285370D01*
G37*
G36*
G01Y1132086D02*
X1285770Y1131943D01*
Y1131193D01*
X1285370Y1131051D01*
X1285170D01*
Y1132086D01*
X1285370D01*
G37*
G36*
G01X1297970Y1134675D02*
X1297570Y1134818D01*
Y1135568D01*
X1297970Y1135710D01*
X1298170D01*
Y1134675D01*
X1297970D01*
G37*
G36*
G01Y1129975D02*
X1297570Y1130118D01*
Y1130868D01*
X1297970Y1131010D01*
X1298170D01*
Y1129975D01*
X1297970D01*
G37*
G36*
G01Y1132325D02*
X1297570Y1132468D01*
Y1133218D01*
X1297970Y1133360D01*
X1298170D01*
Y1132325D01*
X1297970D01*
G37*
G36*
G01Y1144075D02*
X1297570Y1144218D01*
Y1144968D01*
X1297970Y1145110D01*
X1298170D01*
Y1144075D01*
X1297970D01*
G37*
G36*
G01Y1141725D02*
X1297570Y1141868D01*
Y1142618D01*
X1297970Y1142760D01*
X1298170D01*
Y1141725D01*
X1297970D01*
G37*
G36*
G01Y1139375D02*
X1297570Y1139518D01*
Y1140268D01*
X1297970Y1140410D01*
X1298170D01*
Y1139375D01*
X1297970D01*
G37*
G36*
G01Y1137025D02*
X1297570Y1137168D01*
Y1137918D01*
X1297970Y1138060D01*
X1298170D01*
Y1137025D01*
X1297970D01*
G37*
G36*
G01X1296770Y1134675D02*
X1296370Y1134818D01*
Y1135568D01*
X1296770Y1135710D01*
X1296970D01*
Y1134675D01*
X1296770D01*
G37*
G36*
G01X1297170Y1129835D02*
X1297570Y1129693D01*
Y1128943D01*
X1297170Y1128800D01*
X1296970D01*
Y1129835D01*
X1297170D01*
G37*
G36*
G01X1296770Y1129975D02*
X1296370Y1130118D01*
Y1130868D01*
X1296770Y1131010D01*
X1296970D01*
Y1129975D01*
X1296770D01*
G37*
G36*
G01Y1132325D02*
X1296370Y1132468D01*
Y1133218D01*
X1296770Y1133360D01*
X1296970D01*
Y1132325D01*
X1296770D01*
G37*
G36*
G01X1297170Y1134535D02*
X1297570Y1134393D01*
Y1133643D01*
X1297170Y1133500D01*
X1296970D01*
Y1134535D01*
X1297170D01*
G37*
G36*
G01Y1132185D02*
X1297570Y1132043D01*
Y1131293D01*
X1297170Y1131150D01*
X1296970D01*
Y1132185D01*
X1297170D01*
G37*
G36*
G01Y1136885D02*
X1297570Y1136743D01*
Y1135993D01*
X1297170Y1135850D01*
X1296970D01*
Y1136885D01*
X1297170D01*
G37*
G36*
G01Y1143935D02*
X1297570Y1143793D01*
Y1143043D01*
X1297170Y1142900D01*
X1296970D01*
Y1143935D01*
X1297170D01*
G37*
G36*
G01X1296770Y1144075D02*
X1296370Y1144218D01*
Y1144968D01*
X1296770Y1145110D01*
X1296970D01*
Y1144075D01*
X1296770D01*
G37*
G36*
G01X1297170Y1141585D02*
X1297570Y1141443D01*
Y1140693D01*
X1297170Y1140550D01*
X1296970D01*
Y1141585D01*
X1297170D01*
G37*
G36*
G01X1296770Y1141725D02*
X1296370Y1141868D01*
Y1142618D01*
X1296770Y1142760D01*
X1296970D01*
Y1141725D01*
X1296770D01*
G37*
G36*
G01X1297170Y1139235D02*
X1297570Y1139093D01*
Y1138343D01*
X1297170Y1138200D01*
X1296970D01*
Y1139235D01*
X1297170D01*
G37*
G36*
G01X1296770Y1139375D02*
X1296370Y1139518D01*
Y1140268D01*
X1296770Y1140410D01*
X1296970D01*
Y1139375D01*
X1296770D01*
G37*
G36*
G01Y1137025D02*
X1296370Y1137168D01*
Y1137918D01*
X1296770Y1138060D01*
X1296970D01*
Y1137025D01*
X1296770D01*
G37*
G36*
G01X1297970Y1151125D02*
X1297570Y1151268D01*
Y1152018D01*
X1297970Y1152160D01*
X1298170D01*
Y1151125D01*
X1297970D01*
G37*
G36*
G01Y1148775D02*
X1297570Y1148918D01*
Y1149668D01*
X1297970Y1149810D01*
X1298170D01*
Y1148775D01*
X1297970D01*
G37*
G36*
G01Y1146425D02*
X1297570Y1146568D01*
Y1147318D01*
X1297970Y1147460D01*
X1298170D01*
Y1146425D01*
X1297970D01*
G37*
G36*
G01Y1155825D02*
X1297570Y1155968D01*
Y1156718D01*
X1297970Y1156860D01*
X1298170D01*
Y1155825D01*
X1297970D01*
G37*
G36*
G01Y1153475D02*
X1297570Y1153618D01*
Y1154368D01*
X1297970Y1154510D01*
X1298170D01*
Y1153475D01*
X1297970D01*
G37*
G36*
G01X1297170Y1146285D02*
X1297570Y1146143D01*
Y1145393D01*
X1297170Y1145250D01*
X1296970D01*
Y1146285D01*
X1297170D01*
G37*
G36*
G01X1296770Y1151125D02*
X1296370Y1151268D01*
Y1152018D01*
X1296770Y1152160D01*
X1296970D01*
Y1151125D01*
X1296770D01*
G37*
G36*
G01X1297170Y1150985D02*
X1297570Y1150843D01*
Y1150093D01*
X1297170Y1149950D01*
X1296970D01*
Y1150985D01*
X1297170D01*
G37*
G36*
G01Y1148635D02*
X1297570Y1148493D01*
Y1147743D01*
X1297170Y1147600D01*
X1296970D01*
Y1148635D01*
X1297170D01*
G37*
G36*
G01X1296770Y1148775D02*
X1296370Y1148918D01*
Y1149668D01*
X1296770Y1149810D01*
X1296970D01*
Y1148775D01*
X1296770D01*
G37*
G36*
G01Y1146425D02*
X1296370Y1146568D01*
Y1147318D01*
X1296770Y1147460D01*
X1296970D01*
Y1146425D01*
X1296770D01*
G37*
G36*
G01X1297170Y1155685D02*
X1297570Y1155543D01*
Y1154793D01*
X1297170Y1154650D01*
X1296970D01*
Y1155685D01*
X1297170D01*
G37*
G36*
G01Y1153335D02*
X1297570Y1153193D01*
Y1152443D01*
X1297170Y1152300D01*
X1296970D01*
Y1153335D01*
X1297170D01*
G37*
G36*
G01X1296770Y1155825D02*
X1296370Y1155968D01*
Y1156718D01*
X1296770Y1156860D01*
X1296970D01*
Y1155825D01*
X1296770D01*
G37*
G36*
G01Y1153475D02*
X1296370Y1153618D01*
Y1154368D01*
X1296770Y1154510D01*
X1296970D01*
Y1153475D01*
X1296770D01*
G37*
G36*
G01X1312316Y1308620D02*
Y1302408D01*
X1317116Y1297608D01*
X1334616D01*
X1335316Y1296908D01*
Y1291908D01*
X1334316Y1290908D01*
X1314576D01*
X1305816Y1299668D01*
Y1302908D01*
X1302616Y1306108D01*
X1284616D01*
X1283816Y1306908D01*
Y1311908D01*
X1284816Y1312908D01*
X1308028D01*
X1312316Y1308620D01*
G37*
G36*
G01X1468651Y1425371D02*
X1470152D01*
X1470505Y1425018D01*
Y1412728D01*
X1470526Y1412708D01*
Y1410978D01*
X1470886Y1410618D01*
X1473006D01*
X1473618Y1410006D01*
Y1381534D01*
X1473679Y1381473D01*
Y1378145D01*
X1474625Y1377199D01*
X1491046D01*
X1492409Y1378562D01*
X1542510D01*
X1543600Y1377472D01*
Y1351282D01*
X1543241Y1350923D01*
X1520250D01*
X1520030Y1351143D01*
Y1359042D01*
X1520303Y1359315D01*
X1525606D01*
X1526151Y1359860D01*
Y1360288D01*
X1526152Y1360291D01*
G03Y1360300I-798J5D01*
G01Y1362665D01*
G03X1526144Y1362773I-799J-5D01*
G01X1526130Y1362872D01*
X1527628Y1364371D01*
Y1371236D01*
X1525355Y1373509D01*
X1505503D01*
X1502050Y1370056D01*
Y1347933D01*
X1502391Y1347592D01*
Y1328943D01*
X1501573Y1328125D01*
X1487983D01*
X1487908Y1328200D01*
Y1336265D01*
X1488160Y1336517D01*
X1493661D01*
X1494023Y1336879D01*
Y1337490D01*
X1494024Y1337493D01*
G03Y1337502I-798J5D01*
G01Y1339867D01*
G03X1494016Y1339975I-799J-5D01*
G01X1494002Y1340074D01*
X1495466Y1341538D01*
Y1348393D01*
X1492038Y1351821D01*
X1475599D01*
G03X1473457Y1350442I0J-2353D01*
G01X1473442Y1350409D01*
X1469922Y1346889D01*
Y1319679D01*
X1469920Y1319678D01*
Y1319211D01*
X1469922Y1319209D01*
Y1315074D01*
X1469864Y1314932D01*
X1469631Y1314699D01*
X1455855D01*
X1455801Y1314753D01*
Y1322860D01*
X1456032Y1323091D01*
X1461332D01*
X1461895Y1323654D01*
Y1324064D01*
X1461896Y1324067D01*
G03Y1324076I-798J5D01*
G01Y1326441D01*
G03X1461888Y1326549I-799J-5D01*
G01X1461876Y1326634D01*
Y1327465D01*
X1463332Y1328921D01*
Y1335835D01*
X1460614Y1338553D01*
X1442793D01*
X1437794Y1333554D01*
Y1319679D01*
X1437792Y1319678D01*
Y1319211D01*
X1437794Y1319209D01*
Y1315074D01*
X1437736Y1314932D01*
X1437503Y1314699D01*
X1423860D01*
X1423730Y1314829D01*
Y1322872D01*
X1423949Y1323091D01*
X1429036D01*
X1429767Y1323822D01*
Y1324064D01*
X1429768Y1324067D01*
G03Y1324076I-798J5D01*
G01Y1326441D01*
G03X1429760Y1326549I-799J-5D01*
G01X1429746Y1326648D01*
X1429944Y1326846D01*
Y1327687D01*
X1430982Y1328725D01*
Y1334427D01*
X1427888Y1337521D01*
X1412593D01*
G03X1409709Y1337569I-1469J-1597D01*
G01X1409198Y1337131D01*
X1404781Y1332714D01*
Y1328946D01*
X1405666Y1328061D01*
Y1319679D01*
X1405664Y1319678D01*
Y1319211D01*
X1405666Y1319209D01*
Y1315074D01*
X1405608Y1314932D01*
X1405375Y1314699D01*
X1391599D01*
X1391578Y1314720D01*
Y1322894D01*
X1391776Y1323091D01*
X1397101D01*
X1397639Y1323629D01*
Y1324064D01*
X1397640Y1324067D01*
G03Y1324076I-798J5D01*
G01Y1326441D01*
G03X1397632Y1326549I-799J-5D01*
G01X1397618Y1326648D01*
X1397816Y1326846D01*
Y1326872D01*
X1399255Y1328311D01*
Y1334254D01*
X1395988Y1337521D01*
X1380719D01*
G03X1377878Y1337570I-1448J-1558D01*
G01X1377550Y1337283D01*
X1373538Y1333271D01*
Y1319679D01*
X1373536Y1319678D01*
Y1319211D01*
X1373538Y1319209D01*
Y1315074D01*
X1373480Y1314932D01*
X1373247Y1314699D01*
X1359643D01*
X1359440Y1314902D01*
Y1322882D01*
X1359648Y1323091D01*
X1364935D01*
X1365511Y1323667D01*
Y1324064D01*
X1365512Y1324067D01*
G03Y1324076I-798J5D01*
G01Y1326441D01*
G03X1365504Y1326549I-799J-5D01*
G01X1365490Y1326648D01*
X1368053Y1329211D01*
Y1335499D01*
X1366381Y1337171D01*
X1348604D01*
G03X1345426I-1589J-1295D01*
G01X1342206D01*
X1341214Y1336179D01*
Y1328725D01*
X1340614Y1328125D01*
X1327942D01*
X1327514Y1328553D01*
Y1336217D01*
X1327632Y1336335D01*
X1332996D01*
X1333614Y1336953D01*
Y1339853D01*
X1335214Y1341453D01*
Y1348818D01*
X1333279Y1350753D01*
X1316886D01*
G03X1315058Y1351711I-1828J-1265D01*
G01X1315056D01*
G03X1314859Y1351702I3J-2223D01*
G01X1314765Y1351694D01*
X1313656Y1352803D01*
X1311268D01*
X1309388Y1350923D01*
X1304009D01*
X1303740Y1351192D01*
X1295470D01*
X1295320Y1351342D01*
Y1359155D01*
X1295480Y1359315D01*
X1300805D01*
X1301265Y1359775D01*
Y1363482D01*
X1303520Y1365737D01*
Y1371223D01*
G03X1319749Y1390113I-4878J20607D01*
G01X1319764Y1390297D01*
X1359297D01*
X1373622Y1375972D01*
X1422210D01*
X1427300Y1381062D01*
X1430900Y1384662D01*
X1431500Y1385262D01*
X1452814D01*
X1468856Y1401304D01*
Y1422041D01*
X1468459Y1422438D01*
Y1425179D01*
X1468651Y1425371D01*
G37*
G36*
G01X1286090Y1575686D02*
G03I-720J0D01*
G37*
G36*
G01Y1580678D02*
G03I-720J0D01*
G37*
G36*
G01X1298150D02*
G03I-720J0D01*
G37*
G36*
G01X1293194D02*
G03I-720J0D01*
G37*
G36*
G01Y1575686D02*
G03I-720J0D01*
G37*
G36*
G01X1298150D02*
G03I-720J0D01*
G37*
G36*
G01X1286434Y1599884D02*
G03I-720J0D01*
G37*
G36*
G01X1291390D02*
G03I-720J0D01*
G37*
G36*
G01X1298494D02*
G03I-720J0D01*
G37*
G36*
G01X1286090Y1587598D02*
G03I-720J0D01*
G37*
G36*
G01Y1592590D02*
G03I-720J0D01*
G37*
G36*
G01X1298150D02*
G03I-720J0D01*
G37*
G36*
G01X1293194D02*
G03I-720J0D01*
G37*
G36*
G01X1298150Y1587598D02*
G03I-720J0D01*
G37*
G36*
G01X1293194D02*
G03I-720J0D01*
G37*
G36*
G01X1291390Y1616788D02*
G03I-720J0D01*
G37*
G36*
G01X1286434D02*
G03I-720J0D01*
G37*
G36*
G01Y1611796D02*
G03I-720J0D01*
G37*
G36*
G01X1291390D02*
G03I-720J0D01*
G37*
G36*
G01X1286434Y1604876D02*
G03I-720J0D01*
G37*
G36*
G01X1291390D02*
G03I-720J0D01*
G37*
G36*
G01X1298494Y1611796D02*
G03I-720J0D01*
G37*
G36*
G01Y1604876D02*
G03I-720J0D01*
G37*
G36*
G01Y1616788D02*
G03I-720J0D01*
G37*
G36*
G01X1313893Y279862D02*
X1327693D01*
X1329253Y278302D01*
X1329532Y277627D01*
Y261469D01*
G03X1329754Y260696I1462J1D01*
G01Y259025D01*
G03X1330157Y258052I1376J0D01*
G01X1331024Y257185D01*
Y237839D01*
X1330258Y237073D01*
G03X1330211Y237024I969J-977D01*
G02X1329862Y237158I-149J134D01*
G01Y239861D01*
X1329879Y239899D01*
G03X1329942Y240202I-693J302D01*
G01Y247160D01*
G03X1329721Y247695I-756J1D01*
G01X1329080Y248335D01*
Y252031D01*
G03X1328859Y252566I-756J1D01*
G01X1328094Y253331D01*
Y254064D01*
X1328937D01*
G03X1329438Y254566I0J501D01*
G01Y257366D01*
G03X1328937Y257868I-502J0D01*
G01X1327575D01*
X1327556Y258046D01*
G03X1327339Y258501I-752J-80D01*
G01X1327225Y258615D01*
X1327244Y258719D01*
G03X1327271Y259001I-1475J284D01*
G03X1326574Y260269I-1502J0D01*
G01Y262764D01*
X1325579D01*
G03X1325530Y262818I-584J-481D01*
G01Y263000D01*
X1325349D01*
X1322236Y266112D01*
Y271496D01*
X1322847Y272106D01*
X1328031D01*
G03X1328532Y272608I0J501D01*
G01Y277408D01*
G03X1328031Y277910I-502J0D01*
G01X1322431D01*
G03X1321930Y277408I0J-501D01*
G01Y273328D01*
X1320945Y272344D01*
G03X1320724Y271809I535J-534D01*
G01Y265799D01*
G03X1320945Y265264I756J-1D01*
G01X1323682Y262527D01*
X1323639Y262408D01*
G03X1323587Y262103I838J-300D01*
G01X1323588D01*
Y260925D01*
X1323587D01*
G03X1324153Y260090I890J-6D01*
G02X1324378Y259567I-146J-373D01*
G03X1324267Y259001I1391J-567D01*
G03X1325128Y257643I1501J0D01*
G02X1325240Y257435I-86J-181D01*
G03X1325236Y257366I497J-63D01*
G01Y254566D01*
G03X1325737Y254064I502J0D01*
G01X1326580D01*
Y253018D01*
G03X1326802Y252483I756J0D01*
G01X1327568Y251718D01*
Y248022D01*
G03X1327789Y247487I756J-1D01*
G01X1328430Y246847D01*
Y240202D01*
G03X1328493Y239899I756J-1D01*
G01X1328510Y239861D01*
Y239576D01*
X1328205D01*
X1328145Y239662D01*
G03X1328058Y239767I-624J-428D01*
G01X1326980Y240845D01*
G03X1326445Y241066I-534J-535D01*
G01X1324956D01*
X1324950Y241073D01*
Y241947D01*
X1324956Y241954D01*
X1326143D01*
G03X1326678Y242175I1J756D01*
G01X1327128Y242625D01*
G03X1327350Y243160I-534J535D01*
G01Y244522D01*
G03X1327128Y245057I-756J0D01*
G01X1326539Y245646D01*
G03X1326004Y245868I-535J-534D01*
G01X1325210D01*
G03X1325085Y246049I-1295J-761D01*
G02X1325178Y246632I313J249D01*
G03X1325578Y247375I-490J743D01*
G01Y248428D01*
X1325342D01*
Y250496D01*
X1325578D01*
Y251549D01*
G03X1324682Y252439I-890J0D01*
G01Y252438D01*
X1323761D01*
X1323340Y252859D01*
Y254096D01*
X1323425Y254156D01*
G03X1323638Y254566I-288J410D01*
G01Y257366D01*
G03X1323137Y257868I-502J0D01*
G01X1322298D01*
X1322251Y258001D01*
G03X1322072Y258286I-714J-250D01*
G01X1321843Y258515D01*
X1321862Y258619D01*
G03X1321889Y258901I-1475J284D01*
G03X1320959Y260290I-1502J0D01*
G02X1320731Y260786I152J370D01*
G03X1320777Y261073I-844J283D01*
G01X1320776D01*
Y262251D01*
X1320777D01*
G03X1319887Y263148I-890J7D01*
G01X1318959D01*
X1318262Y263845D01*
G03X1317727Y264066I-534J-535D01*
G01X1315053D01*
X1315036Y264083D01*
Y265414D01*
X1319369D01*
G03X1319870Y265916I0J501D01*
G01Y270716D01*
G03X1319369Y271218I-502J0D01*
G01X1313769D01*
G03X1313268Y270716I0J-501D01*
G01Y265916D01*
G03X1313451Y265529I501J0D01*
G01X1313524Y265469D01*
Y263770D01*
G03X1313745Y263235I756J-1D01*
G01X1314205Y262775D01*
G03X1314740Y262554I534J535D01*
G01X1317414D01*
X1317790Y262177D01*
Y260412D01*
X1318834D01*
Y260176D01*
X1319118D01*
Y259707D01*
X1319091Y259660D01*
G03X1318885Y258901I1295J-759D01*
G03X1319409Y257761I1502J0D01*
G02X1319467Y257540I-130J-152D01*
G03X1319436Y257366I470J-174D01*
G01Y254566D01*
G03X1319937Y254064I502J0D01*
G01X1321828D01*
Y252546D01*
G03X1322049Y252011I756J-1D01*
G01X1322608Y251453D01*
Y250496D01*
X1322844D01*
Y248428D01*
X1322608D01*
Y247375D01*
G03X1322865Y246750I890J1D01*
G02X1322860Y246183I-285J-281D01*
G03X1322410Y245111I1052J-1072D01*
G03X1323912Y243609I1502J0D01*
G03X1323983Y243611I-7J1502D01*
G02X1324128Y243264I9J-200D01*
G03X1324108Y243245I511J-558D01*
G01X1323658Y242795D01*
G03X1323436Y242260I534J-535D01*
G01Y242139D01*
G02X1323132Y241969I-200J0D01*
G03X1322708Y242140I-720J-1173D01*
G03X1322337Y242816I-1344J-298D01*
G01X1321842Y243311D01*
G03X1321535Y243543I-975J-971D01*
G03X1321588Y243922I-1323J378D01*
G01Y244622D01*
G03X1321373Y245362I-1376J1D01*
G03X1321588Y246102I-1161J739D01*
G01Y246802D01*
G03X1321373Y247542I-1376J1D01*
G03X1321588Y248282I-1161J739D01*
G01Y248982D01*
G03X1321198Y249942I-1377J0D01*
G01Y250936D01*
G03X1320795Y251909I-1376J0D01*
G01X1320706Y251998D01*
X1320702Y252073D01*
G03X1320301Y252956I-1373J-91D01*
G01X1319806Y253451D01*
G03X1319130Y253822I-974J-973D01*
G03X1318759Y254498I-1344J-298D01*
G01X1318264Y254993D01*
G03X1317588Y255364I-974J-973D01*
G03X1317217Y256040I-1344J-298D01*
G01X1316722Y256535D01*
G03X1316046Y256906I-974J-973D01*
G03X1315675Y257582I-1344J-298D01*
G01X1315180Y258077D01*
G03X1314504Y258448I-974J-973D01*
G03X1314133Y259124I-1344J-298D01*
G01X1313638Y259619D01*
G03X1312755Y260020I-974J-972D01*
G01X1312680Y260024D01*
X1312356Y260349D01*
X1312439Y260483D01*
G03X1312644Y261207I-1171J723D01*
G01Y261907D01*
G03X1312254Y262867I-1377J0D01*
G01Y264328D01*
G03X1312474Y265099I-1241J771D01*
G01Y278443D01*
X1313893Y279862D01*
G37*
G36*
G01X1309510Y290172D02*
G03I-720J0D01*
G37*
G36*
G01X1303170Y290072D02*
G03I-720J0D01*
G37*
G36*
G01X1308518Y287561D02*
G03I-720J0D01*
G37*
G36*
G01X1313966Y287631D02*
G03I-720J0D01*
G37*
G36*
G01X1299218Y852647D02*
X1299618Y852504D01*
Y851754D01*
X1299218Y851611D01*
X1299018D01*
Y852647D01*
X1299218D01*
G37*
G36*
G01X1298018D02*
X1298418Y852504D01*
Y851754D01*
X1298018Y851611D01*
X1297818D01*
Y852647D01*
X1298018D01*
G37*
G36*
G01X1300418D02*
X1300818Y852504D01*
Y851754D01*
X1300418Y851611D01*
X1300218D01*
Y852647D01*
X1300418D01*
G37*
G36*
G01X1306418Y852645D02*
X1306818Y852502D01*
Y851752D01*
X1306418Y851609D01*
X1306218D01*
Y852645D01*
X1306418D01*
G37*
G36*
G01X1308818D02*
X1309218Y852502D01*
Y851752D01*
X1308818Y851609D01*
X1308618D01*
Y852645D01*
X1308818D01*
G37*
G36*
G01X1307618D02*
X1308018Y852502D01*
Y851752D01*
X1307618Y851609D01*
X1307418D01*
Y852645D01*
X1307618D01*
G37*
G36*
G01X1298818Y855137D02*
X1298418Y855279D01*
Y856029D01*
X1298818Y856171D01*
X1299018D01*
Y855137D01*
X1298818D01*
G37*
G36*
G01Y857487D02*
X1298418Y857629D01*
Y858379D01*
X1298818Y858521D01*
X1299018D01*
Y857487D01*
X1298818D01*
G37*
G36*
G01X1299218Y854997D02*
X1299618Y854854D01*
Y854104D01*
X1299218Y853961D01*
X1299018D01*
Y854997D01*
X1299218D01*
G37*
G36*
G01Y857347D02*
X1299618Y857204D01*
Y856454D01*
X1299218Y856311D01*
X1299018D01*
Y857347D01*
X1299218D01*
G37*
G36*
G01Y859697D02*
X1299618Y859554D01*
Y858804D01*
X1299218Y858661D01*
X1299018D01*
Y859697D01*
X1299218D01*
G37*
G36*
G01X1298818Y852787D02*
X1298418Y852929D01*
Y853679D01*
X1298818Y853821D01*
X1299018D01*
Y852787D01*
X1298818D01*
G37*
G36*
G01X1298018Y854997D02*
X1298418Y854854D01*
Y854104D01*
X1298018Y853961D01*
X1297818D01*
Y854997D01*
X1298018D01*
G37*
G36*
G01Y859697D02*
X1298418Y859554D01*
Y858804D01*
X1298018Y858661D01*
X1297818D01*
Y859697D01*
X1298018D01*
G37*
G36*
G01Y857347D02*
X1298418Y857204D01*
Y856454D01*
X1298018Y856311D01*
X1297818D01*
Y857347D01*
X1298018D01*
G37*
G36*
G01X1300018Y857487D02*
X1299618Y857629D01*
Y858379D01*
X1300018Y858521D01*
X1300218D01*
Y857487D01*
X1300018D01*
G37*
G36*
G01Y855137D02*
X1299618Y855279D01*
Y856029D01*
X1300018Y856171D01*
X1300218D01*
Y855137D01*
X1300018D01*
G37*
G36*
G01X1300418Y859697D02*
X1300818Y859554D01*
Y858804D01*
X1300418Y858661D01*
X1300218D01*
Y859697D01*
X1300418D01*
G37*
G36*
G01Y857347D02*
X1300818Y857204D01*
Y856454D01*
X1300418Y856311D01*
X1300218D01*
Y857347D01*
X1300418D01*
G37*
G36*
G01Y854997D02*
X1300818Y854854D01*
Y854104D01*
X1300418Y853961D01*
X1300218D01*
Y854997D01*
X1300418D01*
G37*
G36*
G01X1300018Y852787D02*
X1299618Y852929D01*
Y853679D01*
X1300018Y853821D01*
X1300218D01*
Y852787D01*
X1300018D01*
G37*
G36*
G01X1306018Y857485D02*
X1305618Y857627D01*
Y858377D01*
X1306018Y858519D01*
X1306218D01*
Y857485D01*
X1306018D01*
G37*
G36*
G01Y852785D02*
X1305618Y852927D01*
Y853677D01*
X1306018Y853819D01*
X1306218D01*
Y852785D01*
X1306018D01*
G37*
G36*
G01X1306418Y854995D02*
X1306818Y854852D01*
Y854102D01*
X1306418Y853959D01*
X1306218D01*
Y854995D01*
X1306418D01*
G37*
G36*
G01Y859695D02*
X1306818Y859552D01*
Y858802D01*
X1306418Y858659D01*
X1306218D01*
Y859695D01*
X1306418D01*
G37*
G36*
G01Y857345D02*
X1306818Y857202D01*
Y856452D01*
X1306418Y856309D01*
X1306218D01*
Y857345D01*
X1306418D01*
G37*
G36*
G01X1306018Y855135D02*
X1305618Y855277D01*
Y856027D01*
X1306018Y856169D01*
X1306218D01*
Y855135D01*
X1306018D01*
G37*
G36*
G01X1308818Y854995D02*
X1309218Y854852D01*
Y854102D01*
X1308818Y853959D01*
X1308618D01*
Y854995D01*
X1308818D01*
G37*
G36*
G01Y857345D02*
X1309218Y857202D01*
Y856452D01*
X1308818Y856309D01*
X1308618D01*
Y857345D01*
X1308818D01*
G37*
G36*
G01Y859695D02*
X1309218Y859552D01*
Y858802D01*
X1308818Y858659D01*
X1308618D01*
Y859695D01*
X1308818D01*
G37*
G36*
G01X1308418Y855135D02*
X1308018Y855277D01*
Y856027D01*
X1308418Y856169D01*
X1308618D01*
Y855135D01*
X1308418D01*
G37*
G36*
G01Y857485D02*
X1308018Y857627D01*
Y858377D01*
X1308418Y858519D01*
X1308618D01*
Y857485D01*
X1308418D01*
G37*
G36*
G01Y852785D02*
X1308018Y852927D01*
Y853677D01*
X1308418Y853819D01*
X1308618D01*
Y852785D01*
X1308418D01*
G37*
G36*
G01X1307218Y855135D02*
X1306818Y855277D01*
Y856027D01*
X1307218Y856169D01*
X1307418D01*
Y855135D01*
X1307218D01*
G37*
G36*
G01Y857485D02*
X1306818Y857627D01*
Y858377D01*
X1307218Y858519D01*
X1307418D01*
Y857485D01*
X1307218D01*
G37*
G36*
G01Y852785D02*
X1306818Y852927D01*
Y853677D01*
X1307218Y853819D01*
X1307418D01*
Y852785D01*
X1307218D01*
G37*
G36*
G01X1307618Y854995D02*
X1308018Y854852D01*
Y854102D01*
X1307618Y853959D01*
X1307418D01*
Y854995D01*
X1307618D01*
G37*
G36*
G01Y859695D02*
X1308018Y859552D01*
Y858802D01*
X1307618Y858659D01*
X1307418D01*
Y859695D01*
X1307618D01*
G37*
G36*
G01Y857345D02*
X1308018Y857202D01*
Y856452D01*
X1307618Y856309D01*
X1307418D01*
Y857345D01*
X1307618D01*
G37*
G36*
G01X1309618Y855135D02*
X1309218Y855277D01*
Y856027D01*
X1309618Y856169D01*
X1309818D01*
Y855135D01*
X1309618D01*
G37*
G36*
G01Y857485D02*
X1309218Y857627D01*
Y858377D01*
X1309618Y858519D01*
X1309818D01*
Y857485D01*
X1309618D01*
G37*
G36*
G01X1310018Y854995D02*
X1310418Y854852D01*
Y854102D01*
X1310018Y853959D01*
X1309818D01*
Y854995D01*
X1310018D01*
G37*
G36*
G01Y857345D02*
X1310418Y857202D01*
Y856452D01*
X1310018Y856309D01*
X1309818D01*
Y857345D01*
X1310018D01*
G37*
G36*
G01X1309618Y852785D02*
X1309218Y852927D01*
Y853677D01*
X1309618Y853819D01*
X1309818D01*
Y852785D01*
X1309618D01*
G37*
G36*
G01X1300075Y897822D02*
X1300257Y897438D01*
X1299727Y896908D01*
X1299343Y897090D01*
X1299202Y897231D01*
X1299934Y897963D01*
X1300075Y897822D01*
G37*
G36*
G01X1298230Y896542D02*
X1298048Y896925D01*
X1298578Y897456D01*
X1298962Y897273D01*
X1299103Y897132D01*
X1298371Y896400D01*
X1298230Y896542D01*
G37*
G36*
G01X1301737Y899483D02*
X1301919Y899100D01*
X1301389Y898569D01*
X1301005Y898751D01*
X1300864Y898893D01*
X1301596Y899625D01*
X1301737Y899483D01*
G37*
G36*
G01X1299892Y898203D02*
X1299709Y898587D01*
X1300240Y899117D01*
X1300623Y898935D01*
X1300765Y898794D01*
X1300033Y898062D01*
X1299892Y898203D01*
G37*
G36*
G01X1301553Y899865D02*
X1301371Y900249D01*
X1301901Y900779D01*
X1302285Y900597D01*
X1302426Y900455D01*
X1301695Y899724D01*
X1301553Y899865D01*
G37*
G36*
G01X1298267Y893181D02*
X1298085Y893565D01*
X1298615Y894095D01*
X1298998Y893913D01*
X1299140Y893772D01*
X1298408Y893040D01*
X1298267Y893181D01*
G37*
G36*
G01X1301774Y896123D02*
X1301956Y895739D01*
X1301426Y895209D01*
X1301042Y895391D01*
X1300901Y895533D01*
X1301632Y896264D01*
X1301774Y896123D01*
G37*
G36*
G01X1301590Y896505D02*
X1301408Y896888D01*
X1301938Y897419D01*
X1302322Y897237D01*
X1302463Y897095D01*
X1301731Y896363D01*
X1301590Y896505D01*
G37*
G36*
G01X1299928Y894843D02*
X1299746Y895227D01*
X1300277Y895757D01*
X1300660Y895575D01*
X1300802Y895434D01*
X1300070Y894702D01*
X1299928Y894843D01*
G37*
G36*
G01X1300112Y894461D02*
X1300294Y894078D01*
X1299764Y893547D01*
X1299380Y893729D01*
X1299239Y893871D01*
X1299971Y894603D01*
X1300112Y894461D01*
G37*
G36*
G01X1303436Y897785D02*
X1303618Y897401D01*
X1303087Y896871D01*
X1302704Y897053D01*
X1302562Y897194D01*
X1303294Y897926D01*
X1303436Y897785D01*
G37*
G36*
G01X1303252Y898167D02*
X1303070Y898550D01*
X1303600Y899080D01*
X1303984Y898898D01*
X1304125Y898757D01*
X1303393Y898025D01*
X1303252Y898167D01*
G37*
G36*
G01X1299263Y895310D02*
X1299445Y894927D01*
X1298915Y894396D01*
X1298531Y894578D01*
X1298390Y894720D01*
X1299122Y895452D01*
X1299263Y895310D01*
G37*
G36*
G01X1299079Y895692D02*
X1298897Y896076D01*
X1299428Y896606D01*
X1299811Y896424D01*
X1299953Y896283D01*
X1299221Y895551D01*
X1299079Y895692D01*
G37*
G36*
G01X1300925Y896972D02*
X1301107Y896588D01*
X1300577Y896058D01*
X1300193Y896240D01*
X1300052Y896382D01*
X1300783Y897113D01*
X1300925Y896972D01*
G37*
G36*
G01X1300741Y897354D02*
X1300559Y897737D01*
X1301089Y898268D01*
X1301473Y898086D01*
X1301614Y897944D01*
X1300882Y897212D01*
X1300741Y897354D01*
G37*
G36*
G01X1297958Y886143D02*
X1298358Y886001D01*
Y885251D01*
X1297958Y885109D01*
X1297758D01*
Y886143D01*
X1297958D01*
G37*
G36*
G01Y888493D02*
X1298358Y888351D01*
Y887601D01*
X1297958Y887459D01*
X1297758D01*
Y888493D01*
X1297958D01*
G37*
G36*
G01X1299116Y892332D02*
X1298934Y892716D01*
X1299464Y893246D01*
X1299847Y893064D01*
X1299989Y892923D01*
X1299257Y892191D01*
X1299116Y892332D01*
G37*
G36*
G01X1300777Y893994D02*
X1300595Y894378D01*
X1301126Y894908D01*
X1301509Y894726D01*
X1301651Y894585D01*
X1300919Y893853D01*
X1300777Y893994D01*
G37*
G36*
G01X1299299Y891951D02*
X1299482Y891567D01*
X1298951Y891037D01*
X1298568Y891219D01*
X1298426Y891360D01*
X1299158Y892092D01*
X1299299Y891951D01*
G37*
G36*
G01X1300961Y893612D02*
X1301143Y893229D01*
X1300613Y892698D01*
X1300229Y892880D01*
X1300088Y893022D01*
X1300820Y893754D01*
X1300961Y893612D01*
G37*
G36*
G01X1304101Y897318D02*
X1303919Y897701D01*
X1304449Y898231D01*
X1304833Y898049D01*
X1304974Y897908D01*
X1304242Y897176D01*
X1304101Y897318D01*
G37*
G36*
G01X1302439Y895656D02*
X1302257Y896039D01*
X1302787Y896570D01*
X1303171Y896388D01*
X1303312Y896246D01*
X1302580Y895514D01*
X1302439Y895656D01*
G37*
G36*
G01X1302623Y895274D02*
X1302805Y894890D01*
X1302275Y894360D01*
X1301891Y894542D01*
X1301750Y894684D01*
X1302481Y895415D01*
X1302623Y895274D01*
G37*
G36*
G01X1304285Y896936D02*
X1304467Y896552D01*
X1303936Y896022D01*
X1303553Y896204D01*
X1303411Y896345D01*
X1304143Y897077D01*
X1304285Y896936D01*
G37*
G36*
G01X1298944Y915876D02*
X1298762Y916260D01*
X1299292Y916790D01*
X1299676Y916608D01*
X1299817Y916467D01*
X1299085Y915735D01*
X1298944Y915876D01*
G37*
G36*
G01X1300789Y917156D02*
X1300971Y916773D01*
X1300441Y916242D01*
X1300057Y916425D01*
X1299916Y916566D01*
X1300648Y917298D01*
X1300789Y917156D01*
G37*
G36*
G01X1299128Y915495D02*
X1299310Y915111D01*
X1298779Y914581D01*
X1298396Y914763D01*
X1298254Y914904D01*
X1298986Y915636D01*
X1299128Y915495D01*
G37*
G36*
G01X1298095Y916725D02*
X1297913Y917109D01*
X1298443Y917639D01*
X1298827Y917457D01*
X1298968Y917316D01*
X1298236Y916584D01*
X1298095Y916725D01*
G37*
G36*
G01X1299793Y915027D02*
X1299611Y915411D01*
X1300141Y915941D01*
X1300525Y915759D01*
X1300666Y915618D01*
X1299934Y914886D01*
X1299793Y915027D01*
G37*
G36*
G01X1298131Y913366D02*
X1297949Y913749D01*
X1298479Y914280D01*
X1298863Y914098D01*
X1299004Y913956D01*
X1298272Y913224D01*
X1298131Y913366D01*
G37*
G36*
G01X1299977Y914646D02*
X1300159Y914262D01*
X1299628Y913732D01*
X1299245Y913914D01*
X1299103Y914055D01*
X1299835Y914787D01*
X1299977Y914646D01*
G37*
G36*
G01X1300829Y912159D02*
X1301011Y911775D01*
X1300480Y911245D01*
X1300097Y911427D01*
X1299955Y911568D01*
X1300687Y912300D01*
X1300829Y912159D01*
G37*
G36*
G01X1299167Y910497D02*
X1299349Y910114D01*
X1298819Y909583D01*
X1298435Y909765D01*
X1298294Y909907D01*
X1299026Y910639D01*
X1299167Y910497D01*
G37*
G36*
G01X1300645Y912541D02*
X1300463Y912924D01*
X1300993Y913455D01*
X1301377Y913273D01*
X1301518Y913131D01*
X1300786Y912399D01*
X1300645Y912541D01*
G37*
G36*
G01X1298983Y910879D02*
X1298801Y911263D01*
X1299331Y911793D01*
X1299715Y911611D01*
X1299856Y911469D01*
X1299125Y910738D01*
X1298983Y910879D01*
G37*
G36*
G01X1302490Y913821D02*
X1302672Y913437D01*
X1302142Y912907D01*
X1301758Y913089D01*
X1301617Y913230D01*
X1302349Y913962D01*
X1302490Y913821D01*
G37*
G36*
G01X1300865Y908799D02*
X1301047Y908416D01*
X1300517Y907885D01*
X1300133Y908067D01*
X1299992Y908209D01*
X1300724Y908941D01*
X1300865Y908799D01*
G37*
G36*
G01X1300681Y909181D02*
X1300499Y909565D01*
X1301029Y910095D01*
X1301413Y909913D01*
X1301554Y909771D01*
X1300823Y909040D01*
X1300681Y909181D01*
G37*
G36*
G01X1299019Y907519D02*
X1298837Y907903D01*
X1299368Y908433D01*
X1299751Y908251D01*
X1299893Y908110D01*
X1299161Y907378D01*
X1299019Y907519D01*
G37*
G36*
G01X1299203Y907137D02*
X1299385Y906754D01*
X1298855Y906223D01*
X1298471Y906406D01*
X1298330Y906547D01*
X1299062Y907279D01*
X1299203Y907137D01*
G37*
G36*
G01X1302527Y910461D02*
X1302709Y910077D01*
X1302178Y909547D01*
X1301795Y909729D01*
X1301653Y909870D01*
X1302385Y910602D01*
X1302527Y910461D01*
G37*
G36*
G01X1302343Y910843D02*
X1302161Y911226D01*
X1302691Y911757D01*
X1303075Y911575D01*
X1303216Y911433D01*
X1302484Y910701D01*
X1302343Y910843D01*
G37*
G36*
G01X1300016Y909648D02*
X1300198Y909265D01*
X1299668Y908734D01*
X1299284Y908916D01*
X1299143Y909058D01*
X1299875Y909790D01*
X1300016Y909648D01*
G37*
G36*
G01X1301494Y911692D02*
X1301312Y912075D01*
X1301842Y912606D01*
X1302226Y912424D01*
X1302367Y912282D01*
X1301635Y911550D01*
X1301494Y911692D01*
G37*
G36*
G01X1299832Y910030D02*
X1299650Y910414D01*
X1300180Y910944D01*
X1300564Y910762D01*
X1300705Y910620D01*
X1299974Y909889D01*
X1299832Y910030D01*
G37*
G36*
G01X1298170Y908368D02*
X1297988Y908752D01*
X1298519Y909282D01*
X1298902Y909100D01*
X1299044Y908959D01*
X1298312Y908227D01*
X1298170Y908368D01*
G37*
G36*
G01X1301678Y911310D02*
X1301860Y910926D01*
X1301329Y910396D01*
X1300946Y910578D01*
X1300804Y910719D01*
X1301536Y911451D01*
X1301678Y911310D01*
G37*
G36*
G01X1301714Y907950D02*
X1301896Y907567D01*
X1301366Y907036D01*
X1300982Y907218D01*
X1300841Y907360D01*
X1301573Y908092D01*
X1301714Y907950D01*
G37*
G36*
G01X1298207Y905009D02*
X1298025Y905392D01*
X1298555Y905922D01*
X1298939Y905740D01*
X1299080Y905599D01*
X1298348Y904867D01*
X1298207Y905009D01*
G37*
G36*
G01X1300052Y906288D02*
X1300234Y905905D01*
X1299704Y905374D01*
X1299320Y905557D01*
X1299179Y905698D01*
X1299911Y906430D01*
X1300052Y906288D01*
G37*
G36*
G01X1299868Y906670D02*
X1299686Y907054D01*
X1300217Y907584D01*
X1300600Y907402D01*
X1300742Y907261D01*
X1300010Y906529D01*
X1299868Y906670D01*
G37*
G36*
G01X1301530Y908332D02*
X1301348Y908716D01*
X1301878Y909246D01*
X1302262Y909064D01*
X1302403Y908922D01*
X1301672Y908191D01*
X1301530Y908332D01*
G37*
G36*
G01X1303376Y909612D02*
X1303558Y909228D01*
X1303027Y908698D01*
X1302644Y908880D01*
X1302502Y909021D01*
X1303234Y909753D01*
X1303376Y909612D01*
G37*
G36*
G01X1297909Y930125D02*
X1297727Y930509D01*
X1298257Y931039D01*
X1298641Y930857D01*
X1298782Y930715D01*
X1298051Y929984D01*
X1297909Y930125D01*
G37*
G36*
G01X1297945Y926765D02*
X1297763Y927149D01*
X1298294Y927679D01*
X1298677Y927497D01*
X1298819Y927356D01*
X1298087Y926624D01*
X1297945Y926765D01*
G37*
G36*
G01X1299791Y928045D02*
X1299973Y927662D01*
X1299443Y927131D01*
X1299059Y927313D01*
X1298918Y927455D01*
X1299650Y928187D01*
X1299791Y928045D01*
G37*
G36*
G01X1299091Y918855D02*
X1299273Y918471D01*
X1298742Y917941D01*
X1298359Y918123D01*
X1298217Y918264D01*
X1298949Y918996D01*
X1299091Y918855D01*
G37*
G36*
G01X1299940Y918005D02*
X1300122Y917622D01*
X1299592Y917091D01*
X1299208Y917274D01*
X1299067Y917415D01*
X1299799Y918147D01*
X1299940Y918005D01*
G37*
G36*
G01X1298906Y932254D02*
X1299088Y931870D01*
X1298557Y931340D01*
X1298174Y931522D01*
X1298032Y931663D01*
X1298764Y932395D01*
X1298906Y932254D01*
G37*
G36*
G01X1298942Y928894D02*
X1299124Y928511D01*
X1298594Y927980D01*
X1298210Y928162D01*
X1298069Y928304D01*
X1298801Y929036D01*
X1298942Y928894D01*
G37*
G36*
G01X1300864Y939604D02*
X1300721Y939204D01*
X1299971D01*
X1299828Y939604D01*
Y939804D01*
X1300864D01*
Y939604D01*
G37*
G36*
G01X1298654Y940004D02*
X1298796Y940404D01*
X1299546D01*
X1299688Y940004D01*
Y939804D01*
X1298654D01*
Y940004D01*
G37*
G36*
G01X1301004D02*
X1301146Y940404D01*
X1301896D01*
X1302038Y940004D01*
Y939804D01*
X1301004D01*
Y940004D01*
G37*
G36*
G01X1300864Y937204D02*
X1300721Y936804D01*
X1299971D01*
X1299828Y937204D01*
Y937404D01*
X1300864D01*
Y937204D01*
G37*
G36*
G01X1301004Y937604D02*
X1301146Y938004D01*
X1301896D01*
X1302038Y937604D01*
Y937404D01*
X1301004D01*
Y937604D01*
G37*
G36*
G01X1298654D02*
X1298796Y938004D01*
X1299546D01*
X1299688Y937604D01*
Y937404D01*
X1298654D01*
Y937604D01*
G37*
G36*
G01X1300864Y938404D02*
X1300721Y938004D01*
X1299971D01*
X1299828Y938404D01*
Y938604D01*
X1300864D01*
Y938404D01*
G37*
G36*
G01X1301004Y938804D02*
X1301146Y939204D01*
X1301896D01*
X1302038Y938804D01*
Y938604D01*
X1301004D01*
Y938804D01*
G37*
G36*
G01X1298654D02*
X1298796Y939204D01*
X1299546D01*
X1299688Y938804D01*
Y938604D01*
X1298654D01*
Y938804D01*
G37*
G36*
G01X1301004Y936404D02*
X1301146Y936804D01*
X1301896D01*
X1302038Y936404D01*
Y936204D01*
X1301004D01*
Y936404D01*
G37*
G36*
G01X1300864Y936004D02*
X1300721Y935604D01*
X1299971D01*
X1299828Y936004D01*
Y936204D01*
X1300864D01*
Y936004D01*
G37*
G36*
G01X1303214D02*
X1303071Y935604D01*
X1302321D01*
X1302178Y936004D01*
Y936204D01*
X1303214D01*
Y936004D01*
G37*
G36*
G01X1302108Y954295D02*
X1301725Y954113D01*
X1301195Y954643D01*
X1301377Y955027D01*
X1301518Y955168D01*
X1302250Y954436D01*
X1302108Y954295D01*
G37*
G36*
G01X1303770Y952633D02*
X1303387Y952451D01*
X1302856Y952981D01*
X1303038Y953365D01*
X1303180Y953506D01*
X1303912Y952774D01*
X1303770Y952633D01*
G37*
G36*
G01X1302490Y954479D02*
X1302874Y954661D01*
X1303404Y954130D01*
X1303222Y953747D01*
X1303081Y953605D01*
X1302349Y954337D01*
X1302490Y954479D01*
G37*
G36*
G01X1302071Y950934D02*
X1301687Y950752D01*
X1301157Y951282D01*
X1301339Y951666D01*
X1301481Y951807D01*
X1302213Y951075D01*
X1302071Y950934D01*
G37*
G36*
G01X1300792Y952780D02*
X1301175Y952962D01*
X1301706Y952432D01*
X1301524Y952048D01*
X1301382Y951906D01*
X1300650Y952638D01*
X1300792Y952780D01*
G37*
G36*
G01X1302453Y951118D02*
X1302837Y951300D01*
X1303367Y950770D01*
X1303185Y950386D01*
X1303043Y950245D01*
X1302312Y950976D01*
X1302453Y951118D01*
G37*
G36*
G01X1301641Y953629D02*
X1302024Y953811D01*
X1302555Y953281D01*
X1302373Y952897D01*
X1302231Y952756D01*
X1301499Y953488D01*
X1301641Y953629D01*
G37*
G36*
G01X1301259Y953445D02*
X1300875Y953263D01*
X1300345Y953793D01*
X1300527Y954177D01*
X1300669Y954318D01*
X1301400Y953587D01*
X1301259Y953445D01*
G37*
G36*
G01X1302921Y951784D02*
X1302537Y951601D01*
X1302007Y952132D01*
X1302189Y952515D01*
X1302330Y952657D01*
X1303062Y951925D01*
X1302921Y951784D01*
G37*
G36*
G01X1301604Y950268D02*
X1301988Y950450D01*
X1302518Y949920D01*
X1302336Y949536D01*
X1302194Y949395D01*
X1301463Y950126D01*
X1301604Y950268D01*
G37*
G36*
G01X1297846Y1014119D02*
X1297988Y1014519D01*
X1298738D01*
X1298881Y1014119D01*
Y1013919D01*
X1297846D01*
Y1014119D01*
G37*
G36*
G01Y1012919D02*
X1297988Y1013319D01*
X1298738D01*
X1298881Y1012919D01*
Y1012719D01*
X1297846D01*
Y1012919D01*
G37*
G36*
G01Y1011719D02*
X1297988Y1012119D01*
X1298738D01*
X1298881Y1011719D01*
Y1011519D01*
X1297846D01*
Y1011719D01*
G37*
G36*
G01X1300196Y1017719D02*
X1300338Y1018119D01*
X1301088D01*
X1301231Y1017719D01*
Y1017519D01*
X1300196D01*
Y1017719D01*
G37*
G36*
G01X1297846D02*
X1297988Y1018119D01*
X1298738D01*
X1298881Y1017719D01*
Y1017519D01*
X1297846D01*
Y1017719D01*
G37*
G36*
G01X1300056Y1017319D02*
X1299914Y1016919D01*
X1299164D01*
X1299021Y1017319D01*
Y1017519D01*
X1300056D01*
Y1017319D01*
G37*
G36*
G01Y1016119D02*
X1299914Y1015719D01*
X1299164D01*
X1299021Y1016119D01*
Y1016319D01*
X1300056D01*
Y1016119D01*
G37*
G36*
G01X1297846Y1016519D02*
X1297988Y1016919D01*
X1298738D01*
X1298881Y1016519D01*
Y1016319D01*
X1297846D01*
Y1016519D01*
G37*
G36*
G01X1300056Y1014919D02*
X1299914Y1014519D01*
X1299164D01*
X1299021Y1014919D01*
Y1015119D01*
X1300056D01*
Y1014919D01*
G37*
G36*
G01X1297846Y1015319D02*
X1297988Y1015719D01*
X1298738D01*
X1298881Y1015319D01*
Y1015119D01*
X1297846D01*
Y1015319D01*
G37*
G36*
G01X1300196Y1022519D02*
X1300338Y1022919D01*
X1301088D01*
X1301231Y1022519D01*
Y1022319D01*
X1300196D01*
Y1022519D01*
G37*
G36*
G01X1302406Y1022119D02*
X1302264Y1021719D01*
X1301514D01*
X1301371Y1022119D01*
Y1022319D01*
X1302406D01*
Y1022119D01*
G37*
G36*
G01X1297846Y1022519D02*
X1297988Y1022919D01*
X1298738D01*
X1298881Y1022519D01*
Y1022319D01*
X1297846D01*
Y1022519D01*
G37*
G36*
G01X1300056Y1022119D02*
X1299914Y1021719D01*
X1299164D01*
X1299021Y1022119D01*
Y1022319D01*
X1300056D01*
Y1022119D01*
G37*
G36*
G01X1304756D02*
X1304614Y1021719D01*
X1303864D01*
X1303721Y1022119D01*
Y1022319D01*
X1304756D01*
Y1022119D01*
G37*
G36*
G01X1304896Y1022519D02*
X1305038Y1022919D01*
X1305788D01*
X1305931Y1022519D01*
Y1022319D01*
X1304896D01*
Y1022519D01*
G37*
G36*
G01X1302546D02*
X1302688Y1022919D01*
X1303438D01*
X1303581Y1022519D01*
Y1022319D01*
X1302546D01*
Y1022519D01*
G37*
G36*
G01X1300056Y1018519D02*
X1299914Y1018119D01*
X1299164D01*
X1299021Y1018519D01*
Y1018719D01*
X1300056D01*
Y1018519D01*
G37*
G36*
G01X1300196Y1018919D02*
X1300338Y1019319D01*
X1301088D01*
X1301231Y1018919D01*
Y1018719D01*
X1300196D01*
Y1018919D01*
G37*
G36*
G01X1297846D02*
X1297988Y1019319D01*
X1298738D01*
X1298881Y1018919D01*
Y1018719D01*
X1297846D01*
Y1018919D01*
G37*
G36*
G01X1302406Y1020919D02*
X1302264Y1020519D01*
X1301514D01*
X1301371Y1020919D01*
Y1021119D01*
X1302406D01*
Y1020919D01*
G37*
G36*
G01X1300196Y1021319D02*
X1300338Y1021719D01*
X1301088D01*
X1301231Y1021319D01*
Y1021119D01*
X1300196D01*
Y1021319D01*
G37*
G36*
G01X1300056Y1020919D02*
X1299914Y1020519D01*
X1299164D01*
X1299021Y1020919D01*
Y1021119D01*
X1300056D01*
Y1020919D01*
G37*
G36*
G01X1297846Y1021319D02*
X1297988Y1021719D01*
X1298738D01*
X1298881Y1021319D01*
Y1021119D01*
X1297846D01*
Y1021319D01*
G37*
G36*
G01X1302406Y1019719D02*
X1302264Y1019319D01*
X1301514D01*
X1301371Y1019719D01*
Y1019919D01*
X1302406D01*
Y1019719D01*
G37*
G36*
G01X1300196Y1020119D02*
X1300338Y1020519D01*
X1301088D01*
X1301231Y1020119D01*
Y1019919D01*
X1300196D01*
Y1020119D01*
G37*
G36*
G01X1300056Y1019719D02*
X1299914Y1019319D01*
X1299164D01*
X1299021Y1019719D01*
Y1019919D01*
X1300056D01*
Y1019719D01*
G37*
G36*
G01X1297846Y1020119D02*
X1297988Y1020519D01*
X1298738D01*
X1298881Y1020119D01*
Y1019919D01*
X1297846D01*
Y1020119D01*
G37*
G36*
G01X1300638Y1041834D02*
X1300255Y1041652D01*
X1299724Y1042182D01*
X1299906Y1042566D01*
X1300048Y1042707D01*
X1300780Y1041975D01*
X1300638Y1041834D01*
G37*
G36*
G01X1299358Y1043679D02*
X1299742Y1043862D01*
X1300272Y1043331D01*
X1300090Y1042948D01*
X1299949Y1042806D01*
X1299217Y1043538D01*
X1299358Y1043679D01*
G37*
G36*
G01X1298977Y1043496D02*
X1298593Y1043314D01*
X1298063Y1043844D01*
X1298245Y1044228D01*
X1298386Y1044369D01*
X1299118Y1043637D01*
X1298977Y1043496D01*
G37*
G36*
G01X1300601Y1038474D02*
X1300218Y1038292D01*
X1299687Y1038822D01*
X1299870Y1039206D01*
X1300011Y1039347D01*
X1300743Y1038615D01*
X1300601Y1038474D01*
G37*
G36*
G01X1299322Y1040319D02*
X1299705Y1040501D01*
X1300235Y1039971D01*
X1300053Y1039587D01*
X1299912Y1039446D01*
X1299180Y1040178D01*
X1299322Y1040319D01*
G37*
G36*
G01X1298940Y1040135D02*
X1298556Y1039953D01*
X1298026Y1040484D01*
X1298208Y1040867D01*
X1298349Y1041009D01*
X1299081Y1040277D01*
X1298940Y1040135D01*
G37*
G36*
G01X1299789Y1040985D02*
X1299406Y1040803D01*
X1298875Y1041333D01*
X1299057Y1041717D01*
X1299199Y1041858D01*
X1299931Y1041126D01*
X1299789Y1040985D01*
G37*
G36*
G01X1300171Y1041169D02*
X1300555Y1041351D01*
X1301085Y1040821D01*
X1300903Y1040437D01*
X1300761Y1040296D01*
X1300030Y1041027D01*
X1300171Y1041169D01*
G37*
G36*
G01X1298509Y1042830D02*
X1298893Y1043013D01*
X1299423Y1042482D01*
X1299241Y1042099D01*
X1299100Y1041957D01*
X1298368Y1042689D01*
X1298509Y1042830D01*
G37*
G36*
G01X1298473Y1039470D02*
X1298856Y1039652D01*
X1299386Y1039122D01*
X1299204Y1038738D01*
X1299063Y1038597D01*
X1298331Y1039329D01*
X1298473Y1039470D01*
G37*
G36*
G01X1299752Y1037625D02*
X1299369Y1037443D01*
X1298838Y1037973D01*
X1299021Y1038357D01*
X1299162Y1038498D01*
X1299894Y1037766D01*
X1299752Y1037625D01*
G37*
G36*
G01X1303925Y1063079D02*
X1303541Y1062897D01*
X1303011Y1063427D01*
X1303193Y1063811D01*
X1303334Y1063952D01*
X1304066Y1063220D01*
X1303925Y1063079D01*
G37*
G36*
G01X1304306Y1063262D02*
X1304690Y1063445D01*
X1305220Y1062914D01*
X1305038Y1062531D01*
X1304897Y1062389D01*
X1304165Y1063121D01*
X1304306Y1063262D01*
G37*
G36*
G01X1301795Y1064074D02*
X1302178Y1064256D01*
X1302709Y1063726D01*
X1302527Y1063342D01*
X1302385Y1063201D01*
X1301653Y1063933D01*
X1301795Y1064074D01*
G37*
G36*
G01X1301771Y1055038D02*
X1301387Y1054856D01*
X1300857Y1055387D01*
X1301039Y1055770D01*
X1301180Y1055912D01*
X1301912Y1055180D01*
X1301771Y1055038D01*
G37*
G36*
G01X1300109Y1056700D02*
X1299725Y1056518D01*
X1299195Y1057048D01*
X1299377Y1057432D01*
X1299519Y1057573D01*
X1300250Y1056842D01*
X1300109Y1056700D01*
G37*
G36*
G01X1300491Y1056884D02*
X1300874Y1057066D01*
X1301405Y1056536D01*
X1301223Y1056152D01*
X1301081Y1056011D01*
X1300349Y1056743D01*
X1300491Y1056884D01*
G37*
G36*
G01X1298829Y1058546D02*
X1299213Y1058728D01*
X1299743Y1058197D01*
X1299561Y1057814D01*
X1299420Y1057672D01*
X1298688Y1058404D01*
X1298829Y1058546D01*
G37*
G36*
G01X1303432Y1053377D02*
X1303049Y1053195D01*
X1302518Y1053725D01*
X1302701Y1054109D01*
X1302842Y1054250D01*
X1303574Y1053518D01*
X1303432Y1053377D01*
G37*
G36*
G01X1302153Y1055222D02*
X1302536Y1055404D01*
X1303066Y1054874D01*
X1302884Y1054490D01*
X1302743Y1054349D01*
X1302011Y1055081D01*
X1302153Y1055222D01*
G37*
G36*
G01X1301733Y1051677D02*
X1301349Y1051495D01*
X1300819Y1052025D01*
X1301001Y1052409D01*
X1301142Y1052551D01*
X1301874Y1051819D01*
X1301733Y1051677D01*
G37*
G36*
G01X1300071Y1053339D02*
X1299688Y1053157D01*
X1299157Y1053687D01*
X1299339Y1054071D01*
X1299481Y1054212D01*
X1300213Y1053480D01*
X1300071Y1053339D01*
G37*
G36*
G01X1300453Y1053523D02*
X1300837Y1053705D01*
X1301367Y1053175D01*
X1301185Y1052791D01*
X1301043Y1052650D01*
X1300312Y1053381D01*
X1300453Y1053523D01*
G37*
G36*
G01X1298791Y1055184D02*
X1299175Y1055367D01*
X1299705Y1054836D01*
X1299523Y1054453D01*
X1299382Y1054311D01*
X1298650Y1055043D01*
X1298791Y1055184D01*
G37*
G36*
G01X1300922Y1054189D02*
X1300538Y1054007D01*
X1300008Y1054538D01*
X1300190Y1054921D01*
X1300331Y1055063D01*
X1301063Y1054331D01*
X1300922Y1054189D01*
G37*
G36*
G01X1299260Y1055851D02*
X1298876Y1055669D01*
X1298346Y1056199D01*
X1298528Y1056583D01*
X1298670Y1056724D01*
X1299401Y1055993D01*
X1299260Y1055851D01*
G37*
G36*
G01X1301304Y1054373D02*
X1301687Y1054555D01*
X1302217Y1054025D01*
X1302035Y1053641D01*
X1301894Y1053500D01*
X1301162Y1054232D01*
X1301304Y1054373D01*
G37*
G36*
G01X1299642Y1056035D02*
X1300025Y1056217D01*
X1300556Y1055687D01*
X1300374Y1055303D01*
X1300232Y1055162D01*
X1299500Y1055894D01*
X1299642Y1056035D01*
G37*
G36*
G01X1297980Y1057697D02*
X1298364Y1057879D01*
X1298894Y1057348D01*
X1298712Y1056965D01*
X1298571Y1056823D01*
X1297839Y1057555D01*
X1297980Y1057697D01*
G37*
G36*
G01X1302583Y1052528D02*
X1302200Y1052346D01*
X1301669Y1052876D01*
X1301852Y1053260D01*
X1301993Y1053401D01*
X1302725Y1052669D01*
X1302583Y1052528D01*
G37*
G36*
G01X1300883Y1050828D02*
X1300500Y1050646D01*
X1299969Y1051176D01*
X1300152Y1051560D01*
X1300293Y1051701D01*
X1301025Y1050969D01*
X1300883Y1050828D01*
G37*
G36*
G01X1297942Y1054335D02*
X1298325Y1054517D01*
X1298856Y1053987D01*
X1298674Y1053603D01*
X1298532Y1053462D01*
X1297800Y1054194D01*
X1297942Y1054335D01*
G37*
G36*
G01X1299222Y1052489D02*
X1298838Y1052307D01*
X1298308Y1052838D01*
X1298490Y1053221D01*
X1298631Y1053363D01*
X1299363Y1052631D01*
X1299222Y1052489D01*
G37*
G36*
G01X1299604Y1052673D02*
X1299987Y1052855D01*
X1300517Y1052325D01*
X1300335Y1051941D01*
X1300194Y1051800D01*
X1299462Y1052532D01*
X1299604Y1052673D01*
G37*
G36*
G01X1302088Y1076907D02*
X1301704Y1076725D01*
X1301174Y1077255D01*
X1301356Y1077639D01*
X1301497Y1077780D01*
X1302229Y1077049D01*
X1302088Y1076907D01*
G37*
G36*
G01X1300426Y1078569D02*
X1300042Y1078386D01*
X1299512Y1078917D01*
X1299694Y1079300D01*
X1299835Y1079442D01*
X1300567Y1078710D01*
X1300426Y1078569D01*
G37*
G36*
G01X1300808Y1078753D02*
X1301191Y1078935D01*
X1301722Y1078404D01*
X1301539Y1078021D01*
X1301398Y1077879D01*
X1300666Y1078611D01*
X1300808Y1078753D01*
G37*
G36*
G01X1302469Y1077091D02*
X1302853Y1077273D01*
X1303383Y1076743D01*
X1303201Y1076359D01*
X1303060Y1076218D01*
X1302328Y1076950D01*
X1302469Y1077091D01*
G37*
G36*
G01X1300768Y1075389D02*
X1301152Y1075572D01*
X1301682Y1075041D01*
X1301500Y1074658D01*
X1301359Y1074516D01*
X1300627Y1075248D01*
X1300768Y1075389D01*
G37*
G36*
G01X1300386Y1075206D02*
X1300003Y1075023D01*
X1299472Y1075554D01*
X1299654Y1075937D01*
X1299796Y1076079D01*
X1300528Y1075347D01*
X1300386Y1075206D01*
G37*
G36*
G01X1302048Y1073544D02*
X1301665Y1073362D01*
X1301134Y1073892D01*
X1301316Y1074276D01*
X1301458Y1074417D01*
X1302190Y1073685D01*
X1302048Y1073544D01*
G37*
G36*
G01X1299106Y1077051D02*
X1299490Y1077233D01*
X1300020Y1076703D01*
X1299838Y1076319D01*
X1299697Y1076178D01*
X1298965Y1076909D01*
X1299106Y1077051D01*
G37*
G36*
G01X1298724Y1076867D02*
X1298341Y1076685D01*
X1297811Y1077215D01*
X1297993Y1077599D01*
X1298134Y1077740D01*
X1298866Y1077008D01*
X1298724Y1076867D01*
G37*
G36*
G01X1302430Y1073728D02*
X1302814Y1073910D01*
X1303344Y1073380D01*
X1303162Y1072996D01*
X1303021Y1072855D01*
X1302289Y1073586D01*
X1302430Y1073728D01*
G37*
G36*
G01X1303710Y1071883D02*
X1303327Y1071700D01*
X1302796Y1072231D01*
X1302978Y1072614D01*
X1303120Y1072756D01*
X1303852Y1072024D01*
X1303710Y1071883D01*
G37*
G36*
G01X1301617Y1076239D02*
X1302001Y1076421D01*
X1302531Y1075891D01*
X1302349Y1075507D01*
X1302208Y1075366D01*
X1301476Y1076097D01*
X1301617Y1076239D01*
G37*
G36*
G01X1301236Y1076055D02*
X1300852Y1075873D01*
X1300322Y1076403D01*
X1300504Y1076787D01*
X1300645Y1076928D01*
X1301377Y1076196D01*
X1301236Y1076055D01*
G37*
G36*
G01X1298294Y1079562D02*
X1298677Y1079744D01*
X1299208Y1079214D01*
X1299026Y1078830D01*
X1298884Y1078689D01*
X1298152Y1079420D01*
X1298294Y1079562D01*
G37*
G36*
G01X1299956Y1077900D02*
X1300339Y1078082D01*
X1300870Y1077552D01*
X1300688Y1077169D01*
X1300546Y1077027D01*
X1299814Y1077759D01*
X1299956Y1077900D01*
G37*
G36*
G01X1299574Y1077716D02*
X1299190Y1077534D01*
X1298660Y1078065D01*
X1298842Y1078448D01*
X1298983Y1078590D01*
X1299715Y1077858D01*
X1299574Y1077716D01*
G37*
G36*
G01X1299919Y1074540D02*
X1300302Y1074722D01*
X1300833Y1074192D01*
X1300651Y1073808D01*
X1300509Y1073667D01*
X1299777Y1074398D01*
X1299919Y1074540D01*
G37*
G36*
G01X1301199Y1072694D02*
X1300815Y1072512D01*
X1300285Y1073042D01*
X1300467Y1073426D01*
X1300608Y1073568D01*
X1301340Y1072836D01*
X1301199Y1072694D01*
G37*
G36*
G01X1298257Y1076201D02*
X1298641Y1076383D01*
X1299171Y1075853D01*
X1298989Y1075470D01*
X1298847Y1075328D01*
X1298116Y1076060D01*
X1298257Y1076201D01*
G37*
G36*
G01X1299537Y1074356D02*
X1299153Y1074174D01*
X1298623Y1074704D01*
X1298805Y1075088D01*
X1298946Y1075229D01*
X1299678Y1074497D01*
X1299537Y1074356D01*
G37*
G36*
G01X1301581Y1072878D02*
X1301964Y1073060D01*
X1302495Y1072530D01*
X1302313Y1072146D01*
X1302171Y1072005D01*
X1301439Y1072737D01*
X1301581Y1072878D01*
G37*
G36*
G01X1302861Y1071033D02*
X1302477Y1070851D01*
X1301947Y1071381D01*
X1302129Y1071765D01*
X1302270Y1071906D01*
X1303002Y1071174D01*
X1302861Y1071033D01*
G37*
G36*
G01X1306004Y1064960D02*
X1306388Y1065143D01*
X1306918Y1064612D01*
X1306736Y1064229D01*
X1306595Y1064087D01*
X1305863Y1064819D01*
X1306004Y1064960D01*
G37*
G36*
G01X1305623Y1064777D02*
X1305239Y1064595D01*
X1304709Y1065125D01*
X1304891Y1065509D01*
X1305032Y1065650D01*
X1305764Y1064918D01*
X1305623Y1064777D01*
G37*
G36*
G01X1303961Y1066438D02*
X1303577Y1066256D01*
X1303047Y1066787D01*
X1303229Y1067170D01*
X1303370Y1067312D01*
X1304102Y1066580D01*
X1303961Y1066438D01*
G37*
G36*
G01X1304343Y1066622D02*
X1304726Y1066804D01*
X1305257Y1066274D01*
X1305075Y1065890D01*
X1304933Y1065749D01*
X1304201Y1066481D01*
X1304343Y1066622D01*
G37*
G36*
G01X1302299Y1068100D02*
X1301916Y1067918D01*
X1301385Y1068448D01*
X1301567Y1068832D01*
X1301709Y1068973D01*
X1302441Y1068241D01*
X1302299Y1068100D01*
G37*
G36*
G01X1298976Y1071423D02*
X1298592Y1071241D01*
X1298062Y1071772D01*
X1298244Y1072155D01*
X1298385Y1072297D01*
X1299117Y1071565D01*
X1298976Y1071423D01*
G37*
G36*
G01X1300637Y1069762D02*
X1300254Y1069580D01*
X1299723Y1070110D01*
X1299906Y1070494D01*
X1300047Y1070635D01*
X1300779Y1069903D01*
X1300637Y1069762D01*
G37*
G36*
G01X1301019Y1069946D02*
X1301403Y1070128D01*
X1301933Y1069597D01*
X1301751Y1069214D01*
X1301610Y1069072D01*
X1300878Y1069804D01*
X1301019Y1069946D01*
G37*
G36*
G01X1299358Y1071607D02*
X1299741Y1071789D01*
X1300271Y1071259D01*
X1300089Y1070875D01*
X1299948Y1070734D01*
X1299216Y1071466D01*
X1299358Y1071607D01*
G37*
G36*
G01X1302681Y1068284D02*
X1303065Y1068466D01*
X1303595Y1067936D01*
X1303413Y1067552D01*
X1303271Y1067411D01*
X1302540Y1068142D01*
X1302681Y1068284D01*
G37*
G36*
G01X1302263Y1064740D02*
X1301879Y1064558D01*
X1301349Y1065089D01*
X1301531Y1065472D01*
X1301672Y1065614D01*
X1302404Y1064882D01*
X1302263Y1064740D01*
G37*
G36*
G01X1300601Y1066402D02*
X1300218Y1066220D01*
X1299687Y1066750D01*
X1299869Y1067134D01*
X1300011Y1067275D01*
X1300743Y1066543D01*
X1300601Y1066402D01*
G37*
G36*
G01X1300983Y1066586D02*
X1301367Y1066768D01*
X1301897Y1066238D01*
X1301715Y1065854D01*
X1301573Y1065713D01*
X1300842Y1066444D01*
X1300983Y1066586D01*
G37*
G36*
G01X1302645Y1064924D02*
X1303028Y1065106D01*
X1303559Y1064576D01*
X1303377Y1064192D01*
X1303235Y1064051D01*
X1302503Y1064783D01*
X1302645Y1064924D01*
G37*
G36*
G01X1299321Y1068248D02*
X1299705Y1068430D01*
X1300235Y1067899D01*
X1300053Y1067516D01*
X1299912Y1067374D01*
X1299180Y1068106D01*
X1299321Y1068248D01*
G37*
G36*
G01X1298939Y1068064D02*
X1298556Y1067882D01*
X1298025Y1068412D01*
X1298208Y1068796D01*
X1298349Y1068937D01*
X1299081Y1068205D01*
X1298939Y1068064D01*
G37*
G36*
G01X1305155Y1064111D02*
X1305539Y1064294D01*
X1306069Y1063763D01*
X1305887Y1063380D01*
X1305746Y1063238D01*
X1305014Y1063970D01*
X1305155Y1064111D01*
G37*
G36*
G01X1304774Y1063928D02*
X1304390Y1063746D01*
X1303860Y1064276D01*
X1304042Y1064660D01*
X1304183Y1064801D01*
X1304915Y1064069D01*
X1304774Y1063928D01*
G37*
G36*
G01X1303112Y1065589D02*
X1302728Y1065407D01*
X1302198Y1065938D01*
X1302380Y1066321D01*
X1302521Y1066463D01*
X1303253Y1065731D01*
X1303112Y1065589D01*
G37*
G36*
G01X1303494Y1065773D02*
X1303877Y1065955D01*
X1304408Y1065425D01*
X1304226Y1065041D01*
X1304084Y1064900D01*
X1303352Y1065632D01*
X1303494Y1065773D01*
G37*
G36*
G01X1301832Y1067435D02*
X1302216Y1067617D01*
X1302746Y1067087D01*
X1302564Y1066703D01*
X1302422Y1066562D01*
X1301691Y1067293D01*
X1301832Y1067435D01*
G37*
G36*
G01X1300170Y1069097D02*
X1300554Y1069279D01*
X1301084Y1068748D01*
X1300902Y1068365D01*
X1300761Y1068223D01*
X1300029Y1068955D01*
X1300170Y1069097D01*
G37*
G36*
G01X1299788Y1068913D02*
X1299405Y1068731D01*
X1298874Y1069261D01*
X1299057Y1069645D01*
X1299198Y1069786D01*
X1299930Y1069054D01*
X1299788Y1068913D01*
G37*
G36*
G01X1298509Y1070758D02*
X1298892Y1070940D01*
X1299422Y1070410D01*
X1299240Y1070026D01*
X1299099Y1069885D01*
X1298367Y1070617D01*
X1298509Y1070758D01*
G37*
G36*
G01X1301450Y1067251D02*
X1301067Y1067069D01*
X1300536Y1067599D01*
X1300718Y1067983D01*
X1300860Y1068124D01*
X1301592Y1067392D01*
X1301450Y1067251D01*
G37*
G36*
G01X1299751Y1065552D02*
X1299368Y1065370D01*
X1298837Y1065900D01*
X1299019Y1066284D01*
X1299161Y1066425D01*
X1299893Y1065693D01*
X1299751Y1065552D01*
G37*
G36*
G01X1301413Y1063890D02*
X1301029Y1063708D01*
X1300499Y1064239D01*
X1300681Y1064622D01*
X1300822Y1064764D01*
X1301554Y1064032D01*
X1301413Y1063890D01*
G37*
G36*
G01X1300133Y1065736D02*
X1300517Y1065918D01*
X1301047Y1065388D01*
X1300865Y1065004D01*
X1300723Y1064863D01*
X1299992Y1065594D01*
X1300133Y1065736D01*
G37*
G36*
G01X1298471Y1067398D02*
X1298855Y1067580D01*
X1299385Y1067049D01*
X1299203Y1066666D01*
X1299062Y1066524D01*
X1298330Y1067256D01*
X1298471Y1067398D01*
G37*
G36*
G01X1300016Y1092579D02*
X1299632Y1092397D01*
X1299102Y1092928D01*
X1299284Y1093311D01*
X1299425Y1093453D01*
X1300157Y1092721D01*
X1300016Y1092579D01*
G37*
G36*
G01X1300398Y1092763D02*
X1300781Y1092945D01*
X1301312Y1092415D01*
X1301129Y1092031D01*
X1300988Y1091890D01*
X1300256Y1092622D01*
X1300398Y1092763D01*
G37*
G36*
G01X1301677Y1090918D02*
X1301294Y1090736D01*
X1300764Y1091266D01*
X1300946Y1091650D01*
X1301087Y1091791D01*
X1301819Y1091059D01*
X1301677Y1090918D01*
G37*
G36*
G01X1298025Y1096102D02*
X1298444Y1096166D01*
X1298798Y1095504D01*
X1298513Y1095190D01*
X1298337Y1095096D01*
X1297848Y1096008D01*
X1298025Y1096102D01*
G37*
G36*
G01X1307044Y1086116D02*
X1307428Y1086299D01*
X1307958Y1085768D01*
X1307776Y1085385D01*
X1307635Y1085243D01*
X1306903Y1085975D01*
X1307044Y1086116D01*
G37*
G36*
G01X1303721Y1089440D02*
X1304105Y1089622D01*
X1304635Y1089092D01*
X1304453Y1088708D01*
X1304311Y1088567D01*
X1303580Y1089298D01*
X1303721Y1089440D01*
G37*
G36*
G01X1306663Y1085933D02*
X1306279Y1085751D01*
X1305749Y1086281D01*
X1305931Y1086664D01*
X1306072Y1086806D01*
X1306804Y1086074D01*
X1306663Y1085933D01*
G37*
G36*
G01X1305383Y1087778D02*
X1305766Y1087960D01*
X1306297Y1087430D01*
X1306115Y1087046D01*
X1305973Y1086905D01*
X1305241Y1087637D01*
X1305383Y1087778D01*
G37*
G36*
G01X1305001Y1087594D02*
X1304617Y1087412D01*
X1304087Y1087943D01*
X1304269Y1088326D01*
X1304410Y1088468D01*
X1305142Y1087736D01*
X1305001Y1087594D01*
G37*
G36*
G01X1303339Y1089256D02*
X1302956Y1089074D01*
X1302425Y1089604D01*
X1302607Y1089988D01*
X1302749Y1090129D01*
X1303481Y1089397D01*
X1303339Y1089256D01*
G37*
G36*
G01X1302059Y1091102D02*
X1302443Y1091284D01*
X1302973Y1090753D01*
X1302791Y1090370D01*
X1302650Y1090228D01*
X1301918Y1090960D01*
X1302059Y1091102D01*
G37*
G36*
G01X1308324Y1084271D02*
X1307941Y1084089D01*
X1307410Y1084619D01*
X1307592Y1085003D01*
X1307734Y1085144D01*
X1308466Y1084412D01*
X1308324Y1084271D01*
G37*
G36*
G01X1300361Y1089403D02*
X1300744Y1089585D01*
X1301275Y1089055D01*
X1301093Y1088671D01*
X1300951Y1088530D01*
X1300219Y1089262D01*
X1300361Y1089403D01*
G37*
G36*
G01X1301641Y1087558D02*
X1301257Y1087375D01*
X1300727Y1087906D01*
X1300909Y1088289D01*
X1301050Y1088431D01*
X1301782Y1087699D01*
X1301641Y1087558D01*
G37*
G36*
G01X1298699Y1091065D02*
X1299083Y1091247D01*
X1299613Y1090717D01*
X1299431Y1090333D01*
X1299290Y1090191D01*
X1298558Y1090923D01*
X1298699Y1091065D01*
G37*
G36*
G01X1299979Y1089219D02*
X1299595Y1089037D01*
X1299065Y1089567D01*
X1299247Y1089951D01*
X1299389Y1090092D01*
X1300120Y1089361D01*
X1299979Y1089219D01*
G37*
G36*
G01X1304964Y1084234D02*
X1304580Y1084052D01*
X1304050Y1084582D01*
X1304232Y1084966D01*
X1304374Y1085107D01*
X1305105Y1084376D01*
X1304964Y1084234D01*
G37*
G36*
G01X1305346Y1084418D02*
X1305730Y1084600D01*
X1306260Y1084070D01*
X1306078Y1083686D01*
X1305936Y1083545D01*
X1305204Y1084277D01*
X1305346Y1084418D01*
G37*
G36*
G01X1306626Y1082572D02*
X1306242Y1082390D01*
X1305712Y1082921D01*
X1305894Y1083304D01*
X1306035Y1083446D01*
X1306767Y1082714D01*
X1306626Y1082572D01*
G37*
G36*
G01X1303684Y1086080D02*
X1304068Y1086262D01*
X1304598Y1085731D01*
X1304416Y1085348D01*
X1304275Y1085206D01*
X1303543Y1085938D01*
X1303684Y1086080D01*
G37*
G36*
G01X1303302Y1085896D02*
X1302919Y1085714D01*
X1302388Y1086244D01*
X1302571Y1086628D01*
X1302712Y1086769D01*
X1303444Y1086037D01*
X1303302Y1085896D01*
G37*
G36*
G01X1302022Y1087741D02*
X1302406Y1087923D01*
X1302936Y1087393D01*
X1302754Y1087009D01*
X1302613Y1086868D01*
X1301881Y1087600D01*
X1302022Y1087741D01*
G37*
G36*
G01X1302490Y1088407D02*
X1302106Y1088224D01*
X1301576Y1088755D01*
X1301758Y1089138D01*
X1301899Y1089280D01*
X1302631Y1088548D01*
X1302490Y1088407D01*
G37*
G36*
G01X1301210Y1090252D02*
X1301593Y1090434D01*
X1302124Y1089904D01*
X1301942Y1089520D01*
X1301800Y1089379D01*
X1301068Y1090111D01*
X1301210Y1090252D01*
G37*
G36*
G01X1300828Y1090068D02*
X1300444Y1089886D01*
X1299914Y1090416D01*
X1300096Y1090800D01*
X1300238Y1090941D01*
X1300969Y1090210D01*
X1300828Y1090068D01*
G37*
G36*
G01X1299548Y1091914D02*
X1299932Y1092096D01*
X1300462Y1091566D01*
X1300280Y1091182D01*
X1300139Y1091040D01*
X1299407Y1091772D01*
X1299548Y1091914D01*
G37*
G36*
G01X1299166Y1091730D02*
X1298783Y1091548D01*
X1298252Y1092078D01*
X1298434Y1092462D01*
X1298576Y1092603D01*
X1299308Y1091871D01*
X1299166Y1091730D01*
G37*
G36*
G01X1306195Y1085267D02*
X1306579Y1085449D01*
X1307109Y1084919D01*
X1306927Y1084535D01*
X1306785Y1084394D01*
X1306053Y1085126D01*
X1306195Y1085267D01*
G37*
G36*
G01X1307475Y1083421D02*
X1307091Y1083239D01*
X1306561Y1083770D01*
X1306743Y1084153D01*
X1306884Y1084295D01*
X1307616Y1083563D01*
X1307475Y1083421D01*
G37*
G36*
G01X1302871Y1088590D02*
X1303255Y1088772D01*
X1303785Y1088242D01*
X1303603Y1087858D01*
X1303462Y1087717D01*
X1302730Y1088449D01*
X1302871Y1088590D01*
G37*
G36*
G01X1305813Y1085083D02*
X1305429Y1084901D01*
X1304899Y1085431D01*
X1305081Y1085815D01*
X1305223Y1085956D01*
X1305954Y1085225D01*
X1305813Y1085083D01*
G37*
G36*
G01X1304533Y1086929D02*
X1304917Y1087111D01*
X1305447Y1086580D01*
X1305265Y1086197D01*
X1305124Y1086055D01*
X1304392Y1086787D01*
X1304533Y1086929D01*
G37*
G36*
G01X1304151Y1086745D02*
X1303768Y1086563D01*
X1303237Y1087093D01*
X1303420Y1087477D01*
X1303561Y1087618D01*
X1304293Y1086886D01*
X1304151Y1086745D01*
G37*
G36*
G01X1302447Y1085040D02*
X1302063Y1084858D01*
X1301533Y1085389D01*
X1301715Y1085772D01*
X1301856Y1085914D01*
X1302588Y1085182D01*
X1302447Y1085040D01*
G37*
G36*
G01X1301167Y1086886D02*
X1301551Y1087068D01*
X1302081Y1086538D01*
X1301899Y1086154D01*
X1301757Y1086013D01*
X1301026Y1086744D01*
X1301167Y1086886D01*
G37*
G36*
G01X1299505Y1088548D02*
X1299889Y1088730D01*
X1300419Y1088199D01*
X1300237Y1087816D01*
X1300096Y1087674D01*
X1299364Y1088406D01*
X1299505Y1088548D01*
G37*
G36*
G01X1299123Y1088364D02*
X1298740Y1088182D01*
X1298210Y1088712D01*
X1298392Y1089096D01*
X1298533Y1089237D01*
X1299265Y1088505D01*
X1299123Y1088364D01*
G37*
G36*
G01X1300785Y1086702D02*
X1300402Y1086520D01*
X1299871Y1087050D01*
X1300053Y1087434D01*
X1300195Y1087575D01*
X1300927Y1086843D01*
X1300785Y1086702D01*
G37*
G36*
G01X1304490Y1083562D02*
X1304874Y1083745D01*
X1305404Y1083214D01*
X1305222Y1082831D01*
X1305081Y1082689D01*
X1304349Y1083421D01*
X1304490Y1083562D01*
G37*
G36*
G01X1305770Y1081717D02*
X1305387Y1081535D01*
X1304856Y1082065D01*
X1305038Y1082449D01*
X1305180Y1082590D01*
X1305912Y1081858D01*
X1305770Y1081717D01*
G37*
G36*
G01X1304109Y1083379D02*
X1303725Y1083197D01*
X1303195Y1083727D01*
X1303377Y1084110D01*
X1303518Y1084252D01*
X1304250Y1083520D01*
X1304109Y1083379D01*
G37*
G36*
G01X1302829Y1085224D02*
X1303212Y1085406D01*
X1303743Y1084876D01*
X1303561Y1084492D01*
X1303419Y1084351D01*
X1302687Y1085083D01*
X1302829Y1085224D01*
G37*
G36*
G01X1298764Y1080230D02*
X1298380Y1080048D01*
X1297850Y1080578D01*
X1298032Y1080962D01*
X1298173Y1081103D01*
X1298905Y1080372D01*
X1298764Y1080230D01*
G37*
G36*
G01X1299146Y1080414D02*
X1299529Y1080596D01*
X1300060Y1080066D01*
X1299878Y1079682D01*
X1299736Y1079541D01*
X1299004Y1080273D01*
X1299146Y1080414D01*
G37*
G36*
G01X1310963Y1109640D02*
X1311383Y1109579D01*
X1311530Y1108844D01*
X1311166Y1108625D01*
X1310970Y1108586D01*
X1310767Y1109601D01*
X1310963Y1109640D01*
G37*
G36*
G01X1310500Y1111944D02*
X1310920Y1111883D01*
X1311068Y1111148D01*
X1310704Y1110929D01*
X1310507Y1110890D01*
X1310304Y1111905D01*
X1310500Y1111944D01*
G37*
G36*
G01X1310543Y1109699D02*
X1310122Y1109760D01*
X1309975Y1110495D01*
X1310339Y1110714D01*
X1310535Y1110753D01*
X1310739Y1109738D01*
X1310543Y1109699D01*
G37*
G36*
G01X1308111Y1111466D02*
X1308531Y1111405D01*
X1308678Y1110669D01*
X1308314Y1110451D01*
X1308118Y1110412D01*
X1307915Y1111427D01*
X1308111Y1111466D01*
G37*
G36*
G01X1308152Y1109221D02*
X1307732Y1109282D01*
X1307585Y1110017D01*
X1307949Y1110235D01*
X1308145Y1110275D01*
X1308348Y1109260D01*
X1308152Y1109221D01*
G37*
G36*
G01X1308572Y1109162D02*
X1308992Y1109100D01*
X1309139Y1108365D01*
X1308775Y1108147D01*
X1308578Y1108108D01*
X1308376Y1109122D01*
X1308572Y1109162D01*
G37*
G36*
G01X1309339Y1109458D02*
X1308919Y1109519D01*
X1308772Y1110255D01*
X1309136Y1110473D01*
X1309332Y1110512D01*
X1309535Y1109497D01*
X1309339Y1109458D01*
G37*
G36*
G01X1309759Y1109399D02*
X1310179Y1109338D01*
X1310327Y1108603D01*
X1309963Y1108385D01*
X1309766Y1108345D01*
X1309563Y1109360D01*
X1309759Y1109399D01*
G37*
G36*
G01X1309297Y1111704D02*
X1309717Y1111643D01*
X1309865Y1110907D01*
X1309501Y1110689D01*
X1309305Y1110649D01*
X1309101Y1111664D01*
X1309297Y1111704D01*
G37*
G36*
G01X1307393Y1108926D02*
X1307814Y1108865D01*
X1307961Y1108129D01*
X1307596Y1107911D01*
X1307400Y1107872D01*
X1307197Y1108887D01*
X1307393Y1108926D01*
G37*
G36*
G01X1306932Y1111230D02*
X1307353Y1111169D01*
X1307500Y1110434D01*
X1307135Y1110215D01*
X1306939Y1110176D01*
X1306736Y1111191D01*
X1306932Y1111230D01*
G37*
G36*
G01X1306974Y1108985D02*
X1306554Y1109046D01*
X1306406Y1109781D01*
X1306771Y1110000D01*
X1306967Y1110039D01*
X1307170Y1109024D01*
X1306974Y1108985D01*
G37*
G36*
G01X1301096Y1106759D02*
X1300676Y1106820D01*
X1300528Y1107555D01*
X1300893Y1107773D01*
X1301089Y1107813D01*
X1301292Y1106798D01*
X1301096Y1106759D01*
G37*
G36*
G01X1301054Y1109004D02*
X1301474Y1108943D01*
X1301622Y1108208D01*
X1301257Y1107989D01*
X1301061Y1107950D01*
X1300858Y1108965D01*
X1301054Y1109004D01*
G37*
G36*
G01X1300634Y1109063D02*
X1300214Y1109124D01*
X1300067Y1109859D01*
X1300431Y1110078D01*
X1300627Y1110117D01*
X1300831Y1109102D01*
X1300634Y1109063D01*
G37*
G36*
G01X1302018Y1102150D02*
X1301598Y1102211D01*
X1301451Y1102947D01*
X1301815Y1103165D01*
X1302011Y1103204D01*
X1302214Y1102189D01*
X1302018Y1102150D01*
G37*
G36*
G01X1301515Y1106700D02*
X1301936Y1106639D01*
X1302083Y1105903D01*
X1301719Y1105685D01*
X1301522Y1105646D01*
X1301319Y1106661D01*
X1301515Y1106700D01*
G37*
G36*
G01X1301557Y1104454D02*
X1301137Y1104515D01*
X1300990Y1105251D01*
X1301354Y1105469D01*
X1301550Y1105508D01*
X1301753Y1104494D01*
X1301557Y1104454D01*
G37*
G36*
G01X1301977Y1104396D02*
X1302397Y1104334D01*
X1302544Y1103599D01*
X1302180Y1103381D01*
X1301984Y1103341D01*
X1301781Y1104356D01*
X1301977Y1104396D01*
G37*
G36*
G01X1300124Y1099375D02*
X1299704Y1099437D01*
X1299557Y1100172D01*
X1299921Y1100390D01*
X1300117Y1100429D01*
X1300320Y1099414D01*
X1300124Y1099375D01*
G37*
G36*
G01X1300544Y1099317D02*
X1300964Y1099255D01*
X1301111Y1098520D01*
X1300747Y1098302D01*
X1300551Y1098262D01*
X1300348Y1099277D01*
X1300544Y1099317D01*
G37*
G36*
G01X1300083Y1101621D02*
X1300503Y1101560D01*
X1300650Y1100824D01*
X1300286Y1100606D01*
X1300090Y1100567D01*
X1299886Y1101582D01*
X1300083Y1101621D01*
G37*
G36*
G01X1298698Y1108534D02*
X1299118Y1108472D01*
X1299266Y1107737D01*
X1298901Y1107519D01*
X1298705Y1107479D01*
X1298502Y1108494D01*
X1298698Y1108534D01*
G37*
G36*
G01X1298278Y1108592D02*
X1297858Y1108654D01*
X1297711Y1109389D01*
X1298076Y1109607D01*
X1298272Y1109646D01*
X1298474Y1108631D01*
X1298278Y1108592D01*
G37*
G36*
G01X1299663Y1101680D02*
X1299242Y1101741D01*
X1299096Y1102476D01*
X1299460Y1102695D01*
X1299656Y1102734D01*
X1299859Y1101719D01*
X1299663Y1101680D01*
G37*
G36*
G01X1298740Y1106288D02*
X1298320Y1106349D01*
X1298173Y1107085D01*
X1298537Y1107303D01*
X1298733Y1107342D01*
X1298936Y1106327D01*
X1298740Y1106288D01*
G37*
G36*
G01X1299160Y1106229D02*
X1299580Y1106168D01*
X1299727Y1105433D01*
X1299363Y1105214D01*
X1299167Y1105175D01*
X1298964Y1106190D01*
X1299160Y1106229D01*
G37*
G36*
G01X1299201Y1103984D02*
X1298781Y1104045D01*
X1298634Y1104781D01*
X1298998Y1104999D01*
X1299195Y1105038D01*
X1299397Y1104023D01*
X1299201Y1103984D01*
G37*
G36*
G01X1299621Y1103925D02*
X1300041Y1103864D01*
X1300189Y1103128D01*
X1299824Y1102910D01*
X1299628Y1102871D01*
X1299425Y1103886D01*
X1299621Y1103925D01*
G37*
G36*
G01X1301260Y1101856D02*
X1301680Y1101795D01*
X1301828Y1101059D01*
X1301463Y1100841D01*
X1301267Y1100802D01*
X1301064Y1101817D01*
X1301260Y1101856D01*
G37*
G36*
G01X1301302Y1099611D02*
X1300882Y1099672D01*
X1300734Y1100407D01*
X1301099Y1100625D01*
X1301295Y1100665D01*
X1301498Y1099650D01*
X1301302Y1099611D01*
G37*
G36*
G01X1299918Y1106523D02*
X1299497Y1106584D01*
X1299350Y1107320D01*
X1299714Y1107538D01*
X1299910Y1107577D01*
X1300114Y1106563D01*
X1299918Y1106523D01*
G37*
G36*
G01X1299876Y1108769D02*
X1300296Y1108708D01*
X1300443Y1107972D01*
X1300079Y1107754D01*
X1299883Y1107715D01*
X1299680Y1108729D01*
X1299876Y1108769D01*
G37*
G36*
G01X1299456Y1108827D02*
X1299036Y1108889D01*
X1298889Y1109624D01*
X1299253Y1109842D01*
X1299449Y1109882D01*
X1299652Y1108867D01*
X1299456Y1108827D01*
G37*
G36*
G01X1300337Y1106465D02*
X1300757Y1106403D01*
X1300905Y1105668D01*
X1300541Y1105450D01*
X1300344Y1105410D01*
X1300141Y1106425D01*
X1300337Y1106465D01*
G37*
G36*
G01X1300379Y1104219D02*
X1299959Y1104280D01*
X1299812Y1105016D01*
X1300176Y1105234D01*
X1300372Y1105273D01*
X1300575Y1104258D01*
X1300379Y1104219D01*
G37*
G36*
G01X1300840Y1101915D02*
X1300420Y1101976D01*
X1300273Y1102711D01*
X1300637Y1102930D01*
X1300833Y1102969D01*
X1301037Y1101954D01*
X1300840Y1101915D01*
G37*
G36*
G01X1300799Y1104160D02*
X1301219Y1104099D01*
X1301366Y1103364D01*
X1301002Y1103145D01*
X1300806Y1103106D01*
X1300603Y1104121D01*
X1300799Y1104160D01*
G37*
G36*
G01X1298942Y1099139D02*
X1298521Y1099200D01*
X1298374Y1099936D01*
X1298739Y1100154D01*
X1298935Y1100193D01*
X1299138Y1099178D01*
X1298942Y1099139D01*
G37*
G36*
G01X1298901Y1101385D02*
X1299321Y1101323D01*
X1299468Y1100588D01*
X1299104Y1100370D01*
X1298908Y1100331D01*
X1298705Y1101345D01*
X1298901Y1101385D01*
G37*
G36*
G01X1299361Y1099080D02*
X1299781Y1099019D01*
X1299928Y1098283D01*
X1299564Y1098065D01*
X1299368Y1098026D01*
X1299165Y1099041D01*
X1299361Y1099080D01*
G37*
G36*
G01X1298481Y1101444D02*
X1298061Y1101505D01*
X1297914Y1102240D01*
X1298279Y1102459D01*
X1298475Y1102498D01*
X1298677Y1101483D01*
X1298481Y1101444D01*
G37*
G36*
G01X1297980Y1105994D02*
X1298400Y1105932D01*
X1298547Y1105197D01*
X1298183Y1104979D01*
X1297987Y1104939D01*
X1297784Y1105954D01*
X1297980Y1105994D01*
G37*
G36*
G01X1298441Y1103689D02*
X1298861Y1103628D01*
X1299008Y1102892D01*
X1298643Y1102674D01*
X1298447Y1102635D01*
X1298244Y1103650D01*
X1298441Y1103689D01*
G37*
G36*
G01X1309970Y1113440D02*
X1309570Y1113583D01*
Y1114333D01*
X1309970Y1114475D01*
X1310170D01*
Y1113440D01*
X1309970D01*
G37*
G36*
G01Y1115790D02*
X1309570Y1115933D01*
Y1116683D01*
X1309970Y1116825D01*
X1310170D01*
Y1115790D01*
X1309970D01*
G37*
G36*
G01X1310370Y1115650D02*
X1310770Y1115508D01*
Y1114758D01*
X1310370Y1114615D01*
X1310170D01*
Y1115650D01*
X1310370D01*
G37*
G36*
G01Y1118000D02*
X1310770Y1117858D01*
Y1117108D01*
X1310370Y1116965D01*
X1310170D01*
Y1118000D01*
X1310370D01*
G37*
G36*
G01X1309970Y1118140D02*
X1309570Y1118283D01*
Y1119033D01*
X1309970Y1119175D01*
X1310170D01*
Y1118140D01*
X1309970D01*
G37*
G36*
G01Y1120490D02*
X1309570Y1120633D01*
Y1121383D01*
X1309970Y1121525D01*
X1310170D01*
Y1120490D01*
X1309970D01*
G37*
G36*
G01Y1122840D02*
X1309570Y1122983D01*
Y1123733D01*
X1309970Y1123875D01*
X1310170D01*
Y1122840D01*
X1309970D01*
G37*
G36*
G01X1310370Y1120350D02*
X1310770Y1120208D01*
Y1119458D01*
X1310370Y1119315D01*
X1310170D01*
Y1120350D01*
X1310370D01*
G37*
G36*
G01Y1122700D02*
X1310770Y1122558D01*
Y1121808D01*
X1310370Y1121665D01*
X1310170D01*
Y1122700D01*
X1310370D01*
G37*
G36*
G01Y1125050D02*
X1310770Y1124908D01*
Y1124158D01*
X1310370Y1124015D01*
X1310170D01*
Y1125050D01*
X1310370D01*
G37*
G36*
G01Y1127400D02*
X1310770Y1127258D01*
Y1126508D01*
X1310370Y1126365D01*
X1310170D01*
Y1127400D01*
X1310370D01*
G37*
G36*
G01X1309970Y1125190D02*
X1309570Y1125333D01*
Y1126083D01*
X1309970Y1126225D01*
X1310170D01*
Y1125190D01*
X1309970D01*
G37*
G36*
G01Y1127540D02*
X1309570Y1127683D01*
Y1128433D01*
X1309970Y1128575D01*
X1310170D01*
Y1127540D01*
X1309970D01*
G37*
G36*
G01X1307570Y1113440D02*
X1307170Y1113583D01*
Y1114333D01*
X1307570Y1114475D01*
X1307770D01*
Y1113440D01*
X1307570D01*
G37*
G36*
G01Y1115790D02*
X1307170Y1115933D01*
Y1116683D01*
X1307570Y1116825D01*
X1307770D01*
Y1115790D01*
X1307570D01*
G37*
G36*
G01Y1118140D02*
X1307170Y1118283D01*
Y1119033D01*
X1307570Y1119175D01*
X1307770D01*
Y1118140D01*
X1307570D01*
G37*
G36*
G01Y1120490D02*
X1307170Y1120633D01*
Y1121383D01*
X1307570Y1121525D01*
X1307770D01*
Y1120490D01*
X1307570D01*
G37*
G36*
G01Y1122840D02*
X1307170Y1122983D01*
Y1123733D01*
X1307570Y1123875D01*
X1307770D01*
Y1122840D01*
X1307570D01*
G37*
G36*
G01Y1125190D02*
X1307170Y1125333D01*
Y1126083D01*
X1307570Y1126225D01*
X1307770D01*
Y1125190D01*
X1307570D01*
G37*
G36*
G01Y1127540D02*
X1307170Y1127683D01*
Y1128433D01*
X1307570Y1128575D01*
X1307770D01*
Y1127540D01*
X1307570D01*
G37*
G36*
G01X1307970Y1115650D02*
X1308370Y1115508D01*
Y1114758D01*
X1307970Y1114615D01*
X1307770D01*
Y1115650D01*
X1307970D01*
G37*
G36*
G01Y1118000D02*
X1308370Y1117858D01*
Y1117108D01*
X1307970Y1116965D01*
X1307770D01*
Y1118000D01*
X1307970D01*
G37*
G36*
G01Y1120350D02*
X1308370Y1120208D01*
Y1119458D01*
X1307970Y1119315D01*
X1307770D01*
Y1120350D01*
X1307970D01*
G37*
G36*
G01Y1122700D02*
X1308370Y1122558D01*
Y1121808D01*
X1307970Y1121665D01*
X1307770D01*
Y1122700D01*
X1307970D01*
G37*
G36*
G01Y1125050D02*
X1308370Y1124908D01*
Y1124158D01*
X1307970Y1124015D01*
X1307770D01*
Y1125050D01*
X1307970D01*
G37*
G36*
G01Y1127400D02*
X1308370Y1127258D01*
Y1126508D01*
X1307970Y1126365D01*
X1307770D01*
Y1127400D01*
X1307970D01*
G37*
G36*
G01X1309170Y1118000D02*
X1309570Y1117858D01*
Y1117108D01*
X1309170Y1116965D01*
X1308970D01*
Y1118000D01*
X1309170D01*
G37*
G36*
G01X1308770Y1113440D02*
X1308370Y1113583D01*
Y1114333D01*
X1308770Y1114475D01*
X1308970D01*
Y1113440D01*
X1308770D01*
G37*
G36*
G01Y1115790D02*
X1308370Y1115933D01*
Y1116683D01*
X1308770Y1116825D01*
X1308970D01*
Y1115790D01*
X1308770D01*
G37*
G36*
G01X1309170Y1115650D02*
X1309570Y1115508D01*
Y1114758D01*
X1309170Y1114615D01*
X1308970D01*
Y1115650D01*
X1309170D01*
G37*
G36*
G01X1308770Y1125190D02*
X1308370Y1125333D01*
Y1126083D01*
X1308770Y1126225D01*
X1308970D01*
Y1125190D01*
X1308770D01*
G37*
G36*
G01Y1118140D02*
X1308370Y1118283D01*
Y1119033D01*
X1308770Y1119175D01*
X1308970D01*
Y1118140D01*
X1308770D01*
G37*
G36*
G01X1309170Y1120350D02*
X1309570Y1120208D01*
Y1119458D01*
X1309170Y1119315D01*
X1308970D01*
Y1120350D01*
X1309170D01*
G37*
G36*
G01Y1122700D02*
X1309570Y1122558D01*
Y1121808D01*
X1309170Y1121665D01*
X1308970D01*
Y1122700D01*
X1309170D01*
G37*
G36*
G01Y1125050D02*
X1309570Y1124908D01*
Y1124158D01*
X1309170Y1124015D01*
X1308970D01*
Y1125050D01*
X1309170D01*
G37*
G36*
G01X1308770Y1120490D02*
X1308370Y1120633D01*
Y1121383D01*
X1308770Y1121525D01*
X1308970D01*
Y1120490D01*
X1308770D01*
G37*
G36*
G01Y1122840D02*
X1308370Y1122983D01*
Y1123733D01*
X1308770Y1123875D01*
X1308970D01*
Y1122840D01*
X1308770D01*
G37*
G36*
G01X1309170Y1127400D02*
X1309570Y1127258D01*
Y1126508D01*
X1309170Y1126365D01*
X1308970D01*
Y1127400D01*
X1309170D01*
G37*
G36*
G01X1308770Y1127540D02*
X1308370Y1127683D01*
Y1128433D01*
X1308770Y1128575D01*
X1308970D01*
Y1127540D01*
X1308770D01*
G37*
G36*
G01X1306370Y1115790D02*
X1305970Y1115933D01*
Y1116683D01*
X1306370Y1116825D01*
X1306570D01*
Y1115790D01*
X1306370D01*
G37*
G36*
G01Y1113440D02*
X1305970Y1113583D01*
Y1114333D01*
X1306370Y1114475D01*
X1306570D01*
Y1113440D01*
X1306370D01*
G37*
G36*
G01X1306770Y1118000D02*
X1307170Y1117858D01*
Y1117108D01*
X1306770Y1116965D01*
X1306570D01*
Y1118000D01*
X1306770D01*
G37*
G36*
G01Y1115650D02*
X1307170Y1115508D01*
Y1114758D01*
X1306770Y1114615D01*
X1306570D01*
Y1115650D01*
X1306770D01*
G37*
G36*
G01Y1127400D02*
X1307170Y1127258D01*
Y1126508D01*
X1306770Y1126365D01*
X1306570D01*
Y1127400D01*
X1306770D01*
G37*
G36*
G01X1306370Y1122840D02*
X1305970Y1122983D01*
Y1123733D01*
X1306370Y1123875D01*
X1306570D01*
Y1122840D01*
X1306370D01*
G37*
G36*
G01Y1120490D02*
X1305970Y1120633D01*
Y1121383D01*
X1306370Y1121525D01*
X1306570D01*
Y1120490D01*
X1306370D01*
G37*
G36*
G01X1306770Y1125050D02*
X1307170Y1124908D01*
Y1124158D01*
X1306770Y1124015D01*
X1306570D01*
Y1125050D01*
X1306770D01*
G37*
G36*
G01Y1122700D02*
X1307170Y1122558D01*
Y1121808D01*
X1306770Y1121665D01*
X1306570D01*
Y1122700D01*
X1306770D01*
G37*
G36*
G01Y1120350D02*
X1307170Y1120208D01*
Y1119458D01*
X1306770Y1119315D01*
X1306570D01*
Y1120350D01*
X1306770D01*
G37*
G36*
G01X1306370Y1118140D02*
X1305970Y1118283D01*
Y1119033D01*
X1306370Y1119175D01*
X1306570D01*
Y1118140D01*
X1306370D01*
G37*
G36*
G01Y1125190D02*
X1305970Y1125333D01*
Y1126083D01*
X1306370Y1126225D01*
X1306570D01*
Y1125190D01*
X1306370D01*
G37*
G36*
G01Y1127540D02*
X1305970Y1127683D01*
Y1128433D01*
X1306370Y1128575D01*
X1306570D01*
Y1127540D01*
X1306370D01*
G37*
G36*
G01X1300370Y1113525D02*
X1299970Y1113668D01*
Y1114418D01*
X1300370Y1114560D01*
X1300570D01*
Y1113525D01*
X1300370D01*
G37*
G36*
G01Y1115875D02*
X1299970Y1116018D01*
Y1116768D01*
X1300370Y1116910D01*
X1300570D01*
Y1115875D01*
X1300370D01*
G37*
G36*
G01X1300770Y1113385D02*
X1301170Y1113243D01*
Y1112493D01*
X1300770Y1112350D01*
X1300570D01*
Y1113385D01*
X1300770D01*
G37*
G36*
G01Y1115735D02*
X1301170Y1115593D01*
Y1114843D01*
X1300770Y1114700D01*
X1300570D01*
Y1115735D01*
X1300770D01*
G37*
G36*
G01Y1118085D02*
X1301170Y1117943D01*
Y1117193D01*
X1300770Y1117050D01*
X1300570D01*
Y1118085D01*
X1300770D01*
G37*
G36*
G01X1300370Y1118225D02*
X1299970Y1118368D01*
Y1119118D01*
X1300370Y1119260D01*
X1300570D01*
Y1118225D01*
X1300370D01*
G37*
G36*
G01Y1120575D02*
X1299970Y1120718D01*
Y1121468D01*
X1300370Y1121610D01*
X1300570D01*
Y1120575D01*
X1300370D01*
G37*
G36*
G01Y1122925D02*
X1299970Y1123068D01*
Y1123818D01*
X1300370Y1123960D01*
X1300570D01*
Y1122925D01*
X1300370D01*
G37*
G36*
G01X1300770Y1120435D02*
X1301170Y1120293D01*
Y1119543D01*
X1300770Y1119400D01*
X1300570D01*
Y1120435D01*
X1300770D01*
G37*
G36*
G01Y1122785D02*
X1301170Y1122643D01*
Y1121893D01*
X1300770Y1121750D01*
X1300570D01*
Y1122785D01*
X1300770D01*
G37*
G36*
G01Y1125135D02*
X1301170Y1124993D01*
Y1124243D01*
X1300770Y1124100D01*
X1300570D01*
Y1125135D01*
X1300770D01*
G37*
G36*
G01Y1127485D02*
X1301170Y1127343D01*
Y1126593D01*
X1300770Y1126450D01*
X1300570D01*
Y1127485D01*
X1300770D01*
G37*
G36*
G01X1300370Y1125275D02*
X1299970Y1125418D01*
Y1126168D01*
X1300370Y1126310D01*
X1300570D01*
Y1125275D01*
X1300370D01*
G37*
G36*
G01Y1127625D02*
X1299970Y1127768D01*
Y1128518D01*
X1300370Y1128660D01*
X1300570D01*
Y1127625D01*
X1300370D01*
G37*
G36*
G01X1298370Y1113385D02*
X1298770Y1113243D01*
Y1112493D01*
X1298370Y1112350D01*
X1298170D01*
Y1113385D01*
X1298370D01*
G37*
G36*
G01Y1115735D02*
X1298770Y1115593D01*
Y1114843D01*
X1298370Y1114700D01*
X1298170D01*
Y1115735D01*
X1298370D01*
G37*
G36*
G01Y1118085D02*
X1298770Y1117943D01*
Y1117193D01*
X1298370Y1117050D01*
X1298170D01*
Y1118085D01*
X1298370D01*
G37*
G36*
G01Y1125135D02*
X1298770Y1124993D01*
Y1124243D01*
X1298370Y1124100D01*
X1298170D01*
Y1125135D01*
X1298370D01*
G37*
G36*
G01Y1127485D02*
X1298770Y1127343D01*
Y1126593D01*
X1298370Y1126450D01*
X1298170D01*
Y1127485D01*
X1298370D01*
G37*
G36*
G01Y1120435D02*
X1298770Y1120293D01*
Y1119543D01*
X1298370Y1119400D01*
X1298170D01*
Y1120435D01*
X1298370D01*
G37*
G36*
G01Y1122785D02*
X1298770Y1122643D01*
Y1121893D01*
X1298370Y1121750D01*
X1298170D01*
Y1122785D01*
X1298370D01*
G37*
G36*
G01X1299170Y1113525D02*
X1298770Y1113668D01*
Y1114418D01*
X1299170Y1114560D01*
X1299370D01*
Y1113525D01*
X1299170D01*
G37*
G36*
G01Y1115875D02*
X1298770Y1116018D01*
Y1116768D01*
X1299170Y1116910D01*
X1299370D01*
Y1115875D01*
X1299170D01*
G37*
G36*
G01X1299570Y1113385D02*
X1299970Y1113243D01*
Y1112493D01*
X1299570Y1112350D01*
X1299370D01*
Y1113385D01*
X1299570D01*
G37*
G36*
G01Y1115735D02*
X1299970Y1115593D01*
Y1114843D01*
X1299570Y1114700D01*
X1299370D01*
Y1115735D01*
X1299570D01*
G37*
G36*
G01Y1118085D02*
X1299970Y1117943D01*
Y1117193D01*
X1299570Y1117050D01*
X1299370D01*
Y1118085D01*
X1299570D01*
G37*
G36*
G01X1299170Y1118225D02*
X1298770Y1118368D01*
Y1119118D01*
X1299170Y1119260D01*
X1299370D01*
Y1118225D01*
X1299170D01*
G37*
G36*
G01Y1120575D02*
X1298770Y1120718D01*
Y1121468D01*
X1299170Y1121610D01*
X1299370D01*
Y1120575D01*
X1299170D01*
G37*
G36*
G01Y1122925D02*
X1298770Y1123068D01*
Y1123818D01*
X1299170Y1123960D01*
X1299370D01*
Y1122925D01*
X1299170D01*
G37*
G36*
G01X1299570Y1120435D02*
X1299970Y1120293D01*
Y1119543D01*
X1299570Y1119400D01*
X1299370D01*
Y1120435D01*
X1299570D01*
G37*
G36*
G01Y1122785D02*
X1299970Y1122643D01*
Y1121893D01*
X1299570Y1121750D01*
X1299370D01*
Y1122785D01*
X1299570D01*
G37*
G36*
G01Y1125135D02*
X1299970Y1124993D01*
Y1124243D01*
X1299570Y1124100D01*
X1299370D01*
Y1125135D01*
X1299570D01*
G37*
G36*
G01Y1127485D02*
X1299970Y1127343D01*
Y1126593D01*
X1299570Y1126450D01*
X1299370D01*
Y1127485D01*
X1299570D01*
G37*
G36*
G01X1299170Y1125275D02*
X1298770Y1125418D01*
Y1126168D01*
X1299170Y1126310D01*
X1299370D01*
Y1125275D01*
X1299170D01*
G37*
G36*
G01Y1127625D02*
X1298770Y1127768D01*
Y1128518D01*
X1299170Y1128660D01*
X1299370D01*
Y1127625D01*
X1299170D01*
G37*
G36*
G01X1309970Y1134590D02*
X1309570Y1134733D01*
Y1135483D01*
X1309970Y1135625D01*
X1310170D01*
Y1134590D01*
X1309970D01*
G37*
G36*
G01Y1129890D02*
X1309570Y1130033D01*
Y1130783D01*
X1309970Y1130925D01*
X1310170D01*
Y1129890D01*
X1309970D01*
G37*
G36*
G01Y1132240D02*
X1309570Y1132383D01*
Y1133133D01*
X1309970Y1133275D01*
X1310170D01*
Y1132240D01*
X1309970D01*
G37*
G36*
G01X1310370Y1129750D02*
X1310770Y1129608D01*
Y1128858D01*
X1310370Y1128715D01*
X1310170D01*
Y1129750D01*
X1310370D01*
G37*
G36*
G01Y1134450D02*
X1310770Y1134308D01*
Y1133558D01*
X1310370Y1133415D01*
X1310170D01*
Y1134450D01*
X1310370D01*
G37*
G36*
G01Y1132100D02*
X1310770Y1131958D01*
Y1131208D01*
X1310370Y1131065D01*
X1310170D01*
Y1132100D01*
X1310370D01*
G37*
G36*
G01Y1136800D02*
X1310770Y1136658D01*
Y1135908D01*
X1310370Y1135765D01*
X1310170D01*
Y1136800D01*
X1310370D01*
G37*
G36*
G01X1309970Y1143990D02*
X1309570Y1144133D01*
Y1144883D01*
X1309970Y1145025D01*
X1310170D01*
Y1143990D01*
X1309970D01*
G37*
G36*
G01X1310370Y1143850D02*
X1310770Y1143708D01*
Y1142958D01*
X1310370Y1142815D01*
X1310170D01*
Y1143850D01*
X1310370D01*
G37*
G36*
G01X1309970Y1141640D02*
X1309570Y1141783D01*
Y1142533D01*
X1309970Y1142675D01*
X1310170D01*
Y1141640D01*
X1309970D01*
G37*
G36*
G01X1310370Y1141500D02*
X1310770Y1141358D01*
Y1140608D01*
X1310370Y1140465D01*
X1310170D01*
Y1141500D01*
X1310370D01*
G37*
G36*
G01X1309970Y1136940D02*
X1309570Y1137083D01*
Y1137833D01*
X1309970Y1137975D01*
X1310170D01*
Y1136940D01*
X1309970D01*
G37*
G36*
G01Y1139290D02*
X1309570Y1139433D01*
Y1140183D01*
X1309970Y1140325D01*
X1310170D01*
Y1139290D01*
X1309970D01*
G37*
G36*
G01X1310370Y1139150D02*
X1310770Y1139008D01*
Y1138258D01*
X1310370Y1138115D01*
X1310170D01*
Y1139150D01*
X1310370D01*
G37*
G36*
G01X1307570Y1134590D02*
X1307170Y1134733D01*
Y1135483D01*
X1307570Y1135625D01*
X1307770D01*
Y1134590D01*
X1307570D01*
G37*
G36*
G01Y1129890D02*
X1307170Y1130033D01*
Y1130783D01*
X1307570Y1130925D01*
X1307770D01*
Y1129890D01*
X1307570D01*
G37*
G36*
G01Y1132240D02*
X1307170Y1132383D01*
Y1133133D01*
X1307570Y1133275D01*
X1307770D01*
Y1132240D01*
X1307570D01*
G37*
G36*
G01Y1141640D02*
X1307170Y1141783D01*
Y1142533D01*
X1307570Y1142675D01*
X1307770D01*
Y1141640D01*
X1307570D01*
G37*
G36*
G01Y1136940D02*
X1307170Y1137083D01*
Y1137833D01*
X1307570Y1137975D01*
X1307770D01*
Y1136940D01*
X1307570D01*
G37*
G36*
G01Y1139290D02*
X1307170Y1139433D01*
Y1140183D01*
X1307570Y1140325D01*
X1307770D01*
Y1139290D01*
X1307570D01*
G37*
G36*
G01Y1143990D02*
X1307170Y1144133D01*
Y1144883D01*
X1307570Y1145025D01*
X1307770D01*
Y1143990D01*
X1307570D01*
G37*
G36*
G01X1307970Y1129750D02*
X1308370Y1129608D01*
Y1128858D01*
X1307970Y1128715D01*
X1307770D01*
Y1129750D01*
X1307970D01*
G37*
G36*
G01Y1134450D02*
X1308370Y1134308D01*
Y1133558D01*
X1307970Y1133415D01*
X1307770D01*
Y1134450D01*
X1307970D01*
G37*
G36*
G01Y1132100D02*
X1308370Y1131958D01*
Y1131208D01*
X1307970Y1131065D01*
X1307770D01*
Y1132100D01*
X1307970D01*
G37*
G36*
G01Y1141500D02*
X1308370Y1141358D01*
Y1140608D01*
X1307970Y1140465D01*
X1307770D01*
Y1141500D01*
X1307970D01*
G37*
G36*
G01Y1139150D02*
X1308370Y1139008D01*
Y1138258D01*
X1307970Y1138115D01*
X1307770D01*
Y1139150D01*
X1307970D01*
G37*
G36*
G01Y1136800D02*
X1308370Y1136658D01*
Y1135908D01*
X1307970Y1135765D01*
X1307770D01*
Y1136800D01*
X1307970D01*
G37*
G36*
G01Y1143850D02*
X1308370Y1143708D01*
Y1142958D01*
X1307970Y1142815D01*
X1307770D01*
Y1143850D01*
X1307970D01*
G37*
G36*
G01X1308770Y1134590D02*
X1308370Y1134733D01*
Y1135483D01*
X1308770Y1135625D01*
X1308970D01*
Y1134590D01*
X1308770D01*
G37*
G36*
G01Y1129890D02*
X1308370Y1130033D01*
Y1130783D01*
X1308770Y1130925D01*
X1308970D01*
Y1129890D01*
X1308770D01*
G37*
G36*
G01Y1132240D02*
X1308370Y1132383D01*
Y1133133D01*
X1308770Y1133275D01*
X1308970D01*
Y1132240D01*
X1308770D01*
G37*
G36*
G01X1309170Y1129750D02*
X1309570Y1129608D01*
Y1128858D01*
X1309170Y1128715D01*
X1308970D01*
Y1129750D01*
X1309170D01*
G37*
G36*
G01Y1134450D02*
X1309570Y1134308D01*
Y1133558D01*
X1309170Y1133415D01*
X1308970D01*
Y1134450D01*
X1309170D01*
G37*
G36*
G01Y1132100D02*
X1309570Y1131958D01*
Y1131208D01*
X1309170Y1131065D01*
X1308970D01*
Y1132100D01*
X1309170D01*
G37*
G36*
G01X1308770Y1141640D02*
X1308370Y1141783D01*
Y1142533D01*
X1308770Y1142675D01*
X1308970D01*
Y1141640D01*
X1308770D01*
G37*
G36*
G01Y1136940D02*
X1308370Y1137083D01*
Y1137833D01*
X1308770Y1137975D01*
X1308970D01*
Y1136940D01*
X1308770D01*
G37*
G36*
G01Y1139290D02*
X1308370Y1139433D01*
Y1140183D01*
X1308770Y1140325D01*
X1308970D01*
Y1139290D01*
X1308770D01*
G37*
G36*
G01X1309170Y1136800D02*
X1309570Y1136658D01*
Y1135908D01*
X1309170Y1135765D01*
X1308970D01*
Y1136800D01*
X1309170D01*
G37*
G36*
G01Y1143850D02*
X1309570Y1143708D01*
Y1142958D01*
X1309170Y1142815D01*
X1308970D01*
Y1143850D01*
X1309170D01*
G37*
G36*
G01Y1141500D02*
X1309570Y1141358D01*
Y1140608D01*
X1309170Y1140465D01*
X1308970D01*
Y1141500D01*
X1309170D01*
G37*
G36*
G01Y1139150D02*
X1309570Y1139008D01*
Y1138258D01*
X1309170Y1138115D01*
X1308970D01*
Y1139150D01*
X1309170D01*
G37*
G36*
G01X1308770Y1143990D02*
X1308370Y1144133D01*
Y1144883D01*
X1308770Y1145025D01*
X1308970D01*
Y1143990D01*
X1308770D01*
G37*
G36*
G01X1306770Y1134450D02*
X1307170Y1134308D01*
Y1133558D01*
X1306770Y1133415D01*
X1306570D01*
Y1134450D01*
X1306770D01*
G37*
G36*
G01X1306370Y1132240D02*
X1305970Y1132383D01*
Y1133133D01*
X1306370Y1133275D01*
X1306570D01*
Y1132240D01*
X1306370D01*
G37*
G36*
G01Y1129890D02*
X1305970Y1130033D01*
Y1130783D01*
X1306370Y1130925D01*
X1306570D01*
Y1129890D01*
X1306370D01*
G37*
G36*
G01X1306770Y1129750D02*
X1307170Y1129608D01*
Y1128858D01*
X1306770Y1128715D01*
X1306570D01*
Y1129750D01*
X1306770D01*
G37*
G36*
G01X1306370Y1134590D02*
X1305970Y1134733D01*
Y1135483D01*
X1306370Y1135625D01*
X1306570D01*
Y1134590D01*
X1306370D01*
G37*
G36*
G01X1306770Y1132100D02*
X1307170Y1131958D01*
Y1131208D01*
X1306770Y1131065D01*
X1306570D01*
Y1132100D01*
X1306770D01*
G37*
G36*
G01Y1136800D02*
X1307170Y1136658D01*
Y1135908D01*
X1306770Y1135765D01*
X1306570D01*
Y1136800D01*
X1306770D01*
G37*
G36*
G01X1306370Y1139290D02*
X1305970Y1139433D01*
Y1140183D01*
X1306370Y1140325D01*
X1306570D01*
Y1139290D01*
X1306370D01*
G37*
G36*
G01Y1136940D02*
X1305970Y1137083D01*
Y1137833D01*
X1306370Y1137975D01*
X1306570D01*
Y1136940D01*
X1306370D01*
G37*
G36*
G01X1306770Y1139150D02*
X1307170Y1139008D01*
Y1138258D01*
X1306770Y1138115D01*
X1306570D01*
Y1139150D01*
X1306770D01*
G37*
G36*
G01X1306370Y1141640D02*
X1305970Y1141783D01*
Y1142533D01*
X1306370Y1142675D01*
X1306570D01*
Y1141640D01*
X1306370D01*
G37*
G36*
G01X1306770Y1141500D02*
X1307170Y1141358D01*
Y1140608D01*
X1306770Y1140465D01*
X1306570D01*
Y1141500D01*
X1306770D01*
G37*
G36*
G01X1306370Y1143990D02*
X1305970Y1144133D01*
Y1144883D01*
X1306370Y1145025D01*
X1306570D01*
Y1143990D01*
X1306370D01*
G37*
G36*
G01X1306770Y1143850D02*
X1307170Y1143708D01*
Y1142958D01*
X1306770Y1142815D01*
X1306570D01*
Y1143850D01*
X1306770D01*
G37*
G36*
G01X1300370Y1134675D02*
X1299970Y1134818D01*
Y1135568D01*
X1300370Y1135710D01*
X1300570D01*
Y1134675D01*
X1300370D01*
G37*
G36*
G01Y1129975D02*
X1299970Y1130118D01*
Y1130868D01*
X1300370Y1131010D01*
X1300570D01*
Y1129975D01*
X1300370D01*
G37*
G36*
G01Y1132325D02*
X1299970Y1132468D01*
Y1133218D01*
X1300370Y1133360D01*
X1300570D01*
Y1132325D01*
X1300370D01*
G37*
G36*
G01X1300770Y1129835D02*
X1301170Y1129693D01*
Y1128943D01*
X1300770Y1128800D01*
X1300570D01*
Y1129835D01*
X1300770D01*
G37*
G36*
G01Y1134535D02*
X1301170Y1134393D01*
Y1133643D01*
X1300770Y1133500D01*
X1300570D01*
Y1134535D01*
X1300770D01*
G37*
G36*
G01Y1132185D02*
X1301170Y1132043D01*
Y1131293D01*
X1300770Y1131150D01*
X1300570D01*
Y1132185D01*
X1300770D01*
G37*
G36*
G01X1300370Y1137025D02*
X1299970Y1137168D01*
Y1137918D01*
X1300370Y1138060D01*
X1300570D01*
Y1137025D01*
X1300370D01*
G37*
G36*
G01X1300770Y1139235D02*
X1301170Y1139093D01*
Y1138343D01*
X1300770Y1138200D01*
X1300570D01*
Y1139235D01*
X1300770D01*
G37*
G36*
G01Y1136885D02*
X1301170Y1136743D01*
Y1135993D01*
X1300770Y1135850D01*
X1300570D01*
Y1136885D01*
X1300770D01*
G37*
G36*
G01X1300370Y1144075D02*
X1299970Y1144218D01*
Y1144968D01*
X1300370Y1145110D01*
X1300570D01*
Y1144075D01*
X1300370D01*
G37*
G36*
G01X1300770Y1143935D02*
X1301170Y1143793D01*
Y1143043D01*
X1300770Y1142900D01*
X1300570D01*
Y1143935D01*
X1300770D01*
G37*
G36*
G01X1300370Y1141725D02*
X1299970Y1141868D01*
Y1142618D01*
X1300370Y1142760D01*
X1300570D01*
Y1141725D01*
X1300370D01*
G37*
G36*
G01X1300770Y1141585D02*
X1301170Y1141443D01*
Y1140693D01*
X1300770Y1140550D01*
X1300570D01*
Y1141585D01*
X1300770D01*
G37*
G36*
G01X1300370Y1139375D02*
X1299970Y1139518D01*
Y1140268D01*
X1300370Y1140410D01*
X1300570D01*
Y1139375D01*
X1300370D01*
G37*
G36*
G01X1298370Y1129835D02*
X1298770Y1129693D01*
Y1128943D01*
X1298370Y1128800D01*
X1298170D01*
Y1129835D01*
X1298370D01*
G37*
G36*
G01Y1134535D02*
X1298770Y1134393D01*
Y1133643D01*
X1298370Y1133500D01*
X1298170D01*
Y1134535D01*
X1298370D01*
G37*
G36*
G01Y1132185D02*
X1298770Y1132043D01*
Y1131293D01*
X1298370Y1131150D01*
X1298170D01*
Y1132185D01*
X1298370D01*
G37*
G36*
G01Y1136885D02*
X1298770Y1136743D01*
Y1135993D01*
X1298370Y1135850D01*
X1298170D01*
Y1136885D01*
X1298370D01*
G37*
G36*
G01Y1143935D02*
X1298770Y1143793D01*
Y1143043D01*
X1298370Y1142900D01*
X1298170D01*
Y1143935D01*
X1298370D01*
G37*
G36*
G01Y1141585D02*
X1298770Y1141443D01*
Y1140693D01*
X1298370Y1140550D01*
X1298170D01*
Y1141585D01*
X1298370D01*
G37*
G36*
G01Y1139235D02*
X1298770Y1139093D01*
Y1138343D01*
X1298370Y1138200D01*
X1298170D01*
Y1139235D01*
X1298370D01*
G37*
G36*
G01X1299170Y1134675D02*
X1298770Y1134818D01*
Y1135568D01*
X1299170Y1135710D01*
X1299370D01*
Y1134675D01*
X1299170D01*
G37*
G36*
G01Y1129975D02*
X1298770Y1130118D01*
Y1130868D01*
X1299170Y1131010D01*
X1299370D01*
Y1129975D01*
X1299170D01*
G37*
G36*
G01Y1132325D02*
X1298770Y1132468D01*
Y1133218D01*
X1299170Y1133360D01*
X1299370D01*
Y1132325D01*
X1299170D01*
G37*
G36*
G01X1299570Y1129835D02*
X1299970Y1129693D01*
Y1128943D01*
X1299570Y1128800D01*
X1299370D01*
Y1129835D01*
X1299570D01*
G37*
G36*
G01Y1134535D02*
X1299970Y1134393D01*
Y1133643D01*
X1299570Y1133500D01*
X1299370D01*
Y1134535D01*
X1299570D01*
G37*
G36*
G01Y1132185D02*
X1299970Y1132043D01*
Y1131293D01*
X1299570Y1131150D01*
X1299370D01*
Y1132185D01*
X1299570D01*
G37*
G36*
G01Y1136885D02*
X1299970Y1136743D01*
Y1135993D01*
X1299570Y1135850D01*
X1299370D01*
Y1136885D01*
X1299570D01*
G37*
G36*
G01X1299170Y1144075D02*
X1298770Y1144218D01*
Y1144968D01*
X1299170Y1145110D01*
X1299370D01*
Y1144075D01*
X1299170D01*
G37*
G36*
G01X1299570Y1143935D02*
X1299970Y1143793D01*
Y1143043D01*
X1299570Y1142900D01*
X1299370D01*
Y1143935D01*
X1299570D01*
G37*
G36*
G01X1299170Y1141725D02*
X1298770Y1141868D01*
Y1142618D01*
X1299170Y1142760D01*
X1299370D01*
Y1141725D01*
X1299170D01*
G37*
G36*
G01X1299570Y1141585D02*
X1299970Y1141443D01*
Y1140693D01*
X1299570Y1140550D01*
X1299370D01*
Y1141585D01*
X1299570D01*
G37*
G36*
G01X1299170Y1139375D02*
X1298770Y1139518D01*
Y1140268D01*
X1299170Y1140410D01*
X1299370D01*
Y1139375D01*
X1299170D01*
G37*
G36*
G01Y1137025D02*
X1298770Y1137168D01*
Y1137918D01*
X1299170Y1138060D01*
X1299370D01*
Y1137025D01*
X1299170D01*
G37*
G36*
G01X1299570Y1139235D02*
X1299970Y1139093D01*
Y1138343D01*
X1299570Y1138200D01*
X1299370D01*
Y1139235D01*
X1299570D01*
G37*
G36*
G01X1310370Y1146200D02*
X1310770Y1146058D01*
Y1145308D01*
X1310370Y1145165D01*
X1310170D01*
Y1146200D01*
X1310370D01*
G37*
G36*
G01X1309970Y1151040D02*
X1309570Y1151183D01*
Y1151933D01*
X1309970Y1152075D01*
X1310170D01*
Y1151040D01*
X1309970D01*
G37*
G36*
G01Y1148690D02*
X1309570Y1148833D01*
Y1149583D01*
X1309970Y1149725D01*
X1310170D01*
Y1148690D01*
X1309970D01*
G37*
G36*
G01Y1146340D02*
X1309570Y1146483D01*
Y1147233D01*
X1309970Y1147375D01*
X1310170D01*
Y1146340D01*
X1309970D01*
G37*
G36*
G01X1310370Y1150900D02*
X1310770Y1150758D01*
Y1150008D01*
X1310370Y1149865D01*
X1310170D01*
Y1150900D01*
X1310370D01*
G37*
G36*
G01Y1148550D02*
X1310770Y1148408D01*
Y1147658D01*
X1310370Y1147515D01*
X1310170D01*
Y1148550D01*
X1310370D01*
G37*
G36*
G01X1309970Y1160440D02*
X1309570Y1160583D01*
Y1161333D01*
X1309970Y1161475D01*
X1310170D01*
Y1160440D01*
X1309970D01*
G37*
G36*
G01X1310370Y1160300D02*
X1310770Y1160158D01*
Y1159408D01*
X1310370Y1159265D01*
X1310170D01*
Y1160300D01*
X1310370D01*
G37*
G36*
G01X1309970Y1158090D02*
X1309570Y1158233D01*
Y1158983D01*
X1309970Y1159125D01*
X1310170D01*
Y1158090D01*
X1309970D01*
G37*
G36*
G01X1310370Y1157950D02*
X1310770Y1157808D01*
Y1157058D01*
X1310370Y1156915D01*
X1310170D01*
Y1157950D01*
X1310370D01*
G37*
G36*
G01X1309970Y1155740D02*
X1309570Y1155883D01*
Y1156633D01*
X1309970Y1156775D01*
X1310170D01*
Y1155740D01*
X1309970D01*
G37*
G36*
G01Y1153390D02*
X1309570Y1153533D01*
Y1154283D01*
X1309970Y1154425D01*
X1310170D01*
Y1153390D01*
X1309970D01*
G37*
G36*
G01X1310370Y1155600D02*
X1310770Y1155458D01*
Y1154708D01*
X1310370Y1154565D01*
X1310170D01*
Y1155600D01*
X1310370D01*
G37*
G36*
G01Y1153250D02*
X1310770Y1153108D01*
Y1152358D01*
X1310370Y1152215D01*
X1310170D01*
Y1153250D01*
X1310370D01*
G37*
G36*
G01X1307570Y1151040D02*
X1307170Y1151183D01*
Y1151933D01*
X1307570Y1152075D01*
X1307770D01*
Y1151040D01*
X1307570D01*
G37*
G36*
G01Y1148690D02*
X1307170Y1148833D01*
Y1149583D01*
X1307570Y1149725D01*
X1307770D01*
Y1148690D01*
X1307570D01*
G37*
G36*
G01Y1146340D02*
X1307170Y1146483D01*
Y1147233D01*
X1307570Y1147375D01*
X1307770D01*
Y1146340D01*
X1307570D01*
G37*
G36*
G01Y1153390D02*
X1307170Y1153533D01*
Y1154283D01*
X1307570Y1154425D01*
X1307770D01*
Y1153390D01*
X1307570D01*
G37*
G36*
G01Y1160440D02*
X1307170Y1160583D01*
Y1161333D01*
X1307570Y1161475D01*
X1307770D01*
Y1160440D01*
X1307570D01*
G37*
G36*
G01Y1158090D02*
X1307170Y1158233D01*
Y1158983D01*
X1307570Y1159125D01*
X1307770D01*
Y1158090D01*
X1307570D01*
G37*
G36*
G01Y1155740D02*
X1307170Y1155883D01*
Y1156633D01*
X1307570Y1156775D01*
X1307770D01*
Y1155740D01*
X1307570D01*
G37*
G36*
G01X1307970Y1150900D02*
X1308370Y1150758D01*
Y1150008D01*
X1307970Y1149865D01*
X1307770D01*
Y1150900D01*
X1307970D01*
G37*
G36*
G01Y1148550D02*
X1308370Y1148408D01*
Y1147658D01*
X1307970Y1147515D01*
X1307770D01*
Y1148550D01*
X1307970D01*
G37*
G36*
G01Y1146200D02*
X1308370Y1146058D01*
Y1145308D01*
X1307970Y1145165D01*
X1307770D01*
Y1146200D01*
X1307970D01*
G37*
G36*
G01Y1155600D02*
X1308370Y1155458D01*
Y1154708D01*
X1307970Y1154565D01*
X1307770D01*
Y1155600D01*
X1307970D01*
G37*
G36*
G01Y1153250D02*
X1308370Y1153108D01*
Y1152358D01*
X1307970Y1152215D01*
X1307770D01*
Y1153250D01*
X1307970D01*
G37*
G36*
G01Y1160300D02*
X1308370Y1160158D01*
Y1159408D01*
X1307970Y1159265D01*
X1307770D01*
Y1160300D01*
X1307970D01*
G37*
G36*
G01Y1157950D02*
X1308370Y1157808D01*
Y1157058D01*
X1307970Y1156915D01*
X1307770D01*
Y1157950D01*
X1307970D01*
G37*
G36*
G01X1309170Y1150900D02*
X1309570Y1150758D01*
Y1150008D01*
X1309170Y1149865D01*
X1308970D01*
Y1150900D01*
X1309170D01*
G37*
G36*
G01Y1148550D02*
X1309570Y1148408D01*
Y1147658D01*
X1309170Y1147515D01*
X1308970D01*
Y1148550D01*
X1309170D01*
G37*
G36*
G01X1308770Y1151040D02*
X1308370Y1151183D01*
Y1151933D01*
X1308770Y1152075D01*
X1308970D01*
Y1151040D01*
X1308770D01*
G37*
G36*
G01Y1148690D02*
X1308370Y1148833D01*
Y1149583D01*
X1308770Y1149725D01*
X1308970D01*
Y1148690D01*
X1308770D01*
G37*
G36*
G01Y1146340D02*
X1308370Y1146483D01*
Y1147233D01*
X1308770Y1147375D01*
X1308970D01*
Y1146340D01*
X1308770D01*
G37*
G36*
G01X1309170Y1146200D02*
X1309570Y1146058D01*
Y1145308D01*
X1309170Y1145165D01*
X1308970D01*
Y1146200D01*
X1309170D01*
G37*
G36*
G01Y1160300D02*
X1309570Y1160158D01*
Y1159408D01*
X1309170Y1159265D01*
X1308970D01*
Y1160300D01*
X1309170D01*
G37*
G36*
G01Y1157950D02*
X1309570Y1157808D01*
Y1157058D01*
X1309170Y1156915D01*
X1308970D01*
Y1157950D01*
X1309170D01*
G37*
G36*
G01Y1155600D02*
X1309570Y1155458D01*
Y1154708D01*
X1309170Y1154565D01*
X1308970D01*
Y1155600D01*
X1309170D01*
G37*
G36*
G01Y1153250D02*
X1309570Y1153108D01*
Y1152358D01*
X1309170Y1152215D01*
X1308970D01*
Y1153250D01*
X1309170D01*
G37*
G36*
G01X1308770Y1160440D02*
X1308370Y1160583D01*
Y1161333D01*
X1308770Y1161475D01*
X1308970D01*
Y1160440D01*
X1308770D01*
G37*
G36*
G01Y1158090D02*
X1308370Y1158233D01*
Y1158983D01*
X1308770Y1159125D01*
X1308970D01*
Y1158090D01*
X1308770D01*
G37*
G36*
G01Y1155740D02*
X1308370Y1155883D01*
Y1156633D01*
X1308770Y1156775D01*
X1308970D01*
Y1155740D01*
X1308770D01*
G37*
G36*
G01Y1153390D02*
X1308370Y1153533D01*
Y1154283D01*
X1308770Y1154425D01*
X1308970D01*
Y1153390D01*
X1308770D01*
G37*
G36*
G01X1306770Y1146200D02*
X1307170Y1146058D01*
Y1145308D01*
X1306770Y1145165D01*
X1306570D01*
Y1146200D01*
X1306770D01*
G37*
G36*
G01X1306370Y1151040D02*
X1305970Y1151183D01*
Y1151933D01*
X1306370Y1152075D01*
X1306570D01*
Y1151040D01*
X1306370D01*
G37*
G36*
G01Y1146340D02*
X1305970Y1146483D01*
Y1147233D01*
X1306370Y1147375D01*
X1306570D01*
Y1146340D01*
X1306370D01*
G37*
G36*
G01Y1148690D02*
X1305970Y1148833D01*
Y1149583D01*
X1306370Y1149725D01*
X1306570D01*
Y1148690D01*
X1306370D01*
G37*
G36*
G01X1306770Y1148550D02*
X1307170Y1148408D01*
Y1147658D01*
X1306770Y1147515D01*
X1306570D01*
Y1148550D01*
X1306770D01*
G37*
G36*
G01Y1150900D02*
X1307170Y1150758D01*
Y1150008D01*
X1306770Y1149865D01*
X1306570D01*
Y1150900D01*
X1306770D01*
G37*
G36*
G01Y1157950D02*
X1307170Y1157808D01*
Y1157058D01*
X1306770Y1156915D01*
X1306570D01*
Y1157950D01*
X1306770D01*
G37*
G36*
G01X1306370Y1160440D02*
X1305970Y1160583D01*
Y1161333D01*
X1306370Y1161475D01*
X1306570D01*
Y1160440D01*
X1306370D01*
G37*
G36*
G01X1306770Y1160300D02*
X1307170Y1160158D01*
Y1159408D01*
X1306770Y1159265D01*
X1306570D01*
Y1160300D01*
X1306770D01*
G37*
G36*
G01X1306370Y1153390D02*
X1305970Y1153533D01*
Y1154283D01*
X1306370Y1154425D01*
X1306570D01*
Y1153390D01*
X1306370D01*
G37*
G36*
G01Y1155740D02*
X1305970Y1155883D01*
Y1156633D01*
X1306370Y1156775D01*
X1306570D01*
Y1155740D01*
X1306370D01*
G37*
G36*
G01X1306770Y1153250D02*
X1307170Y1153108D01*
Y1152358D01*
X1306770Y1152215D01*
X1306570D01*
Y1153250D01*
X1306770D01*
G37*
G36*
G01Y1155600D02*
X1307170Y1155458D01*
Y1154708D01*
X1306770Y1154565D01*
X1306570D01*
Y1155600D01*
X1306770D01*
G37*
G36*
G01X1306370Y1158090D02*
X1305970Y1158233D01*
Y1158983D01*
X1306370Y1159125D01*
X1306570D01*
Y1158090D01*
X1306370D01*
G37*
G36*
G01X1300370Y1151125D02*
X1299970Y1151268D01*
Y1152018D01*
X1300370Y1152160D01*
X1300570D01*
Y1151125D01*
X1300370D01*
G37*
G36*
G01Y1148775D02*
X1299970Y1148918D01*
Y1149668D01*
X1300370Y1149810D01*
X1300570D01*
Y1148775D01*
X1300370D01*
G37*
G36*
G01Y1146425D02*
X1299970Y1146568D01*
Y1147318D01*
X1300370Y1147460D01*
X1300570D01*
Y1146425D01*
X1300370D01*
G37*
G36*
G01X1300770Y1150985D02*
X1301170Y1150843D01*
Y1150093D01*
X1300770Y1149950D01*
X1300570D01*
Y1150985D01*
X1300770D01*
G37*
G36*
G01Y1148635D02*
X1301170Y1148493D01*
Y1147743D01*
X1300770Y1147600D01*
X1300570D01*
Y1148635D01*
X1300770D01*
G37*
G36*
G01Y1146285D02*
X1301170Y1146143D01*
Y1145393D01*
X1300770Y1145250D01*
X1300570D01*
Y1146285D01*
X1300770D01*
G37*
G36*
G01X1300370Y1160525D02*
X1299970Y1160668D01*
Y1161418D01*
X1300370Y1161560D01*
X1300570D01*
Y1160525D01*
X1300370D01*
G37*
G36*
G01X1300770Y1160385D02*
X1301170Y1160243D01*
Y1159493D01*
X1300770Y1159350D01*
X1300570D01*
Y1160385D01*
X1300770D01*
G37*
G36*
G01X1300370Y1158175D02*
X1299970Y1158318D01*
Y1159068D01*
X1300370Y1159210D01*
X1300570D01*
Y1158175D01*
X1300370D01*
G37*
G36*
G01X1300770Y1158035D02*
X1301170Y1157893D01*
Y1157143D01*
X1300770Y1157000D01*
X1300570D01*
Y1158035D01*
X1300770D01*
G37*
G36*
G01X1300370Y1155825D02*
X1299970Y1155968D01*
Y1156718D01*
X1300370Y1156860D01*
X1300570D01*
Y1155825D01*
X1300370D01*
G37*
G36*
G01Y1153475D02*
X1299970Y1153618D01*
Y1154368D01*
X1300370Y1154510D01*
X1300570D01*
Y1153475D01*
X1300370D01*
G37*
G36*
G01X1300770Y1155685D02*
X1301170Y1155543D01*
Y1154793D01*
X1300770Y1154650D01*
X1300570D01*
Y1155685D01*
X1300770D01*
G37*
G36*
G01Y1153335D02*
X1301170Y1153193D01*
Y1152443D01*
X1300770Y1152300D01*
X1300570D01*
Y1153335D01*
X1300770D01*
G37*
G36*
G01X1298370Y1146285D02*
X1298770Y1146143D01*
Y1145393D01*
X1298370Y1145250D01*
X1298170D01*
Y1146285D01*
X1298370D01*
G37*
G36*
G01Y1150985D02*
X1298770Y1150843D01*
Y1150093D01*
X1298370Y1149950D01*
X1298170D01*
Y1150985D01*
X1298370D01*
G37*
G36*
G01Y1148635D02*
X1298770Y1148493D01*
Y1147743D01*
X1298370Y1147600D01*
X1298170D01*
Y1148635D01*
X1298370D01*
G37*
G36*
G01Y1158035D02*
X1298770Y1157893D01*
Y1157143D01*
X1298370Y1157000D01*
X1298170D01*
Y1158035D01*
X1298370D01*
G37*
G36*
G01Y1155685D02*
X1298770Y1155543D01*
Y1154793D01*
X1298370Y1154650D01*
X1298170D01*
Y1155685D01*
X1298370D01*
G37*
G36*
G01Y1153335D02*
X1298770Y1153193D01*
Y1152443D01*
X1298370Y1152300D01*
X1298170D01*
Y1153335D01*
X1298370D01*
G37*
G36*
G01X1299570Y1146285D02*
X1299970Y1146143D01*
Y1145393D01*
X1299570Y1145250D01*
X1299370D01*
Y1146285D01*
X1299570D01*
G37*
G36*
G01X1299170Y1151125D02*
X1298770Y1151268D01*
Y1152018D01*
X1299170Y1152160D01*
X1299370D01*
Y1151125D01*
X1299170D01*
G37*
G36*
G01Y1148775D02*
X1298770Y1148918D01*
Y1149668D01*
X1299170Y1149810D01*
X1299370D01*
Y1148775D01*
X1299170D01*
G37*
G36*
G01Y1146425D02*
X1298770Y1146568D01*
Y1147318D01*
X1299170Y1147460D01*
X1299370D01*
Y1146425D01*
X1299170D01*
G37*
G36*
G01X1299570Y1150985D02*
X1299970Y1150843D01*
Y1150093D01*
X1299570Y1149950D01*
X1299370D01*
Y1150985D01*
X1299570D01*
G37*
G36*
G01Y1148635D02*
X1299970Y1148493D01*
Y1147743D01*
X1299570Y1147600D01*
X1299370D01*
Y1148635D01*
X1299570D01*
G37*
G36*
G01Y1160385D02*
X1299970Y1160243D01*
Y1159493D01*
X1299570Y1159350D01*
X1299370D01*
Y1160385D01*
X1299570D01*
G37*
G36*
G01X1299170Y1158175D02*
X1298770Y1158318D01*
Y1159068D01*
X1299170Y1159210D01*
X1299370D01*
Y1158175D01*
X1299170D01*
G37*
G36*
G01X1299570Y1158035D02*
X1299970Y1157893D01*
Y1157143D01*
X1299570Y1157000D01*
X1299370D01*
Y1158035D01*
X1299570D01*
G37*
G36*
G01X1299170Y1155825D02*
X1298770Y1155968D01*
Y1156718D01*
X1299170Y1156860D01*
X1299370D01*
Y1155825D01*
X1299170D01*
G37*
G36*
G01Y1153475D02*
X1298770Y1153618D01*
Y1154368D01*
X1299170Y1154510D01*
X1299370D01*
Y1153475D01*
X1299170D01*
G37*
G36*
G01X1299570Y1155685D02*
X1299970Y1155543D01*
Y1154793D01*
X1299570Y1154650D01*
X1299370D01*
Y1155685D01*
X1299570D01*
G37*
G36*
G01Y1153335D02*
X1299970Y1153193D01*
Y1152443D01*
X1299570Y1152300D01*
X1299370D01*
Y1153335D01*
X1299570D01*
G37*
G36*
G01X1309970Y1165140D02*
X1309570Y1165283D01*
Y1166033D01*
X1309970Y1166175D01*
X1310170D01*
Y1165140D01*
X1309970D01*
G37*
G36*
G01Y1162790D02*
X1309570Y1162933D01*
Y1163683D01*
X1309970Y1163825D01*
X1310170D01*
Y1162790D01*
X1309970D01*
G37*
G36*
G01X1310370Y1167350D02*
X1310770Y1167208D01*
Y1166458D01*
X1310370Y1166315D01*
X1310170D01*
Y1167350D01*
X1310370D01*
G37*
G36*
G01Y1165000D02*
X1310770Y1164858D01*
Y1164108D01*
X1310370Y1163965D01*
X1310170D01*
Y1165000D01*
X1310370D01*
G37*
G36*
G01Y1162650D02*
X1310770Y1162508D01*
Y1161758D01*
X1310370Y1161615D01*
X1310170D01*
Y1162650D01*
X1310370D01*
G37*
G36*
G01X1309970Y1167490D02*
X1309570Y1167633D01*
Y1168383D01*
X1309970Y1168525D01*
X1310170D01*
Y1167490D01*
X1309970D01*
G37*
G36*
G01X1307570D02*
X1307170Y1167633D01*
Y1168383D01*
X1307570Y1168525D01*
X1307770D01*
Y1167490D01*
X1307570D01*
G37*
G36*
G01Y1165140D02*
X1307170Y1165283D01*
Y1166033D01*
X1307570Y1166175D01*
X1307770D01*
Y1165140D01*
X1307570D01*
G37*
G36*
G01Y1162790D02*
X1307170Y1162933D01*
Y1163683D01*
X1307570Y1163825D01*
X1307770D01*
Y1162790D01*
X1307570D01*
G37*
G36*
G01X1307970Y1167350D02*
X1308370Y1167208D01*
Y1166458D01*
X1307970Y1166315D01*
X1307770D01*
Y1167350D01*
X1307970D01*
G37*
G36*
G01Y1165000D02*
X1308370Y1164858D01*
Y1164108D01*
X1307970Y1163965D01*
X1307770D01*
Y1165000D01*
X1307970D01*
G37*
G36*
G01Y1162650D02*
X1308370Y1162508D01*
Y1161758D01*
X1307970Y1161615D01*
X1307770D01*
Y1162650D01*
X1307970D01*
G37*
G36*
G01X1309170Y1167350D02*
X1309570Y1167208D01*
Y1166458D01*
X1309170Y1166315D01*
X1308970D01*
Y1167350D01*
X1309170D01*
G37*
G36*
G01Y1165000D02*
X1309570Y1164858D01*
Y1164108D01*
X1309170Y1163965D01*
X1308970D01*
Y1165000D01*
X1309170D01*
G37*
G36*
G01Y1162650D02*
X1309570Y1162508D01*
Y1161758D01*
X1309170Y1161615D01*
X1308970D01*
Y1162650D01*
X1309170D01*
G37*
G36*
G01X1308770Y1167490D02*
X1308370Y1167633D01*
Y1168383D01*
X1308770Y1168525D01*
X1308970D01*
Y1167490D01*
X1308770D01*
G37*
G36*
G01Y1165140D02*
X1308370Y1165283D01*
Y1166033D01*
X1308770Y1166175D01*
X1308970D01*
Y1165140D01*
X1308770D01*
G37*
G36*
G01Y1162790D02*
X1308370Y1162933D01*
Y1163683D01*
X1308770Y1163825D01*
X1308970D01*
Y1162790D01*
X1308770D01*
G37*
G36*
G01X1306370D02*
X1305970Y1162933D01*
Y1163683D01*
X1306370Y1163825D01*
X1306570D01*
Y1162790D01*
X1306370D01*
G37*
G36*
G01Y1165140D02*
X1305970Y1165283D01*
Y1166033D01*
X1306370Y1166175D01*
X1306570D01*
Y1165140D01*
X1306370D01*
G37*
G36*
G01Y1167490D02*
X1305970Y1167633D01*
Y1168383D01*
X1306370Y1168525D01*
X1306570D01*
Y1167490D01*
X1306370D01*
G37*
G36*
G01X1306770Y1162650D02*
X1307170Y1162508D01*
Y1161758D01*
X1306770Y1161615D01*
X1306570D01*
Y1162650D01*
X1306770D01*
G37*
G36*
G01Y1165000D02*
X1307170Y1164858D01*
Y1164108D01*
X1306770Y1163965D01*
X1306570D01*
Y1165000D01*
X1306770D01*
G37*
G36*
G01Y1167350D02*
X1307170Y1167208D01*
Y1166458D01*
X1306770Y1166315D01*
X1306570D01*
Y1167350D01*
X1306770D01*
G37*
G36*
G01X1300770Y1162735D02*
X1301170Y1162593D01*
Y1161843D01*
X1300770Y1161700D01*
X1300570D01*
Y1162735D01*
X1300770D01*
G37*
G36*
G01X1310210Y1575686D02*
G03I-720J0D01*
G37*
G36*
G01X1305254D02*
G03I-720J0D01*
G37*
G36*
G01X1310210Y1580678D02*
G03I-720J0D01*
G37*
G36*
G01X1305254D02*
G03I-720J0D01*
G37*
G36*
G01X1303450Y1599884D02*
G03I-720J0D01*
G37*
G36*
G01X1310554D02*
G03I-720J0D01*
G37*
G36*
G01X1310210Y1587598D02*
G03I-720J0D01*
G37*
G36*
G01X1305254D02*
G03I-720J0D01*
G37*
G36*
G01X1310210Y1592590D02*
G03I-720J0D01*
G37*
G36*
G01X1305254D02*
G03I-720J0D01*
G37*
G36*
G01X1303450Y1611796D02*
G03I-720J0D01*
G37*
G36*
G01Y1604876D02*
G03I-720J0D01*
G37*
G36*
G01Y1616788D02*
G03I-720J0D01*
G37*
G36*
G01X1310554D02*
G03I-720J0D01*
G37*
G36*
G01Y1611796D02*
G03I-720J0D01*
G37*
G36*
G01Y1604876D02*
G03I-720J0D01*
G37*
G36*
G01X1326132Y239554D02*
X1326988Y238697D01*
G03X1327284Y238514I535J535D01*
G01X1327286Y238512D01*
Y233802D01*
X1326759D01*
G02X1326882Y233480I-346J-316D01*
G01Y233177D01*
G02X1326761Y232854I-467J-9D01*
G01X1327517D01*
X1327733Y232639D01*
X1327589Y232495D01*
X1327588Y232493D01*
G03X1327244Y231694I758J-800D01*
G03X1327835Y230717I1103J0D01*
G01X1327862Y230703D01*
X1328026Y230540D01*
X1327868Y230382D01*
G03X1327741Y230206I478J-479D01*
G01X1327697Y230118D01*
X1327694Y230117D01*
G02X1327458Y230274I-40J196D01*
G03X1326377Y231162I-1081J-214D01*
G03X1325792Y230994I0J-1103D01*
G02X1325705Y231234I101J173D01*
G03X1325784Y231693I-1297J460D01*
G01Y232855D01*
X1325997D01*
G02X1325874Y233176I345J316D01*
G01Y233479D01*
G02X1325995Y233802I467J9D01*
G01X1325784D01*
Y235497D01*
G03X1326174Y236457I-987J960D01*
G01Y237157D01*
G03X1325833Y238063I-1377J-1D01*
G01X1325784Y238120D01*
Y238247D01*
G03X1325591Y238949I-1377J-1D01*
G02X1325934Y239554I344J205D01*
G01X1326132D01*
G37*
G36*
G01X1316816Y1289608D02*
X1315928Y1288720D01*
Y1283796D01*
X1316916Y1282808D01*
X1335480D01*
X1340380Y1277908D01*
X1365784D01*
X1367316Y1279436D01*
Y1284598D01*
X1367041Y1284873D01*
X1347051D01*
X1342316Y1289608D01*
X1316816D01*
G37*
G36*
G01X1322270Y1580678D02*
G03I-720J0D01*
G37*
G36*
G01X1317314D02*
G03I-720J0D01*
G37*
G36*
G01X1322270Y1575686D02*
G03I-720J0D01*
G37*
G36*
G01X1317314D02*
G03I-720J0D01*
G37*
G36*
G01X1329374D02*
G03I-720J0D01*
G37*
G36*
G01Y1580678D02*
G03I-720J0D01*
G37*
G36*
G01X1315510Y1599884D02*
G03I-720J0D01*
G37*
G36*
G01X1322614D02*
G03I-720J0D01*
G37*
G36*
G01X1327570D02*
G03I-720J0D01*
G37*
G36*
G01X1322270Y1592590D02*
G03I-720J0D01*
G37*
G36*
G01X1317314D02*
G03I-720J0D01*
G37*
G36*
G01X1322270Y1587598D02*
G03I-720J0D01*
G37*
G36*
G01X1317314D02*
G03I-720J0D01*
G37*
G36*
G01X1329374D02*
G03I-720J0D01*
G37*
G36*
G01Y1592590D02*
G03I-720J0D01*
G37*
G36*
G01X1315510Y1616788D02*
G03I-720J0D01*
G37*
G36*
G01Y1611796D02*
G03I-720J0D01*
G37*
G36*
G01Y1604876D02*
G03I-720J0D01*
G37*
G36*
G01X1322614Y1611796D02*
G03I-720J0D01*
G37*
G36*
G01Y1604876D02*
G03I-720J0D01*
G37*
G36*
G01X1327570Y1611796D02*
G03I-720J0D01*
G37*
G36*
G01Y1604876D02*
G03I-720J0D01*
G37*
G36*
G01X1322614Y1616788D02*
G03I-720J0D01*
G37*
G36*
G01X1327570D02*
G03I-720J0D01*
G37*
G36*
G01X1344805Y-33989D02*
G03I-557J0D01*
G37*
G36*
G01Y-29033D02*
G03I-557J0D01*
G37*
G36*
G01Y-13989D02*
G03I-557J0D01*
G37*
G36*
G01Y-23989D02*
G03I-557J0D01*
G37*
G36*
G01Y-19033D02*
G03I-557J0D01*
G37*
G36*
G01Y-3989D02*
G03I-557J0D01*
G37*
G36*
G01Y967D02*
G03I-557J0D01*
G37*
G36*
G01Y-9033D02*
G03I-557J0D01*
G37*
G36*
G01X1334330Y1575686D02*
G03I-720J0D01*
G37*
G36*
G01Y1580678D02*
G03I-720J0D01*
G37*
G36*
G01X1346390D02*
G03I-720J0D01*
G37*
G36*
G01X1341434D02*
G03I-720J0D01*
G37*
G36*
G01X1346390Y1575686D02*
G03I-720J0D01*
G37*
G36*
G01X1341434D02*
G03I-720J0D01*
G37*
G36*
G01X1339630Y1599884D02*
G03I-720J0D01*
G37*
G36*
G01X1334674D02*
G03I-720J0D01*
G37*
G36*
G01X1346734D02*
G03I-720J0D01*
G37*
G36*
G01X1334330Y1587598D02*
G03I-720J0D01*
G37*
G36*
G01Y1592590D02*
G03I-720J0D01*
G37*
G36*
G01X1346390D02*
G03I-720J0D01*
G37*
G36*
G01X1341434D02*
G03I-720J0D01*
G37*
G36*
G01X1346390Y1587598D02*
G03I-720J0D01*
G37*
G36*
G01X1341434D02*
G03I-720J0D01*
G37*
G36*
G01X1339630Y1616788D02*
G03I-720J0D01*
G37*
G36*
G01Y1611796D02*
G03I-720J0D01*
G37*
G36*
G01Y1604876D02*
G03I-720J0D01*
G37*
G36*
G01X1334674Y1616788D02*
G03I-720J0D01*
G37*
G36*
G01Y1611796D02*
G03I-720J0D01*
G37*
G36*
G01Y1604876D02*
G03I-720J0D01*
G37*
G36*
G01X1346734Y1611796D02*
G03I-720J0D01*
G37*
G36*
G01Y1604876D02*
G03I-720J0D01*
G37*
G36*
G01Y1616788D02*
G03I-720J0D01*
G37*
G36*
G01X1399316Y1283908D02*
Y1279408D01*
X1397816Y1277908D01*
X1380816D01*
X1378816Y1275908D01*
Y1270908D01*
X1377916Y1270008D01*
X1348713D01*
X1347316Y1271401D01*
Y1276408D01*
X1347816Y1276908D01*
X1366316D01*
X1368316Y1278908D01*
Y1283908D01*
X1369016Y1284608D01*
X1398616D01*
X1399316Y1283908D01*
G37*
G36*
G01X1358450Y1575686D02*
G03I-720J0D01*
G37*
G36*
G01X1353494D02*
G03I-720J0D01*
G37*
G36*
G01X1358450Y1580678D02*
G03I-720J0D01*
G37*
G36*
G01X1353494D02*
G03I-720J0D01*
G37*
G36*
G01X1351690Y1599884D02*
G03I-720J0D01*
G37*
G36*
G01X1363750D02*
G03I-720J0D01*
G37*
G36*
G01X1358794D02*
G03I-720J0D01*
G37*
G36*
G01X1358450Y1587598D02*
G03I-720J0D01*
G37*
G36*
G01X1353494D02*
G03I-720J0D01*
G37*
G36*
G01X1358450Y1592590D02*
G03I-720J0D01*
G37*
G36*
G01X1353494D02*
G03I-720J0D01*
G37*
G36*
G01X1351690Y1611796D02*
G03I-720J0D01*
G37*
G36*
G01Y1604876D02*
G03I-720J0D01*
G37*
G36*
G01Y1616788D02*
G03I-720J0D01*
G37*
G36*
G01X1363750D02*
G03I-720J0D01*
G37*
G36*
G01Y1611796D02*
G03I-720J0D01*
G37*
G36*
G01Y1604876D02*
G03I-720J0D01*
G37*
G36*
G01X1358794Y1616788D02*
G03I-720J0D01*
G37*
G36*
G01Y1611796D02*
G03I-720J0D01*
G37*
G36*
G01Y1604876D02*
G03I-720J0D01*
G37*
G36*
G01X1371306Y176366D02*
G03I-720J0D01*
G37*
G36*
G01X1378295Y197604D02*
G03I-698J0D01*
G37*
G36*
G01X1370510Y1580678D02*
G03I-720J0D01*
G37*
G36*
G01X1365554D02*
G03I-720J0D01*
G37*
G36*
G01X1370510Y1575592D02*
G03I-720J0D01*
G37*
G36*
G01X1365554D02*
G03I-720J0D01*
G37*
G36*
G01X1377614Y1575686D02*
G03I-720J0D01*
G37*
G36*
G01Y1580678D02*
G03I-720J0D01*
G37*
G36*
G01X1375810Y1599790D02*
G03I-720J0D01*
G37*
G36*
G01X1370854D02*
G03I-720J0D01*
G37*
G36*
G01X1370510Y1592590D02*
G03I-720J0D01*
G37*
G36*
G01X1365554D02*
G03I-720J0D01*
G37*
G36*
G01X1370510Y1587598D02*
G03I-720J0D01*
G37*
G36*
G01X1365554D02*
G03I-720J0D01*
G37*
G36*
G01X1377614D02*
G03I-720J0D01*
G37*
G36*
G01Y1592590D02*
G03I-720J0D01*
G37*
G36*
G01X1375810Y1611796D02*
G03I-720J0D01*
G37*
G36*
G01Y1604876D02*
G03I-720J0D01*
G37*
G36*
G01Y1616788D02*
G03I-720J0D01*
G37*
G36*
G01X1370854Y1611796D02*
G03I-720J0D01*
G37*
G36*
G01Y1604876D02*
G03I-720J0D01*
G37*
G36*
G01Y1616788D02*
G03I-720J0D01*
G37*
G36*
G01X1380689Y176330D02*
G03I-720J0D01*
G37*
G36*
G01X1387478Y197668D02*
G03I-698J0D01*
G37*
G36*
G01X1396019D02*
G03I-698J0D01*
G37*
G36*
G01X1385910Y501242D02*
G03I-720J0D01*
G37*
G36*
G01X1390940Y497742D02*
G03I-720J0D01*
G37*
G36*
G01X1380448Y929879D02*
X1380201Y930126D01*
Y938214D01*
X1380586Y938599D01*
X1381506D01*
X1382905Y937200D01*
X1387485D01*
X1387880Y936805D01*
Y933998D01*
X1386094Y932211D01*
X1386016Y932133D01*
Y930169D01*
X1385726Y929879D01*
X1380448D01*
G37*
G36*
G01X1389788Y937364D02*
X1391588D01*
X1392188Y936764D01*
Y934364D01*
X1394135Y932417D01*
X1404606D01*
X1405102Y931921D01*
Y928448D01*
X1402574Y925920D01*
X1396887D01*
G02X1396487Y926307I0J400D01*
G03X1395187Y927566I-1300J-42D01*
G03X1394127Y927019I0J-1301D01*
G02X1393518Y926968I-326J232D01*
G01X1393065Y927421D01*
X1387494D01*
X1387027Y927888D01*
Y932008D01*
X1389188Y934169D01*
Y936764D01*
X1389788Y937364D01*
G37*
G36*
G01X1380912Y966580D02*
X1403485D01*
X1403816Y966249D01*
Y961649D01*
X1403390Y961223D01*
X1384350D01*
X1383766Y960639D01*
Y952835D01*
X1384516Y952085D01*
X1403280D01*
X1403786Y951579D01*
Y946839D01*
X1403360Y946413D01*
X1382570D01*
X1381346Y945189D01*
X1380236D01*
X1380002Y945423D01*
Y946803D01*
X1380053Y946922D01*
G03X1380172Y947507I-1382J586D01*
G01Y949620D01*
G03X1379825Y950579I-1501J-1D01*
G01Y952956D01*
G03X1380172Y953915I-1154J960D01*
G01Y956029D01*
G03X1379825Y956988I-1501J-1D01*
G01Y959530D01*
G03X1380073Y960326I-1153J796D01*
G03X1380034Y960656I-1402J2D01*
G01X1380028Y960679D01*
Y962435D01*
G03X1379825Y963148I-1357J-1D01*
G01Y965493D01*
X1380912Y966580D01*
G37*
G36*
G01X1393937Y937262D02*
X1404510D01*
X1404805Y936966D01*
Y933612D01*
X1404549Y933356D01*
X1394440D01*
X1393654Y934142D01*
Y936979D01*
X1393937Y937262D01*
G37*
G36*
G01D02*
X1404510D01*
X1404805Y936966D01*
Y933612D01*
X1404549Y933356D01*
X1394440D01*
X1393654Y934142D01*
Y936979D01*
X1393937Y937262D01*
G37*
G36*
G01X1380502Y943259D02*
X1382732Y945489D01*
X1387908D01*
X1388608Y944789D01*
Y938853D01*
X1388048Y938293D01*
X1383106D01*
X1380502Y940897D01*
Y943259D01*
G37*
G36*
G01X1380806Y1009887D02*
X1403378D01*
X1403766Y1009499D01*
Y1005119D01*
X1403318Y1004671D01*
X1384648D01*
X1383636Y1003659D01*
Y996468D01*
X1384746Y995358D01*
X1403517D01*
X1403836Y995039D01*
Y990529D01*
X1403483Y990176D01*
X1384633D01*
X1383676Y989219D01*
Y981994D01*
X1384596Y981074D01*
X1403541D01*
X1403816Y980799D01*
Y976199D01*
X1403369Y975752D01*
X1382770D01*
X1382744Y975778D01*
X1380345D01*
X1380148Y975975D01*
Y976392D01*
X1380123Y976417D01*
Y996620D01*
G03X1380499Y997574I-1020J953D01*
G01Y999631D01*
X1380500Y999635D01*
G03X1380501Y999684I-1396J53D01*
G03X1380123Y1000639I-1397J-1D01*
G01Y1003029D01*
G03X1380501Y1003984I-1019J956D01*
G01Y1006093D01*
G03X1380123Y1007048I-1397J-1D01*
G01Y1009204D01*
X1380806Y1009887D01*
G37*
G36*
G01X1381750Y974773D02*
X1387984D01*
X1388684Y974073D01*
Y968137D01*
X1388124Y967577D01*
X1383885D01*
X1383879Y967583D01*
X1382329D01*
X1379771Y970141D01*
Y972448D01*
G03X1379954Y972924I-1100J696D01*
G01X1379964Y972987D01*
X1381750Y974773D01*
G37*
G36*
G01X1381051Y1018150D02*
X1391905D01*
X1392255Y1017800D01*
Y1016156D01*
G02X1391731Y1015775I-400J-1D01*
G03X1391326Y1015840I-406J-1236D01*
G03Y1013238I0J-1301D01*
G03X1391731Y1013303I-1J1301D01*
G02X1392255Y1012922I124J-380D01*
G01Y1011533D01*
X1391695Y1010973D01*
X1381716D01*
X1380666Y1012023D01*
Y1017765D01*
X1381051Y1018150D01*
G37*
G36*
G01X1403218Y1024487D02*
X1403796Y1023909D01*
Y1019119D01*
X1403508Y1018831D01*
X1381114D01*
X1380595Y1019350D01*
Y1035885D01*
X1381091Y1036381D01*
X1384895D01*
X1385320Y1035956D01*
Y1031493D01*
X1384717Y1030890D01*
X1384695D01*
X1384387Y1030582D01*
Y1025387D01*
X1385287Y1024487D01*
X1403218D01*
G37*
G36*
G01X1385533Y1030162D02*
X1386336Y1030965D01*
X1397740D01*
X1399855Y1028850D01*
Y1025702D01*
X1399796Y1025643D01*
X1385875D01*
X1385533Y1025985D01*
Y1030162D01*
G37*
G36*
G01X1381316Y1276908D02*
X1398316D01*
X1400316Y1278908D01*
Y1283908D01*
X1401016Y1284608D01*
X1431816D01*
Y1279616D01*
X1430108Y1277908D01*
X1411816D01*
X1410816Y1276908D01*
Y1270908D01*
X1409916Y1270008D01*
X1380716D01*
X1379816Y1270908D01*
Y1275408D01*
X1381316Y1276908D01*
G37*
G36*
G01X1382570Y1575686D02*
G03I-720J0D01*
G37*
G36*
G01Y1580678D02*
G03I-720J0D01*
G37*
G36*
G01X1387870Y1599884D02*
G03I-720J0D01*
G37*
G36*
G01X1382914D02*
G03I-720J0D01*
G37*
G36*
G01X1382570Y1587598D02*
G03I-720J0D01*
G37*
G36*
G01Y1592590D02*
G03I-720J0D01*
G37*
G36*
G01X1387870Y1616788D02*
G03I-720J0D01*
G37*
G36*
G01X1382914D02*
G03I-720J0D01*
G37*
G36*
G01X1387870Y1611796D02*
G03I-720J0D01*
G37*
G36*
G01Y1604876D02*
G03I-720J0D01*
G37*
G36*
G01X1382914Y1611796D02*
G03I-720J0D01*
G37*
G36*
G01Y1604876D02*
G03I-720J0D01*
G37*
G36*
G01X1410278Y151948D02*
G03I-720J0D01*
G37*
G36*
G01X1405122Y138742D02*
G03I-720J0D01*
G37*
G36*
G01X1410278Y156904D02*
G03I-720J0D01*
G37*
G36*
G01X1410436Y171696D02*
G03I-720J0D01*
G37*
G36*
G01X1401960Y171672D02*
G03I-720J0D01*
G37*
G36*
G01X1404769Y197668D02*
G03I-698J0D01*
G37*
G36*
G01X1413674Y138742D02*
G03I-720J0D01*
G37*
G36*
G01X1418988Y171696D02*
G03I-720J0D01*
G37*
G36*
G01X1413549Y197668D02*
G03I-698J0D01*
G37*
G36*
G01X1412816Y1276908D02*
X1430816D01*
X1432816Y1278908D01*
Y1283908D01*
X1433516Y1284608D01*
X1463116D01*
X1463416Y1284308D01*
Y1279008D01*
X1462316Y1277908D01*
X1443816D01*
X1442816Y1276908D01*
Y1270908D01*
X1441916Y1270008D01*
X1412718D01*
X1411816Y1270908D01*
Y1275908D01*
X1412816Y1276908D01*
G37*
G36*
G01X1422636Y1575362D02*
G03I-491J0D01*
G37*
G36*
G01X1439336Y64412D02*
G03I-656J0D01*
G37*
G36*
G01X1437156Y300319D02*
G03I-720J0D01*
G37*
G36*
G01X1439714Y943038D02*
X1441976D01*
X1442003Y943030D01*
G03X1442256Y942995I247J855D01*
G01Y942996D01*
X1443381D01*
X1443815Y942561D01*
Y941276D01*
X1444736Y940355D01*
X1452428D01*
X1453244Y939539D01*
Y938150D01*
X1453241Y938132D01*
G03X1453219Y937896I1279J-238D01*
G03X1453241Y937660I1301J2D01*
G01X1453244Y937642D01*
Y934043D01*
X1453234Y934013D01*
G03X1453169Y933598I1287J-414D01*
G03X1453234Y933183I1352J-1D01*
G01X1453244Y933153D01*
Y931732D01*
X1453241Y931715D01*
G03X1453221Y931488I1281J-227D01*
G03X1453241Y931261I1301J0D01*
G01X1453244Y931244D01*
Y927634D01*
X1453234Y927604D01*
G03X1453206Y927504I1287J-414D01*
G01X1453193Y927449D01*
X1451339Y925595D01*
X1429376D01*
X1428422Y926549D01*
Y936885D01*
X1428706Y937169D01*
X1431192D01*
X1437061Y943038D01*
X1437976D01*
X1438003Y943030D01*
G03X1438256Y942995I247J855D01*
G01Y942996D01*
X1439434D01*
Y942995D01*
G03X1439687Y943030I6J890D01*
G01X1439714Y943038D01*
G37*
G36*
G01X1449791Y967949D02*
X1453024D01*
X1453304Y967669D01*
Y966230D01*
X1453287Y966192D01*
G03X1453169Y965640I1234J-552D01*
G03X1453287Y965088I1352J0D01*
G01X1453304Y965050D01*
Y963994D01*
X1453293Y963962D01*
G03X1453219Y963530I1227J-433D01*
G03X1453293Y963098I1301J1D01*
G01X1453304Y963066D01*
Y959822D01*
X1453287Y959784D01*
G03X1453169Y959232I1234J-552D01*
G03X1453287Y958680I1352J0D01*
G01X1453304Y958642D01*
Y957586D01*
X1453293Y957554D01*
G03X1453219Y957122I1227J-433D01*
G03X1453293Y956690I1301J1D01*
G01X1453304Y956658D01*
Y953413D01*
X1453287Y953375D01*
G03X1453169Y952823I1234J-552D01*
G03X1453287Y952271I1352J0D01*
G01X1453304Y952233D01*
Y951177D01*
X1453293Y951145D01*
G03X1453219Y950713I1227J-433D01*
G03X1453293Y950281I1301J1D01*
G01X1453304Y950249D01*
Y949176D01*
X1455011Y947469D01*
Y946004D01*
G02X1454590Y945604I-400J-1D01*
G03X1454520Y945606I-72J-1300D01*
G03X1453231Y944490I0J-1302D01*
G01X1453207Y944319D01*
X1451469D01*
X1449160Y946628D01*
X1430167D01*
X1429806Y946989D01*
Y951979D01*
X1429900Y952073D01*
X1447865D01*
X1448157Y952365D01*
X1449048Y953257D01*
Y960647D01*
X1448326Y961369D01*
X1431050D01*
X1429826Y962593D01*
Y966529D01*
X1430036Y966739D01*
X1448581D01*
X1449791Y967949D01*
G37*
G36*
G01X1441786Y945919D02*
X1448586D01*
X1451136Y943369D01*
Y941299D01*
X1450906Y941069D01*
X1444731D01*
X1444516Y941284D01*
Y942469D01*
X1444316Y942668D01*
Y942769D01*
X1443546Y943540D01*
X1441676D01*
X1441666Y943549D01*
Y945799D01*
X1441786Y945919D01*
G37*
G36*
G01X1448961Y1024574D02*
X1452756D01*
X1453011Y1024319D01*
Y976328D01*
X1452483Y975800D01*
X1448280D01*
X1448261Y975781D01*
X1432224D01*
X1429676Y978329D01*
Y981659D01*
X1429937Y981920D01*
X1433057D01*
X1433888Y981089D01*
X1448043D01*
X1449044Y982091D01*
Y989359D01*
X1448060Y990343D01*
X1431019D01*
X1429826Y991536D01*
Y995619D01*
X1430026Y995819D01*
X1431678D01*
X1432012Y995485D01*
X1448386D01*
X1449216Y996315D01*
Y1003835D01*
X1448446Y1004605D01*
X1430240D01*
X1429786Y1005059D01*
Y1009807D01*
X1429938Y1009959D01*
X1447976D01*
X1448896Y1010879D01*
Y1018244D01*
X1448123Y1019017D01*
X1430292D01*
X1429666Y1019643D01*
Y1023783D01*
X1430456Y1024573D01*
X1448960D01*
X1448961Y1024574D01*
G37*
G36*
G01X1443716Y1025569D02*
X1433516D01*
X1432716Y1026369D01*
Y1029269D01*
X1433316Y1029869D01*
X1434966D01*
X1435986Y1030889D01*
X1443686D01*
X1443916Y1030659D01*
Y1025769D01*
X1443716Y1025569D01*
G37*
G36*
G01X1443816Y1275908D02*
Y1270908D01*
X1444716Y1270008D01*
X1464916D01*
X1476816Y1281908D01*
Y1289108D01*
X1478616Y1290908D01*
X1494280D01*
X1495666Y1292294D01*
Y1297758D01*
X1495616Y1297808D01*
X1469477D01*
X1467316Y1295647D01*
Y1287908D01*
X1464816Y1285408D01*
Y1278908D01*
X1462816Y1276908D01*
X1444816D01*
X1443816Y1275908D01*
G37*
G36*
G01X1438764Y1671103D02*
G03I-491J0D01*
G37*
G36*
G01X1445431Y974754D02*
X1453032D01*
X1453322Y974464D01*
Y972675D01*
X1453302Y972634D01*
G03X1453169Y972049I1220J-585D01*
G03X1453296Y971477I1352J0D01*
G01X1453315Y971436D01*
Y970428D01*
X1453302Y970394D01*
G03X1453220Y969939I1219J-455D01*
G03X1453302Y969484I1301J0D01*
G01X1453315Y969450D01*
Y968738D01*
X1453136Y968559D01*
X1448869D01*
X1447874Y967564D01*
X1445926D01*
X1445924Y967567D01*
X1445118D01*
X1444758Y967927D01*
Y970121D01*
X1444186Y970693D01*
Y971687D01*
X1445232Y972733D01*
Y974555D01*
X1445431Y974754D01*
G37*
G36*
G01X1453209Y1025462D02*
X1445248D01*
X1444502Y1026208D01*
Y1033265D01*
X1444926Y1033689D01*
X1452926D01*
X1453494Y1033121D01*
Y1025747D01*
X1453209Y1025462D01*
G37*
G36*
G01X1461733Y1418691D02*
X1463057Y1417368D01*
Y1417071D01*
X1463784Y1416344D01*
X1464262D01*
X1467167D01*
X1467298Y1416213D01*
Y1415808D01*
X1467292Y1415802D01*
Y1415677D01*
X1467173Y1415558D01*
X1467048D01*
X1463048D01*
X1462298Y1416308D01*
X1461798D01*
X1461554D01*
X1460357Y1417505D01*
Y1417755D01*
X1461293Y1418691D01*
X1461733D01*
G37*
G36*
G01X1508201Y1444406D02*
X1453806D01*
X1453314Y1444898D01*
Y1456218D01*
X1453325Y1456229D01*
Y1457727D01*
X1457691Y1462093D01*
X1507115D01*
X1509510Y1459698D01*
Y1445715D01*
X1508201Y1444406D01*
G37*
G36*
G01X1446871Y1676291D02*
G03I-491J0D01*
G37*
G36*
G01X1482303Y281120D02*
X1481459Y280276D01*
X1470818D01*
X1469648Y281446D01*
Y314756D01*
Y318910D01*
X1470694Y319956D01*
X1474848D01*
X1481458D01*
X1482303Y319111D01*
Y281120D01*
G37*
G36*
G01X1467542Y1420815D02*
X1467110Y1420383D01*
X1466033D01*
X1465107Y1421309D01*
Y1424535D01*
Y1424752D01*
X1465582Y1425227D01*
X1465586Y1425223D01*
X1467310D01*
X1467542Y1424991D01*
Y1420815D01*
G37*
G36*
G01X1475178Y1417225D02*
X1483089D01*
X1483354Y1417490D01*
Y1423855D01*
Y1426243D01*
X1482803Y1426794D01*
X1480879D01*
X1480570Y1426485D01*
Y1423635D01*
Y1419811D01*
X1479995Y1419236D01*
X1475202D01*
X1474980Y1419014D01*
Y1417423D01*
X1475178Y1417225D01*
G37*
G36*
G01X1467029Y1417348D02*
X1464524D01*
X1463654Y1418218D01*
X1462790Y1419082D01*
X1461402Y1420470D01*
X1460786Y1421086D01*
Y1422748D01*
X1461050Y1423012D01*
X1463383D01*
X1463462Y1422933D01*
Y1422710D01*
Y1421267D01*
X1463464Y1421265D01*
X1465691Y1419038D01*
X1466957D01*
X1467219D01*
X1467498Y1418759D01*
Y1417496D01*
X1467350Y1417348D01*
X1467029D01*
G37*
G36*
G01X1473682Y1419159D02*
Y1416548D01*
X1472946Y1415812D01*
Y1412426D01*
X1472769Y1412249D01*
X1471805D01*
X1471682Y1412372D01*
Y1412494D01*
Y1418373D01*
X1471678Y1418377D01*
Y1420454D01*
Y1420948D01*
Y1424769D01*
Y1425696D01*
X1470852Y1426522D01*
X1465498D01*
X1465491Y1426515D01*
X1465005D01*
X1463798Y1425308D01*
Y1424508D01*
X1463302Y1424012D01*
X1461051D01*
X1460400Y1424663D01*
Y1434845D01*
X1461565Y1436010D01*
X1478243D01*
X1478750Y1435503D01*
Y1425327D01*
X1478746Y1425324D01*
Y1424216D01*
X1476780Y1422250D01*
X1475673D01*
X1473682Y1420259D01*
Y1419701D01*
Y1419159D01*
G37*
G36*
G01X1462237Y1575686D02*
G03I-720J0D01*
G37*
G36*
G01Y1580678D02*
G03I-720J0D01*
G37*
G36*
G01X1474297D02*
G03I-720J0D01*
G37*
G36*
G01Y1575686D02*
G03I-720J0D01*
G37*
G36*
G01X1467193D02*
G03I-720J0D01*
G37*
G36*
G01Y1580678D02*
G03I-720J0D01*
G37*
G36*
G01X1462237Y1587598D02*
G03I-720J0D01*
G37*
G36*
G01Y1592590D02*
G03I-720J0D01*
G37*
G36*
G01X1472493Y1599884D02*
G03I-720J0D01*
G37*
G36*
G01X1467537D02*
G03I-720J0D01*
G37*
G36*
G01X1474297Y1592590D02*
G03I-720J0D01*
G37*
G36*
G01Y1587598D02*
G03I-720J0D01*
G37*
G36*
G01X1467193D02*
G03I-720J0D01*
G37*
G36*
G01Y1592590D02*
G03I-720J0D01*
G37*
G36*
G01X1467537Y1611796D02*
G03I-720J0D01*
G37*
G36*
G01X1472493D02*
G03I-720J0D01*
G37*
G36*
G01X1467537Y1604876D02*
G03I-720J0D01*
G37*
G36*
G01X1472493D02*
G03I-720J0D01*
G37*
G36*
G01Y1616788D02*
G03I-720J0D01*
G37*
G36*
G01X1467537D02*
G03I-720J0D01*
G37*
G36*
G01X1480711Y-29033D02*
G03I-557J0D01*
G37*
G36*
G01Y-33989D02*
G03I-557J0D01*
G37*
G36*
G01Y-13989D02*
G03I-557J0D01*
G37*
G36*
G01Y-19033D02*
G03I-557J0D01*
G37*
G36*
G01Y-23989D02*
G03I-557J0D01*
G37*
G36*
G01Y967D02*
G03I-557J0D01*
G37*
G36*
G01Y-3989D02*
G03I-557J0D01*
G37*
G36*
G01Y-9033D02*
G03I-557J0D01*
G37*
G36*
G01X1483458Y280690D02*
Y317956D01*
Y319556D01*
X1483858Y319956D01*
X1490258D01*
X1490958Y319256D01*
Y317956D01*
Y280944D01*
X1490469Y280455D01*
X1483693D01*
X1483458Y280690D01*
G37*
G36*
G01X1505818Y300447D02*
X1501422Y304843D01*
X1493320D01*
X1492746Y304269D01*
Y292407D01*
Y291787D01*
X1493120Y291413D01*
X1500572D01*
X1501622Y292463D01*
Y293320D01*
Y296443D01*
X1502322Y297143D01*
X1502432Y297253D01*
X1505376D01*
X1507379Y299256D01*
X1507445Y299322D01*
X1514000D01*
X1514034Y299356D01*
Y300112D01*
X1513957Y300189D01*
X1506076D01*
X1506011Y300254D01*
X1505970Y300295D01*
X1505818Y300447D01*
G37*
G36*
G01X1509049Y1314052D02*
X1509789Y1314792D01*
X1527880D01*
X1528576Y1315488D01*
Y1320254D01*
X1527949Y1320881D01*
X1502551D01*
X1498816Y1317146D01*
Y1300408D01*
X1496816Y1298408D01*
Y1292013D01*
X1494711Y1289908D01*
X1479116D01*
X1477816Y1288608D01*
Y1283308D01*
X1477916Y1283208D01*
X1500437D01*
X1504726Y1287498D01*
Y1298458D01*
X1507967Y1301699D01*
Y1303739D01*
Y1307008D01*
Y1312970D01*
X1509049Y1314052D01*
G37*
G36*
G01X1491313Y1580678D02*
G03I-720J0D01*
G37*
G36*
G01Y1575686D02*
G03I-720J0D01*
G37*
G36*
G01X1486357D02*
G03I-720J0D01*
G37*
G36*
G01Y1580678D02*
G03I-720J0D01*
G37*
G36*
G01X1479253D02*
G03I-720J0D01*
G37*
G36*
G01Y1575686D02*
G03I-720J0D01*
G37*
G36*
G01X1491657Y1599884D02*
G03I-720J0D01*
G37*
G36*
G01X1479597D02*
G03I-720J0D01*
G37*
G36*
G01X1484553D02*
G03I-720J0D01*
G37*
G36*
G01X1491313Y1587598D02*
G03I-720J0D01*
G37*
G36*
G01X1486357D02*
G03I-720J0D01*
G37*
G36*
G01Y1592590D02*
G03I-720J0D01*
G37*
G36*
G01X1491313D02*
G03I-720J0D01*
G37*
G36*
G01X1479253D02*
G03I-720J0D01*
G37*
G36*
G01Y1587598D02*
G03I-720J0D01*
G37*
G36*
G01X1491657Y1604876D02*
G03I-720J0D01*
G37*
G36*
G01Y1611796D02*
G03I-720J0D01*
G37*
G36*
G01Y1616788D02*
G03I-720J0D01*
G37*
G36*
G01X1484553D02*
G03I-720J0D01*
G37*
G36*
G01X1479597D02*
G03I-720J0D01*
G37*
G36*
G01Y1611796D02*
G03I-720J0D01*
G37*
G36*
G01X1484553D02*
G03I-720J0D01*
G37*
G36*
G01X1479597Y1604876D02*
G03I-720J0D01*
G37*
G36*
G01X1484553D02*
G03I-720J0D01*
G37*
G36*
G01X1479444Y1637189D02*
G03I-720J0D01*
G37*
G36*
G01X1484168Y1738108D02*
X1783936D01*
G02X1784122Y1737984I1J-200D01*
G01X1784285Y1737584D01*
X1784260Y1737466D01*
X1784217Y1737423D01*
G03X1783016Y1736176I22078J-22466D01*
G02X1782868Y1736110I-149J134D01*
G01X1617787D01*
X1617756Y1736121D01*
G03X1617126Y1736222I-629J-1909D01*
G03X1616496Y1736121I-1J-2010D01*
G01X1616465Y1736110D01*
X1602039D01*
X1602008Y1736121D01*
G03X1601378Y1736222I-629J-1909D01*
G03X1600748Y1736121I-1J-2010D01*
G01X1600717Y1736110D01*
X1586291D01*
X1586260Y1736121D01*
G03X1585630Y1736222I-629J-1909D01*
G03X1585000Y1736121I-1J-2010D01*
G01X1584969Y1736110D01*
X1571740D01*
X1571687Y1736126D01*
X1571662Y1736142D01*
G03X1571390Y1736222I-272J-421D01*
G01X1568374D01*
G03X1568102Y1736142I0J-501D01*
G01X1568077Y1736126D01*
X1568024Y1736110D01*
X1550858D01*
X1550827Y1736121D01*
G03X1550197Y1736222I-629J-1909D01*
G03X1549567Y1736121I-1J-2010D01*
G01X1549536Y1736110D01*
X1535110D01*
X1535079Y1736121D01*
G03X1534449Y1736222I-629J-1909D01*
G03X1533819Y1736121I-1J-2010D01*
G01X1533788Y1736110D01*
X1519362D01*
X1519331Y1736121D01*
G03X1518701Y1736222I-629J-1909D01*
G03X1518071Y1736121I-1J-2010D01*
G01X1518040Y1736110D01*
X1504811D01*
X1504758Y1736126D01*
X1504733Y1736142D01*
G03X1504462Y1736222I-272J-421D01*
G01X1501444D01*
G03X1501173Y1736142I1J-501D01*
G01X1501148Y1736126D01*
X1501095Y1736110D01*
X1485236D01*
G02X1485088Y1736176I1J200D01*
G03X1483887Y1737423I-23279J-21219D01*
G01X1483844Y1737466D01*
X1483819Y1737584D01*
X1483982Y1737984D01*
G02X1484168Y1738108I185J-76D01*
G37*
G36*
G01X1510684Y295468D02*
X1510733Y295418D01*
Y292732D01*
X1510482Y292481D01*
X1509792Y291790D01*
Y290025D01*
Y287262D01*
X1509394Y286864D01*
X1503241D01*
X1503001Y287104D01*
Y288668D01*
X1505534Y291201D01*
X1507396Y293063D01*
X1508237Y293904D01*
X1508979Y294646D01*
X1509340Y295007D01*
X1509801Y295468D01*
X1510684D01*
G37*
G36*
G01X1507800Y298143D02*
X1505619Y295962D01*
X1503622D01*
X1503522Y295862D01*
Y294343D01*
X1503722Y294143D01*
X1505260D01*
X1508499Y297382D01*
X1509030D01*
X1510740D01*
X1510840Y297482D01*
Y298122D01*
X1510700Y298262D01*
X1507919D01*
X1507800Y298143D01*
G37*
G36*
G01X1515735Y304082D02*
X1516551D01*
X1517347Y304878D01*
Y313869D01*
Y314577D01*
Y316785D01*
X1516310Y317822D01*
X1509680D01*
X1508540D01*
X1507950Y317232D01*
Y308322D01*
X1508433Y307839D01*
Y305042D01*
X1509206Y304268D01*
X1510680D01*
X1510750Y304338D01*
Y306742D01*
X1510530Y306962D01*
Y308582D01*
X1509530Y309582D01*
X1509240Y309872D01*
Y312802D01*
X1509530Y313092D01*
X1510500Y314062D01*
X1510980Y314542D01*
X1515490D01*
X1515992Y314040D01*
Y313550D01*
Y311340D01*
Y310914D01*
Y307914D01*
X1515685Y307607D01*
Y304132D01*
X1515735Y304082D01*
G37*
G36*
G01X1510477Y1575686D02*
G03I-720J0D01*
G37*
G36*
G01Y1580678D02*
G03I-720J0D01*
G37*
G36*
G01X1503373D02*
G03I-720J0D01*
G37*
G36*
G01X1498417D02*
G03I-720J0D01*
G37*
G36*
G01X1503373Y1575686D02*
G03I-720J0D01*
G37*
G36*
G01X1498417D02*
G03I-720J0D01*
G37*
G36*
G01X1503717Y1599884D02*
G03I-720J0D01*
G37*
G36*
G01X1508673D02*
G03I-720J0D01*
G37*
G36*
G01X1496613D02*
G03I-720J0D01*
G37*
G36*
G01X1510477Y1587598D02*
G03I-720J0D01*
G37*
G36*
G01Y1592590D02*
G03I-720J0D01*
G37*
G36*
G01X1503373D02*
G03I-720J0D01*
G37*
G36*
G01X1498417D02*
G03I-720J0D01*
G37*
G36*
G01X1503373Y1587598D02*
G03I-720J0D01*
G37*
G36*
G01X1498417D02*
G03I-720J0D01*
G37*
G36*
G01X1503717Y1616788D02*
G03I-720J0D01*
G37*
G36*
G01X1508673D02*
G03I-720J0D01*
G37*
G36*
G01X1503717Y1604876D02*
G03I-720J0D01*
G37*
G36*
G01Y1611796D02*
G03I-720J0D01*
G37*
G36*
G01X1508673Y1604876D02*
G03I-720J0D01*
G37*
G36*
G01Y1611796D02*
G03I-720J0D01*
G37*
G36*
G01X1496613Y1604876D02*
G03I-720J0D01*
G37*
G36*
G01Y1611796D02*
G03I-720J0D01*
G37*
G36*
G01Y1616788D02*
G03I-720J0D01*
G37*
G36*
G01X1519369Y266253D02*
X1522742D01*
X1523395Y265600D01*
Y263907D01*
X1526285Y261017D01*
X1544665D01*
X1547950Y257732D01*
Y253002D01*
X1547530Y252582D01*
X1539120D01*
X1535265Y256437D01*
X1525717D01*
G03X1525323Y256587I-905J-1786D01*
G01X1525271Y256601D01*
X1521090Y260782D01*
X1519560D01*
X1518850Y261492D01*
Y265734D01*
X1519369Y266253D01*
G37*
G36*
G01X1524339Y292687D02*
X1535655D01*
X1537050Y291292D01*
X1543720D01*
X1544428Y292000D01*
Y293236D01*
Y298896D01*
X1543450Y299874D01*
X1540342D01*
X1540334Y299882D01*
X1539804D01*
X1539409Y300277D01*
X1518810D01*
X1518745Y300212D01*
X1516774D01*
X1516436Y299874D01*
X1514881Y298319D01*
X1514309D01*
X1514094D01*
X1512483D01*
X1512321Y298157D01*
Y297400D01*
Y297307D01*
X1512500Y297128D01*
X1517648D01*
X1520369Y294407D01*
X1522619D01*
X1524339Y292687D01*
G37*
G36*
G01X1512407Y301287D02*
Y302121D01*
Y302209D01*
X1512524Y302326D01*
X1516722D01*
X1518358Y303962D01*
Y304253D01*
Y307856D01*
Y310456D01*
Y314456D01*
X1518958Y315056D01*
X1537858D01*
X1538738Y314176D01*
Y309676D01*
Y307756D01*
Y302046D01*
X1537969Y301277D01*
X1518430D01*
X1518400Y301247D01*
X1518323D01*
X1512447D01*
X1512407Y301287D01*
G37*
G36*
G01X1524086Y1111204D02*
X1524486Y1111061D01*
Y1110311D01*
X1524086Y1110169D01*
X1523886D01*
Y1111204D01*
X1524086D01*
G37*
G36*
G01X1523686Y1111344D02*
X1523286Y1111487D01*
Y1112237D01*
X1523686Y1112379D01*
X1523886D01*
Y1111344D01*
X1523686D01*
G37*
G36*
G01Y1108994D02*
X1523286Y1109137D01*
Y1109887D01*
X1523686Y1110029D01*
X1523886D01*
Y1108994D01*
X1523686D01*
G37*
G36*
G01X1524086Y1108854D02*
X1524486Y1108711D01*
Y1107961D01*
X1524086Y1107819D01*
X1523886D01*
Y1108854D01*
X1524086D01*
G37*
G36*
G01X1524886Y1111344D02*
X1524486Y1111487D01*
Y1112237D01*
X1524886Y1112379D01*
X1525086D01*
Y1111344D01*
X1524886D01*
G37*
G36*
G01X1525286Y1111204D02*
X1525686Y1111061D01*
Y1110311D01*
X1525286Y1110169D01*
X1525086D01*
Y1111204D01*
X1525286D01*
G37*
G36*
G01X1524886Y1108994D02*
X1524486Y1109137D01*
Y1109887D01*
X1524886Y1110029D01*
X1525086D01*
Y1108994D01*
X1524886D01*
G37*
G36*
G01X1525286Y1108854D02*
X1525686Y1108711D01*
Y1107961D01*
X1525286Y1107819D01*
X1525086D01*
Y1108854D01*
X1525286D01*
G37*
G36*
G01X1524086Y1113554D02*
X1524486Y1113411D01*
Y1112661D01*
X1524086Y1112519D01*
X1523886D01*
Y1113554D01*
X1524086D01*
G37*
G36*
G01Y1115904D02*
X1524486Y1115761D01*
Y1115011D01*
X1524086Y1114869D01*
X1523886D01*
Y1115904D01*
X1524086D01*
G37*
G36*
G01Y1118254D02*
X1524486Y1118111D01*
Y1117361D01*
X1524086Y1117219D01*
X1523886D01*
Y1118254D01*
X1524086D01*
G37*
G36*
G01X1523686Y1113694D02*
X1523286Y1113837D01*
Y1114587D01*
X1523686Y1114729D01*
X1523886D01*
Y1113694D01*
X1523686D01*
G37*
G36*
G01Y1116044D02*
X1523286Y1116187D01*
Y1116937D01*
X1523686Y1117079D01*
X1523886D01*
Y1116044D01*
X1523686D01*
G37*
G36*
G01Y1127794D02*
X1523286Y1127937D01*
Y1128687D01*
X1523686Y1128829D01*
X1523886D01*
Y1127794D01*
X1523686D01*
G37*
G36*
G01Y1118394D02*
X1523286Y1118537D01*
Y1119287D01*
X1523686Y1119429D01*
X1523886D01*
Y1118394D01*
X1523686D01*
G37*
G36*
G01X1524086Y1127654D02*
X1524486Y1127511D01*
Y1126761D01*
X1524086Y1126619D01*
X1523886D01*
Y1127654D01*
X1524086D01*
G37*
G36*
G01Y1120604D02*
X1524486Y1120461D01*
Y1119711D01*
X1524086Y1119569D01*
X1523886D01*
Y1120604D01*
X1524086D01*
G37*
G36*
G01Y1122954D02*
X1524486Y1122811D01*
Y1122061D01*
X1524086Y1121919D01*
X1523886D01*
Y1122954D01*
X1524086D01*
G37*
G36*
G01Y1125304D02*
X1524486Y1125161D01*
Y1124411D01*
X1524086Y1124269D01*
X1523886D01*
Y1125304D01*
X1524086D01*
G37*
G36*
G01X1523686Y1125444D02*
X1523286Y1125587D01*
Y1126337D01*
X1523686Y1126479D01*
X1523886D01*
Y1125444D01*
X1523686D01*
G37*
G36*
G01Y1120744D02*
X1523286Y1120887D01*
Y1121637D01*
X1523686Y1121779D01*
X1523886D01*
Y1120744D01*
X1523686D01*
G37*
G36*
G01Y1123094D02*
X1523286Y1123237D01*
Y1123987D01*
X1523686Y1124129D01*
X1523886D01*
Y1123094D01*
X1523686D01*
G37*
G36*
G01X1525286Y1113554D02*
X1525686Y1113411D01*
Y1112661D01*
X1525286Y1112519D01*
X1525086D01*
Y1113554D01*
X1525286D01*
G37*
G36*
G01Y1115904D02*
X1525686Y1115761D01*
Y1115011D01*
X1525286Y1114869D01*
X1525086D01*
Y1115904D01*
X1525286D01*
G37*
G36*
G01Y1118254D02*
X1525686Y1118111D01*
Y1117361D01*
X1525286Y1117219D01*
X1525086D01*
Y1118254D01*
X1525286D01*
G37*
G36*
G01X1524886Y1113694D02*
X1524486Y1113837D01*
Y1114587D01*
X1524886Y1114729D01*
X1525086D01*
Y1113694D01*
X1524886D01*
G37*
G36*
G01Y1116044D02*
X1524486Y1116187D01*
Y1116937D01*
X1524886Y1117079D01*
X1525086D01*
Y1116044D01*
X1524886D01*
G37*
G36*
G01Y1127794D02*
X1524486Y1127937D01*
Y1128687D01*
X1524886Y1128829D01*
X1525086D01*
Y1127794D01*
X1524886D01*
G37*
G36*
G01X1525286Y1127654D02*
X1525686Y1127511D01*
Y1126761D01*
X1525286Y1126619D01*
X1525086D01*
Y1127654D01*
X1525286D01*
G37*
G36*
G01X1524886Y1125444D02*
X1524486Y1125587D01*
Y1126337D01*
X1524886Y1126479D01*
X1525086D01*
Y1125444D01*
X1524886D01*
G37*
G36*
G01X1525286Y1120604D02*
X1525686Y1120461D01*
Y1119711D01*
X1525286Y1119569D01*
X1525086D01*
Y1120604D01*
X1525286D01*
G37*
G36*
G01Y1122954D02*
X1525686Y1122811D01*
Y1122061D01*
X1525286Y1121919D01*
X1525086D01*
Y1122954D01*
X1525286D01*
G37*
G36*
G01Y1125304D02*
X1525686Y1125161D01*
Y1124411D01*
X1525286Y1124269D01*
X1525086D01*
Y1125304D01*
X1525286D01*
G37*
G36*
G01X1524886Y1120744D02*
X1524486Y1120887D01*
Y1121637D01*
X1524886Y1121779D01*
X1525086D01*
Y1120744D01*
X1524886D01*
G37*
G36*
G01Y1123094D02*
X1524486Y1123237D01*
Y1123987D01*
X1524886Y1124129D01*
X1525086D01*
Y1123094D01*
X1524886D01*
G37*
G36*
G01Y1118394D02*
X1524486Y1118537D01*
Y1119287D01*
X1524886Y1119429D01*
X1525086D01*
Y1118394D01*
X1524886D01*
G37*
G36*
G01X1524086Y1130004D02*
X1524486Y1129861D01*
Y1129111D01*
X1524086Y1128969D01*
X1523886D01*
Y1130004D01*
X1524086D01*
G37*
G36*
G01Y1132354D02*
X1524486Y1132211D01*
Y1131461D01*
X1524086Y1131319D01*
X1523886D01*
Y1132354D01*
X1524086D01*
G37*
G36*
G01Y1134704D02*
X1524486Y1134561D01*
Y1133811D01*
X1524086Y1133669D01*
X1523886D01*
Y1134704D01*
X1524086D01*
G37*
G36*
G01X1523686Y1132494D02*
X1523286Y1132637D01*
Y1133387D01*
X1523686Y1133529D01*
X1523886D01*
Y1132494D01*
X1523686D01*
G37*
G36*
G01Y1130144D02*
X1523286Y1130287D01*
Y1131037D01*
X1523686Y1131179D01*
X1523886D01*
Y1130144D01*
X1523686D01*
G37*
G36*
G01X1524086Y1144104D02*
X1524486Y1143961D01*
Y1143211D01*
X1524086Y1143069D01*
X1523886D01*
Y1144104D01*
X1524086D01*
G37*
G36*
G01Y1141754D02*
X1524486Y1141611D01*
Y1140861D01*
X1524086Y1140719D01*
X1523886D01*
Y1141754D01*
X1524086D01*
G37*
G36*
G01X1523686Y1144244D02*
X1523286Y1144387D01*
Y1145137D01*
X1523686Y1145279D01*
X1523886D01*
Y1144244D01*
X1523686D01*
G37*
G36*
G01Y1141894D02*
X1523286Y1142037D01*
Y1142787D01*
X1523686Y1142929D01*
X1523886D01*
Y1141894D01*
X1523686D01*
G37*
G36*
G01Y1134844D02*
X1523286Y1134987D01*
Y1135737D01*
X1523686Y1135879D01*
X1523886D01*
Y1134844D01*
X1523686D01*
G37*
G36*
G01X1524086Y1139404D02*
X1524486Y1139261D01*
Y1138511D01*
X1524086Y1138369D01*
X1523886D01*
Y1139404D01*
X1524086D01*
G37*
G36*
G01X1523686Y1137194D02*
X1523286Y1137337D01*
Y1138087D01*
X1523686Y1138229D01*
X1523886D01*
Y1137194D01*
X1523686D01*
G37*
G36*
G01Y1139544D02*
X1523286Y1139687D01*
Y1140437D01*
X1523686Y1140579D01*
X1523886D01*
Y1139544D01*
X1523686D01*
G37*
G36*
G01X1524086Y1137054D02*
X1524486Y1136911D01*
Y1136161D01*
X1524086Y1136019D01*
X1523886D01*
Y1137054D01*
X1524086D01*
G37*
G36*
G01X1525286Y1130004D02*
X1525686Y1129861D01*
Y1129111D01*
X1525286Y1128969D01*
X1525086D01*
Y1130004D01*
X1525286D01*
G37*
G36*
G01Y1132354D02*
X1525686Y1132211D01*
Y1131461D01*
X1525286Y1131319D01*
X1525086D01*
Y1132354D01*
X1525286D01*
G37*
G36*
G01Y1134704D02*
X1525686Y1134561D01*
Y1133811D01*
X1525286Y1133669D01*
X1525086D01*
Y1134704D01*
X1525286D01*
G37*
G36*
G01X1524886Y1132494D02*
X1524486Y1132637D01*
Y1133387D01*
X1524886Y1133529D01*
X1525086D01*
Y1132494D01*
X1524886D01*
G37*
G36*
G01Y1130144D02*
X1524486Y1130287D01*
Y1131037D01*
X1524886Y1131179D01*
X1525086D01*
Y1130144D01*
X1524886D01*
G37*
G36*
G01X1525286Y1144104D02*
X1525686Y1143961D01*
Y1143211D01*
X1525286Y1143069D01*
X1525086D01*
Y1144104D01*
X1525286D01*
G37*
G36*
G01Y1141754D02*
X1525686Y1141611D01*
Y1140861D01*
X1525286Y1140719D01*
X1525086D01*
Y1141754D01*
X1525286D01*
G37*
G36*
G01X1524886Y1141894D02*
X1524486Y1142037D01*
Y1142787D01*
X1524886Y1142929D01*
X1525086D01*
Y1141894D01*
X1524886D01*
G37*
G36*
G01Y1144244D02*
X1524486Y1144387D01*
Y1145137D01*
X1524886Y1145279D01*
X1525086D01*
Y1144244D01*
X1524886D01*
G37*
G36*
G01Y1134844D02*
X1524486Y1134987D01*
Y1135737D01*
X1524886Y1135879D01*
X1525086D01*
Y1134844D01*
X1524886D01*
G37*
G36*
G01X1525286Y1137054D02*
X1525686Y1136911D01*
Y1136161D01*
X1525286Y1136019D01*
X1525086D01*
Y1137054D01*
X1525286D01*
G37*
G36*
G01Y1139404D02*
X1525686Y1139261D01*
Y1138511D01*
X1525286Y1138369D01*
X1525086D01*
Y1139404D01*
X1525286D01*
G37*
G36*
G01X1524886Y1137194D02*
X1524486Y1137337D01*
Y1138087D01*
X1524886Y1138229D01*
X1525086D01*
Y1137194D01*
X1524886D01*
G37*
G36*
G01Y1139544D02*
X1524486Y1139687D01*
Y1140437D01*
X1524886Y1140579D01*
X1525086D01*
Y1139544D01*
X1524886D01*
G37*
G36*
G01X1524086Y1148804D02*
X1524486Y1148661D01*
Y1147911D01*
X1524086Y1147769D01*
X1523886D01*
Y1148804D01*
X1524086D01*
G37*
G36*
G01Y1146454D02*
X1524486Y1146311D01*
Y1145561D01*
X1524086Y1145419D01*
X1523886D01*
Y1146454D01*
X1524086D01*
G37*
G36*
G01X1523686Y1146594D02*
X1523286Y1146737D01*
Y1147487D01*
X1523686Y1147629D01*
X1523886D01*
Y1146594D01*
X1523686D01*
G37*
G36*
G01Y1151294D02*
X1523286Y1151437D01*
Y1152187D01*
X1523686Y1152329D01*
X1523886D01*
Y1151294D01*
X1523686D01*
G37*
G36*
G01Y1148944D02*
X1523286Y1149087D01*
Y1149837D01*
X1523686Y1149979D01*
X1523886D01*
Y1148944D01*
X1523686D01*
G37*
G36*
G01X1524086Y1151154D02*
X1524486Y1151011D01*
Y1150261D01*
X1524086Y1150119D01*
X1523886D01*
Y1151154D01*
X1524086D01*
G37*
G36*
G01Y1160554D02*
X1524486Y1160411D01*
Y1159661D01*
X1524086Y1159519D01*
X1523886D01*
Y1160554D01*
X1524086D01*
G37*
G36*
G01X1523686Y1160694D02*
X1523286Y1160837D01*
Y1161587D01*
X1523686Y1161729D01*
X1523886D01*
Y1160694D01*
X1523686D01*
G37*
G36*
G01X1524086Y1158204D02*
X1524486Y1158061D01*
Y1157311D01*
X1524086Y1157169D01*
X1523886D01*
Y1158204D01*
X1524086D01*
G37*
G36*
G01X1523686Y1158344D02*
X1523286Y1158487D01*
Y1159237D01*
X1523686Y1159379D01*
X1523886D01*
Y1158344D01*
X1523686D01*
G37*
G36*
G01X1524086Y1155854D02*
X1524486Y1155711D01*
Y1154961D01*
X1524086Y1154819D01*
X1523886D01*
Y1155854D01*
X1524086D01*
G37*
G36*
G01X1523686Y1155994D02*
X1523286Y1156137D01*
Y1156887D01*
X1523686Y1157029D01*
X1523886D01*
Y1155994D01*
X1523686D01*
G37*
G36*
G01X1524086Y1153504D02*
X1524486Y1153361D01*
Y1152611D01*
X1524086Y1152469D01*
X1523886D01*
Y1153504D01*
X1524086D01*
G37*
G36*
G01X1523686Y1153644D02*
X1523286Y1153787D01*
Y1154537D01*
X1523686Y1154679D01*
X1523886D01*
Y1153644D01*
X1523686D01*
G37*
G36*
G01X1525286Y1148804D02*
X1525686Y1148661D01*
Y1147911D01*
X1525286Y1147769D01*
X1525086D01*
Y1148804D01*
X1525286D01*
G37*
G36*
G01Y1146454D02*
X1525686Y1146311D01*
Y1145561D01*
X1525286Y1145419D01*
X1525086D01*
Y1146454D01*
X1525286D01*
G37*
G36*
G01X1524886Y1146594D02*
X1524486Y1146737D01*
Y1147487D01*
X1524886Y1147629D01*
X1525086D01*
Y1146594D01*
X1524886D01*
G37*
G36*
G01Y1151294D02*
X1524486Y1151437D01*
Y1152187D01*
X1524886Y1152329D01*
X1525086D01*
Y1151294D01*
X1524886D01*
G37*
G36*
G01Y1148944D02*
X1524486Y1149087D01*
Y1149837D01*
X1524886Y1149979D01*
X1525086D01*
Y1148944D01*
X1524886D01*
G37*
G36*
G01X1525286Y1151154D02*
X1525686Y1151011D01*
Y1150261D01*
X1525286Y1150119D01*
X1525086D01*
Y1151154D01*
X1525286D01*
G37*
G36*
G01Y1160554D02*
X1525686Y1160411D01*
Y1159661D01*
X1525286Y1159519D01*
X1525086D01*
Y1160554D01*
X1525286D01*
G37*
G36*
G01X1524886Y1160694D02*
X1524486Y1160837D01*
Y1161587D01*
X1524886Y1161729D01*
X1525086D01*
Y1160694D01*
X1524886D01*
G37*
G36*
G01X1525286Y1158204D02*
X1525686Y1158061D01*
Y1157311D01*
X1525286Y1157169D01*
X1525086D01*
Y1158204D01*
X1525286D01*
G37*
G36*
G01X1524886Y1158344D02*
X1524486Y1158487D01*
Y1159237D01*
X1524886Y1159379D01*
X1525086D01*
Y1158344D01*
X1524886D01*
G37*
G36*
G01X1525286Y1155854D02*
X1525686Y1155711D01*
Y1154961D01*
X1525286Y1154819D01*
X1525086D01*
Y1155854D01*
X1525286D01*
G37*
G36*
G01X1524886Y1155994D02*
X1524486Y1156137D01*
Y1156887D01*
X1524886Y1157029D01*
X1525086D01*
Y1155994D01*
X1524886D01*
G37*
G36*
G01X1525286Y1153504D02*
X1525686Y1153361D01*
Y1152611D01*
X1525286Y1152469D01*
X1525086D01*
Y1153504D01*
X1525286D01*
G37*
G36*
G01X1524886Y1153644D02*
X1524486Y1153787D01*
Y1154537D01*
X1524886Y1154679D01*
X1525086D01*
Y1153644D01*
X1524886D01*
G37*
G36*
G01X1524086Y1162904D02*
X1524486Y1162761D01*
Y1162011D01*
X1524086Y1161869D01*
X1523886D01*
Y1162904D01*
X1524086D01*
G37*
G36*
G01X1523686Y1163044D02*
X1523286Y1163187D01*
Y1163937D01*
X1523686Y1164079D01*
X1523886D01*
Y1163044D01*
X1523686D01*
G37*
G36*
G01X1525286Y1162904D02*
X1525686Y1162761D01*
Y1162011D01*
X1525286Y1161869D01*
X1525086D01*
Y1162904D01*
X1525286D01*
G37*
G36*
G01X1522537Y1580678D02*
G03I-720J0D01*
G37*
G36*
G01Y1575686D02*
G03I-720J0D01*
G37*
G36*
G01X1515433D02*
G03I-720J0D01*
G37*
G36*
G01Y1580678D02*
G03I-720J0D01*
G37*
G36*
G01X1520733Y1599884D02*
G03I-720J0D01*
G37*
G36*
G01X1515777D02*
G03I-720J0D01*
G37*
G36*
G01X1522537Y1592590D02*
G03I-720J0D01*
G37*
G36*
G01Y1587598D02*
G03I-720J0D01*
G37*
G36*
G01X1515433D02*
G03I-720J0D01*
G37*
G36*
G01Y1592590D02*
G03I-720J0D01*
G37*
G36*
G01X1520733Y1604876D02*
G03I-720J0D01*
G37*
G36*
G01X1515777D02*
G03I-720J0D01*
G37*
G36*
G01X1520733Y1611796D02*
G03I-720J0D01*
G37*
G36*
G01X1515777D02*
G03I-720J0D01*
G37*
G36*
G01Y1616788D02*
G03I-720J0D01*
G37*
G36*
G01X1520733D02*
G03I-720J0D01*
G37*
G36*
G01X1535538Y66801D02*
G03I-720J0D01*
G37*
G36*
G01X1540494D02*
G03I-720J0D01*
G37*
G36*
G01X1542494Y69297D02*
G03I-720J0D01*
G37*
G36*
G01X1533538D02*
G03I-720J0D01*
G37*
G36*
G01X1535538Y71793D02*
G03I-720J0D01*
G37*
G36*
G01X1540494D02*
G03I-720J0D01*
G37*
G36*
G01X1535494Y103093D02*
G03I-720J0D01*
G37*
G36*
G01X1530538D02*
G03I-720J0D01*
G37*
G36*
G01X1540991Y315291D02*
X1547745D01*
X1549599Y313437D01*
Y302436D01*
X1548929Y301766D01*
X1541049D01*
X1539958Y302857D01*
Y314258D01*
X1540991Y315291D01*
G37*
G36*
G01X1541370Y850614D02*
X1540970Y850757D01*
Y851507D01*
X1541370Y851649D01*
X1541570D01*
Y850614D01*
X1541370D01*
G37*
G36*
G01Y845914D02*
X1540970Y846057D01*
Y846807D01*
X1541370Y846949D01*
X1541570D01*
Y845914D01*
X1541370D01*
G37*
G36*
G01Y848264D02*
X1540970Y848407D01*
Y849157D01*
X1541370Y849299D01*
X1541570D01*
Y848264D01*
X1541370D01*
G37*
G36*
G01X1541770Y848124D02*
X1542170Y847981D01*
Y847231D01*
X1541770Y847089D01*
X1541570D01*
Y848124D01*
X1541770D01*
G37*
G36*
G01Y850474D02*
X1542170Y850331D01*
Y849581D01*
X1541770Y849439D01*
X1541570D01*
Y850474D01*
X1541770D01*
G37*
G36*
G01X1539570D02*
X1539970Y850331D01*
Y849581D01*
X1539570Y849439D01*
X1539370D01*
Y850474D01*
X1539570D01*
G37*
G36*
G01X1539170Y850614D02*
X1538770Y850757D01*
Y851507D01*
X1539170Y851649D01*
X1539370D01*
Y850614D01*
X1539170D01*
G37*
G36*
G01X1536770D02*
X1536370Y850757D01*
Y851507D01*
X1536770Y851649D01*
X1536970D01*
Y850614D01*
X1536770D01*
G37*
G36*
G01X1537170Y850474D02*
X1537570Y850331D01*
Y849581D01*
X1537170Y849439D01*
X1536970D01*
Y850474D01*
X1537170D01*
G37*
G36*
G01X1537970Y850614D02*
X1537570Y850757D01*
Y851507D01*
X1537970Y851649D01*
X1538170D01*
Y850614D01*
X1537970D01*
G37*
G36*
G01X1538370Y850474D02*
X1538770Y850331D01*
Y849581D01*
X1538370Y849439D01*
X1538170D01*
Y850474D01*
X1538370D01*
G37*
G36*
G01X1535570Y850614D02*
X1535170Y850757D01*
Y851507D01*
X1535570Y851649D01*
X1535770D01*
Y850614D01*
X1535570D01*
G37*
G36*
G01X1535970Y850474D02*
X1536370Y850331D01*
Y849581D01*
X1535970Y849439D01*
X1535770D01*
Y850474D01*
X1535970D01*
G37*
G36*
G01X1529970Y851255D02*
X1530370Y851113D01*
Y850363D01*
X1529970Y850220D01*
X1529770D01*
Y851255D01*
X1529970D01*
G37*
G36*
G01X1529570Y851395D02*
X1529170Y851537D01*
Y852287D01*
X1529570Y852430D01*
X1529770D01*
Y851395D01*
X1529570D01*
G37*
G36*
G01X1527570Y848905D02*
X1527970Y848763D01*
Y848013D01*
X1527570Y847870D01*
X1527370D01*
Y848905D01*
X1527570D01*
G37*
G36*
G01X1527170Y849045D02*
X1526770Y849187D01*
Y849937D01*
X1527170Y850080D01*
X1527370D01*
Y849045D01*
X1527170D01*
G37*
G36*
G01X1527570Y851255D02*
X1527970Y851113D01*
Y850363D01*
X1527570Y850220D01*
X1527370D01*
Y851255D01*
X1527570D01*
G37*
G36*
G01X1527170Y851395D02*
X1526770Y851537D01*
Y852287D01*
X1527170Y852430D01*
X1527370D01*
Y851395D01*
X1527170D01*
G37*
G36*
G01X1528770Y848905D02*
X1529170Y848763D01*
Y848013D01*
X1528770Y847870D01*
X1528570D01*
Y848905D01*
X1528770D01*
G37*
G36*
G01X1528370Y851395D02*
X1527970Y851537D01*
Y852287D01*
X1528370Y852430D01*
X1528570D01*
Y851395D01*
X1528370D01*
G37*
G36*
G01Y849045D02*
X1527970Y849187D01*
Y849937D01*
X1528370Y850080D01*
X1528570D01*
Y849045D01*
X1528370D01*
G37*
G36*
G01X1528770Y851255D02*
X1529170Y851113D01*
Y850363D01*
X1528770Y850220D01*
X1528570D01*
Y851255D01*
X1528770D01*
G37*
G36*
G01X1526370D02*
X1526770Y851113D01*
Y850363D01*
X1526370Y850220D01*
X1526170D01*
Y851255D01*
X1526370D01*
G37*
G36*
G01X1525970Y851395D02*
X1525570Y851537D01*
Y852287D01*
X1525970Y852430D01*
X1526170D01*
Y851395D01*
X1525970D01*
G37*
G36*
G01Y849045D02*
X1525570Y849187D01*
Y849937D01*
X1525970Y850080D01*
X1526170D01*
Y849045D01*
X1525970D01*
G37*
G36*
G01X1541370Y855314D02*
X1540970Y855457D01*
Y856207D01*
X1541370Y856349D01*
X1541570D01*
Y855314D01*
X1541370D01*
G37*
G36*
G01Y857664D02*
X1540970Y857807D01*
Y858557D01*
X1541370Y858699D01*
X1541570D01*
Y857664D01*
X1541370D01*
G37*
G36*
G01Y860014D02*
X1540970Y860157D01*
Y860907D01*
X1541370Y861049D01*
X1541570D01*
Y860014D01*
X1541370D01*
G37*
G36*
G01X1541770Y855174D02*
X1542170Y855031D01*
Y854281D01*
X1541770Y854139D01*
X1541570D01*
Y855174D01*
X1541770D01*
G37*
G36*
G01Y857524D02*
X1542170Y857381D01*
Y856631D01*
X1541770Y856489D01*
X1541570D01*
Y857524D01*
X1541770D01*
G37*
G36*
G01Y859874D02*
X1542170Y859731D01*
Y858981D01*
X1541770Y858839D01*
X1541570D01*
Y859874D01*
X1541770D01*
G37*
G36*
G01Y862224D02*
X1542170Y862081D01*
Y861331D01*
X1541770Y861189D01*
X1541570D01*
Y862224D01*
X1541770D01*
G37*
G36*
G01X1541370Y852964D02*
X1540970Y853107D01*
Y853857D01*
X1541370Y853999D01*
X1541570D01*
Y852964D01*
X1541370D01*
G37*
G36*
G01X1541770Y852824D02*
X1542170Y852681D01*
Y851931D01*
X1541770Y851789D01*
X1541570D01*
Y852824D01*
X1541770D01*
G37*
G36*
G01X1541370Y867064D02*
X1540970Y867207D01*
Y867957D01*
X1541370Y868099D01*
X1541570D01*
Y867064D01*
X1541370D01*
G37*
G36*
G01Y862364D02*
X1540970Y862507D01*
Y863257D01*
X1541370Y863399D01*
X1541570D01*
Y862364D01*
X1541370D01*
G37*
G36*
G01Y864714D02*
X1540970Y864857D01*
Y865607D01*
X1541370Y865749D01*
X1541570D01*
Y864714D01*
X1541370D01*
G37*
G36*
G01X1541770Y864574D02*
X1542170Y864431D01*
Y863681D01*
X1541770Y863539D01*
X1541570D01*
Y864574D01*
X1541770D01*
G37*
G36*
G01Y866924D02*
X1542170Y866781D01*
Y866031D01*
X1541770Y865889D01*
X1541570D01*
Y866924D01*
X1541770D01*
G37*
G36*
G01X1539170Y852964D02*
X1538770Y853107D01*
Y853857D01*
X1539170Y853999D01*
X1539370D01*
Y852964D01*
X1539170D01*
G37*
G36*
G01X1539570Y862224D02*
X1539970Y862081D01*
Y861331D01*
X1539570Y861189D01*
X1539370D01*
Y862224D01*
X1539570D01*
G37*
G36*
G01Y859874D02*
X1539970Y859731D01*
Y858981D01*
X1539570Y858839D01*
X1539370D01*
Y859874D01*
X1539570D01*
G37*
G36*
G01Y857524D02*
X1539970Y857381D01*
Y856631D01*
X1539570Y856489D01*
X1539370D01*
Y857524D01*
X1539570D01*
G37*
G36*
G01Y855174D02*
X1539970Y855031D01*
Y854281D01*
X1539570Y854139D01*
X1539370D01*
Y855174D01*
X1539570D01*
G37*
G36*
G01X1539170Y860014D02*
X1538770Y860157D01*
Y860907D01*
X1539170Y861049D01*
X1539370D01*
Y860014D01*
X1539170D01*
G37*
G36*
G01Y857664D02*
X1538770Y857807D01*
Y858557D01*
X1539170Y858699D01*
X1539370D01*
Y857664D01*
X1539170D01*
G37*
G36*
G01Y855314D02*
X1538770Y855457D01*
Y856207D01*
X1539170Y856349D01*
X1539370D01*
Y855314D01*
X1539170D01*
G37*
G36*
G01X1539570Y866924D02*
X1539970Y866781D01*
Y866031D01*
X1539570Y865889D01*
X1539370D01*
Y866924D01*
X1539570D01*
G37*
G36*
G01Y864574D02*
X1539970Y864431D01*
Y863681D01*
X1539570Y863539D01*
X1539370D01*
Y864574D01*
X1539570D01*
G37*
G36*
G01X1539170Y862364D02*
X1538770Y862507D01*
Y863257D01*
X1539170Y863399D01*
X1539370D01*
Y862364D01*
X1539170D01*
G37*
G36*
G01Y864714D02*
X1538770Y864857D01*
Y865607D01*
X1539170Y865749D01*
X1539370D01*
Y864714D01*
X1539170D01*
G37*
G36*
G01Y867064D02*
X1538770Y867207D01*
Y867957D01*
X1539170Y868099D01*
X1539370D01*
Y867064D01*
X1539170D01*
G37*
G36*
G01X1539570Y852824D02*
X1539970Y852681D01*
Y851931D01*
X1539570Y851789D01*
X1539370D01*
Y852824D01*
X1539570D01*
G37*
G36*
G01X1536770Y867064D02*
X1536370Y867207D01*
Y867957D01*
X1536770Y868099D01*
X1536970D01*
Y867064D01*
X1536770D01*
G37*
G36*
G01Y862364D02*
X1536370Y862507D01*
Y863257D01*
X1536770Y863399D01*
X1536970D01*
Y862364D01*
X1536770D01*
G37*
G36*
G01Y864714D02*
X1536370Y864857D01*
Y865607D01*
X1536770Y865749D01*
X1536970D01*
Y864714D01*
X1536770D01*
G37*
G36*
G01X1537170Y866924D02*
X1537570Y866781D01*
Y866031D01*
X1537170Y865889D01*
X1536970D01*
Y866924D01*
X1537170D01*
G37*
G36*
G01Y864574D02*
X1537570Y864431D01*
Y863681D01*
X1537170Y863539D01*
X1536970D01*
Y864574D01*
X1537170D01*
G37*
G36*
G01X1536770Y855314D02*
X1536370Y855457D01*
Y856207D01*
X1536770Y856349D01*
X1536970D01*
Y855314D01*
X1536770D01*
G37*
G36*
G01Y857664D02*
X1536370Y857807D01*
Y858557D01*
X1536770Y858699D01*
X1536970D01*
Y857664D01*
X1536770D01*
G37*
G36*
G01Y860014D02*
X1536370Y860157D01*
Y860907D01*
X1536770Y861049D01*
X1536970D01*
Y860014D01*
X1536770D01*
G37*
G36*
G01X1537170Y855174D02*
X1537570Y855031D01*
Y854281D01*
X1537170Y854139D01*
X1536970D01*
Y855174D01*
X1537170D01*
G37*
G36*
G01Y857524D02*
X1537570Y857381D01*
Y856631D01*
X1537170Y856489D01*
X1536970D01*
Y857524D01*
X1537170D01*
G37*
G36*
G01Y859874D02*
X1537570Y859731D01*
Y858981D01*
X1537170Y858839D01*
X1536970D01*
Y859874D01*
X1537170D01*
G37*
G36*
G01Y862224D02*
X1537570Y862081D01*
Y861331D01*
X1537170Y861189D01*
X1536970D01*
Y862224D01*
X1537170D01*
G37*
G36*
G01X1536770Y852964D02*
X1536370Y853107D01*
Y853857D01*
X1536770Y853999D01*
X1536970D01*
Y852964D01*
X1536770D01*
G37*
G36*
G01X1537170Y852824D02*
X1537570Y852681D01*
Y851931D01*
X1537170Y851789D01*
X1536970D01*
Y852824D01*
X1537170D01*
G37*
G36*
G01X1538370Y855174D02*
X1538770Y855031D01*
Y854281D01*
X1538370Y854139D01*
X1538170D01*
Y855174D01*
X1538370D01*
G37*
G36*
G01Y857524D02*
X1538770Y857381D01*
Y856631D01*
X1538370Y856489D01*
X1538170D01*
Y857524D01*
X1538370D01*
G37*
G36*
G01Y859874D02*
X1538770Y859731D01*
Y858981D01*
X1538370Y858839D01*
X1538170D01*
Y859874D01*
X1538370D01*
G37*
G36*
G01Y862224D02*
X1538770Y862081D01*
Y861331D01*
X1538370Y861189D01*
X1538170D01*
Y862224D01*
X1538370D01*
G37*
G36*
G01Y852824D02*
X1538770Y852681D01*
Y851931D01*
X1538370Y851789D01*
X1538170D01*
Y852824D01*
X1538370D01*
G37*
G36*
G01X1537970Y855314D02*
X1537570Y855457D01*
Y856207D01*
X1537970Y856349D01*
X1538170D01*
Y855314D01*
X1537970D01*
G37*
G36*
G01Y857664D02*
X1537570Y857807D01*
Y858557D01*
X1537970Y858699D01*
X1538170D01*
Y857664D01*
X1537970D01*
G37*
G36*
G01Y860014D02*
X1537570Y860157D01*
Y860907D01*
X1537970Y861049D01*
X1538170D01*
Y860014D01*
X1537970D01*
G37*
G36*
G01Y852964D02*
X1537570Y853107D01*
Y853857D01*
X1537970Y853999D01*
X1538170D01*
Y852964D01*
X1537970D01*
G37*
G36*
G01Y867064D02*
X1537570Y867207D01*
Y867957D01*
X1537970Y868099D01*
X1538170D01*
Y867064D01*
X1537970D01*
G37*
G36*
G01X1538370Y864574D02*
X1538770Y864431D01*
Y863681D01*
X1538370Y863539D01*
X1538170D01*
Y864574D01*
X1538370D01*
G37*
G36*
G01Y866924D02*
X1538770Y866781D01*
Y866031D01*
X1538370Y865889D01*
X1538170D01*
Y866924D01*
X1538370D01*
G37*
G36*
G01X1537970Y862364D02*
X1537570Y862507D01*
Y863257D01*
X1537970Y863399D01*
X1538170D01*
Y862364D01*
X1537970D01*
G37*
G36*
G01Y864714D02*
X1537570Y864857D01*
Y865607D01*
X1537970Y865749D01*
X1538170D01*
Y864714D01*
X1537970D01*
G37*
G36*
G01X1535970Y855174D02*
X1536370Y855031D01*
Y854281D01*
X1535970Y854139D01*
X1535770D01*
Y855174D01*
X1535970D01*
G37*
G36*
G01Y857524D02*
X1536370Y857381D01*
Y856631D01*
X1535970Y856489D01*
X1535770D01*
Y857524D01*
X1535970D01*
G37*
G36*
G01Y859874D02*
X1536370Y859731D01*
Y858981D01*
X1535970Y858839D01*
X1535770D01*
Y859874D01*
X1535970D01*
G37*
G36*
G01Y862224D02*
X1536370Y862081D01*
Y861331D01*
X1535970Y861189D01*
X1535770D01*
Y862224D01*
X1535970D01*
G37*
G36*
G01X1535570Y855314D02*
X1535170Y855457D01*
Y856207D01*
X1535570Y856349D01*
X1535770D01*
Y855314D01*
X1535570D01*
G37*
G36*
G01Y857664D02*
X1535170Y857807D01*
Y858557D01*
X1535570Y858699D01*
X1535770D01*
Y857664D01*
X1535570D01*
G37*
G36*
G01Y860014D02*
X1535170Y860157D01*
Y860907D01*
X1535570Y861049D01*
X1535770D01*
Y860014D01*
X1535570D01*
G37*
G36*
G01X1535970Y852824D02*
X1536370Y852681D01*
Y851931D01*
X1535970Y851789D01*
X1535770D01*
Y852824D01*
X1535970D01*
G37*
G36*
G01X1535570Y852964D02*
X1535170Y853107D01*
Y853857D01*
X1535570Y853999D01*
X1535770D01*
Y852964D01*
X1535570D01*
G37*
G36*
G01Y867064D02*
X1535170Y867207D01*
Y867957D01*
X1535570Y868099D01*
X1535770D01*
Y867064D01*
X1535570D01*
G37*
G36*
G01X1535970Y866924D02*
X1536370Y866781D01*
Y866031D01*
X1535970Y865889D01*
X1535770D01*
Y866924D01*
X1535970D01*
G37*
G36*
G01Y864574D02*
X1536370Y864431D01*
Y863681D01*
X1535970Y863539D01*
X1535770D01*
Y864574D01*
X1535970D01*
G37*
G36*
G01X1535570Y862364D02*
X1535170Y862507D01*
Y863257D01*
X1535570Y863399D01*
X1535770D01*
Y862364D01*
X1535570D01*
G37*
G36*
G01Y864714D02*
X1535170Y864857D01*
Y865607D01*
X1535570Y865749D01*
X1535770D01*
Y864714D01*
X1535570D01*
G37*
G36*
G01X1529970Y855955D02*
X1530370Y855813D01*
Y855063D01*
X1529970Y854920D01*
X1529770D01*
Y855955D01*
X1529970D01*
G37*
G36*
G01Y858305D02*
X1530370Y858163D01*
Y857413D01*
X1529970Y857270D01*
X1529770D01*
Y858305D01*
X1529970D01*
G37*
G36*
G01Y860655D02*
X1530370Y860513D01*
Y859763D01*
X1529970Y859620D01*
X1529770D01*
Y860655D01*
X1529970D01*
G37*
G36*
G01X1529570Y853745D02*
X1529170Y853887D01*
Y854637D01*
X1529570Y854780D01*
X1529770D01*
Y853745D01*
X1529570D01*
G37*
G36*
G01Y856095D02*
X1529170Y856237D01*
Y856987D01*
X1529570Y857130D01*
X1529770D01*
Y856095D01*
X1529570D01*
G37*
G36*
G01Y858445D02*
X1529170Y858587D01*
Y859337D01*
X1529570Y859480D01*
X1529770D01*
Y858445D01*
X1529570D01*
G37*
G36*
G01Y860795D02*
X1529170Y860937D01*
Y861687D01*
X1529570Y861830D01*
X1529770D01*
Y860795D01*
X1529570D01*
G37*
G36*
G01X1529970Y853605D02*
X1530370Y853463D01*
Y852713D01*
X1529970Y852570D01*
X1529770D01*
Y853605D01*
X1529970D01*
G37*
G36*
G01X1529570Y867845D02*
X1529170Y867987D01*
Y868737D01*
X1529570Y868880D01*
X1529770D01*
Y867845D01*
X1529570D01*
G37*
G36*
G01X1529970Y863005D02*
X1530370Y862863D01*
Y862113D01*
X1529970Y861970D01*
X1529770D01*
Y863005D01*
X1529970D01*
G37*
G36*
G01Y865355D02*
X1530370Y865213D01*
Y864463D01*
X1529970Y864320D01*
X1529770D01*
Y865355D01*
X1529970D01*
G37*
G36*
G01Y867705D02*
X1530370Y867563D01*
Y866813D01*
X1529970Y866670D01*
X1529770D01*
Y867705D01*
X1529970D01*
G37*
G36*
G01X1529570Y863145D02*
X1529170Y863287D01*
Y864037D01*
X1529570Y864180D01*
X1529770D01*
Y863145D01*
X1529570D01*
G37*
G36*
G01Y865495D02*
X1529170Y865637D01*
Y866387D01*
X1529570Y866530D01*
X1529770D01*
Y865495D01*
X1529570D01*
G37*
G36*
G01X1527570Y853605D02*
X1527970Y853463D01*
Y852713D01*
X1527570Y852570D01*
X1527370D01*
Y853605D01*
X1527570D01*
G37*
G36*
G01Y860655D02*
X1527970Y860513D01*
Y859763D01*
X1527570Y859620D01*
X1527370D01*
Y860655D01*
X1527570D01*
G37*
G36*
G01Y858305D02*
X1527970Y858163D01*
Y857413D01*
X1527570Y857270D01*
X1527370D01*
Y858305D01*
X1527570D01*
G37*
G36*
G01Y855955D02*
X1527970Y855813D01*
Y855063D01*
X1527570Y854920D01*
X1527370D01*
Y855955D01*
X1527570D01*
G37*
G36*
G01X1527170Y860795D02*
X1526770Y860937D01*
Y861687D01*
X1527170Y861830D01*
X1527370D01*
Y860795D01*
X1527170D01*
G37*
G36*
G01Y858445D02*
X1526770Y858587D01*
Y859337D01*
X1527170Y859480D01*
X1527370D01*
Y858445D01*
X1527170D01*
G37*
G36*
G01Y856095D02*
X1526770Y856237D01*
Y856987D01*
X1527170Y857130D01*
X1527370D01*
Y856095D01*
X1527170D01*
G37*
G36*
G01Y853745D02*
X1526770Y853887D01*
Y854637D01*
X1527170Y854780D01*
X1527370D01*
Y853745D01*
X1527170D01*
G37*
G36*
G01X1527570Y867705D02*
X1527970Y867563D01*
Y866813D01*
X1527570Y866670D01*
X1527370D01*
Y867705D01*
X1527570D01*
G37*
G36*
G01Y865355D02*
X1527970Y865213D01*
Y864463D01*
X1527570Y864320D01*
X1527370D01*
Y865355D01*
X1527570D01*
G37*
G36*
G01Y863005D02*
X1527970Y862863D01*
Y862113D01*
X1527570Y861970D01*
X1527370D01*
Y863005D01*
X1527570D01*
G37*
G36*
G01X1527170Y865495D02*
X1526770Y865637D01*
Y866387D01*
X1527170Y866530D01*
X1527370D01*
Y865495D01*
X1527170D01*
G37*
G36*
G01Y863145D02*
X1526770Y863287D01*
Y864037D01*
X1527170Y864180D01*
X1527370D01*
Y863145D01*
X1527170D01*
G37*
G36*
G01Y867845D02*
X1526770Y867987D01*
Y868737D01*
X1527170Y868880D01*
X1527370D01*
Y867845D01*
X1527170D01*
G37*
G36*
G01X1528370Y853745D02*
X1527970Y853887D01*
Y854637D01*
X1528370Y854780D01*
X1528570D01*
Y853745D01*
X1528370D01*
G37*
G36*
G01Y856095D02*
X1527970Y856237D01*
Y856987D01*
X1528370Y857130D01*
X1528570D01*
Y856095D01*
X1528370D01*
G37*
G36*
G01Y858445D02*
X1527970Y858587D01*
Y859337D01*
X1528370Y859480D01*
X1528570D01*
Y858445D01*
X1528370D01*
G37*
G36*
G01Y860795D02*
X1527970Y860937D01*
Y861687D01*
X1528370Y861830D01*
X1528570D01*
Y860795D01*
X1528370D01*
G37*
G36*
G01Y867845D02*
X1527970Y867987D01*
Y868737D01*
X1528370Y868880D01*
X1528570D01*
Y867845D01*
X1528370D01*
G37*
G36*
G01Y863145D02*
X1527970Y863287D01*
Y864037D01*
X1528370Y864180D01*
X1528570D01*
Y863145D01*
X1528370D01*
G37*
G36*
G01Y865495D02*
X1527970Y865637D01*
Y866387D01*
X1528370Y866530D01*
X1528570D01*
Y865495D01*
X1528370D01*
G37*
G36*
G01X1528770Y855955D02*
X1529170Y855813D01*
Y855063D01*
X1528770Y854920D01*
X1528570D01*
Y855955D01*
X1528770D01*
G37*
G36*
G01Y858305D02*
X1529170Y858163D01*
Y857413D01*
X1528770Y857270D01*
X1528570D01*
Y858305D01*
X1528770D01*
G37*
G36*
G01Y860655D02*
X1529170Y860513D01*
Y859763D01*
X1528770Y859620D01*
X1528570D01*
Y860655D01*
X1528770D01*
G37*
G36*
G01Y853605D02*
X1529170Y853463D01*
Y852713D01*
X1528770Y852570D01*
X1528570D01*
Y853605D01*
X1528770D01*
G37*
G36*
G01Y863005D02*
X1529170Y862863D01*
Y862113D01*
X1528770Y861970D01*
X1528570D01*
Y863005D01*
X1528770D01*
G37*
G36*
G01Y865355D02*
X1529170Y865213D01*
Y864463D01*
X1528770Y864320D01*
X1528570D01*
Y865355D01*
X1528770D01*
G37*
G36*
G01Y867705D02*
X1529170Y867563D01*
Y866813D01*
X1528770Y866670D01*
X1528570D01*
Y867705D01*
X1528770D01*
G37*
G36*
G01X1525970Y853745D02*
X1525570Y853887D01*
Y854637D01*
X1525970Y854780D01*
X1526170D01*
Y853745D01*
X1525970D01*
G37*
G36*
G01Y856095D02*
X1525570Y856237D01*
Y856987D01*
X1525970Y857130D01*
X1526170D01*
Y856095D01*
X1525970D01*
G37*
G36*
G01Y858445D02*
X1525570Y858587D01*
Y859337D01*
X1525970Y859480D01*
X1526170D01*
Y858445D01*
X1525970D01*
G37*
G36*
G01Y860795D02*
X1525570Y860937D01*
Y861687D01*
X1525970Y861830D01*
X1526170D01*
Y860795D01*
X1525970D01*
G37*
G36*
G01X1526370Y867705D02*
X1526770Y867563D01*
Y866813D01*
X1526370Y866670D01*
X1526170D01*
Y867705D01*
X1526370D01*
G37*
G36*
G01Y863005D02*
X1526770Y862863D01*
Y862113D01*
X1526370Y861970D01*
X1526170D01*
Y863005D01*
X1526370D01*
G37*
G36*
G01Y865355D02*
X1526770Y865213D01*
Y864463D01*
X1526370Y864320D01*
X1526170D01*
Y865355D01*
X1526370D01*
G37*
G36*
G01X1525970Y867845D02*
X1525570Y867987D01*
Y868737D01*
X1525970Y868880D01*
X1526170D01*
Y867845D01*
X1525970D01*
G37*
G36*
G01Y865495D02*
X1525570Y865637D01*
Y866387D01*
X1525970Y866530D01*
X1526170D01*
Y865495D01*
X1525970D01*
G37*
G36*
G01Y863145D02*
X1525570Y863287D01*
Y864037D01*
X1525970Y864180D01*
X1526170D01*
Y863145D01*
X1525970D01*
G37*
G36*
G01X1526370Y855955D02*
X1526770Y855813D01*
Y855063D01*
X1526370Y854920D01*
X1526170D01*
Y855955D01*
X1526370D01*
G37*
G36*
G01Y858305D02*
X1526770Y858163D01*
Y857413D01*
X1526370Y857270D01*
X1526170D01*
Y858305D01*
X1526370D01*
G37*
G36*
G01Y860655D02*
X1526770Y860513D01*
Y859763D01*
X1526370Y859620D01*
X1526170D01*
Y860655D01*
X1526370D01*
G37*
G36*
G01Y853605D02*
X1526770Y853463D01*
Y852713D01*
X1526370Y852570D01*
X1526170D01*
Y853605D01*
X1526370D01*
G37*
G36*
G01X1541770Y883374D02*
X1542170Y883231D01*
Y882481D01*
X1541770Y882339D01*
X1541570D01*
Y883374D01*
X1541770D01*
G37*
G36*
G01X1541370Y883514D02*
X1540970Y883657D01*
Y884407D01*
X1541370Y884549D01*
X1541570D01*
Y883514D01*
X1541370D01*
G37*
G36*
G01Y881164D02*
X1540970Y881307D01*
Y882057D01*
X1541370Y882199D01*
X1541570D01*
Y881164D01*
X1541370D01*
G37*
G36*
G01Y878814D02*
X1540970Y878957D01*
Y879707D01*
X1541370Y879849D01*
X1541570D01*
Y878814D01*
X1541370D01*
G37*
G36*
G01X1541770Y881024D02*
X1542170Y880881D01*
Y880131D01*
X1541770Y879989D01*
X1541570D01*
Y881024D01*
X1541770D01*
G37*
G36*
G01Y869274D02*
X1542170Y869131D01*
Y868381D01*
X1541770Y868239D01*
X1541570D01*
Y869274D01*
X1541770D01*
G37*
G36*
G01Y878674D02*
X1542170Y878531D01*
Y877781D01*
X1541770Y877639D01*
X1541570D01*
Y878674D01*
X1541770D01*
G37*
G36*
G01Y871624D02*
X1542170Y871481D01*
Y870731D01*
X1541770Y870589D01*
X1541570D01*
Y871624D01*
X1541770D01*
G37*
G36*
G01X1541370Y869414D02*
X1540970Y869557D01*
Y870307D01*
X1541370Y870449D01*
X1541570D01*
Y869414D01*
X1541370D01*
G37*
G36*
G01Y876464D02*
X1540970Y876607D01*
Y877357D01*
X1541370Y877499D01*
X1541570D01*
Y876464D01*
X1541370D01*
G37*
G36*
G01Y874114D02*
X1540970Y874257D01*
Y875007D01*
X1541370Y875149D01*
X1541570D01*
Y874114D01*
X1541370D01*
G37*
G36*
G01Y871764D02*
X1540970Y871907D01*
Y872657D01*
X1541370Y872799D01*
X1541570D01*
Y871764D01*
X1541370D01*
G37*
G36*
G01X1541770Y876324D02*
X1542170Y876181D01*
Y875431D01*
X1541770Y875289D01*
X1541570D01*
Y876324D01*
X1541770D01*
G37*
G36*
G01Y873974D02*
X1542170Y873831D01*
Y873081D01*
X1541770Y872939D01*
X1541570D01*
Y873974D01*
X1541770D01*
G37*
G36*
G01X1539570Y878674D02*
X1539970Y878531D01*
Y877781D01*
X1539570Y877639D01*
X1539370D01*
Y878674D01*
X1539570D01*
G37*
G36*
G01Y881024D02*
X1539970Y880881D01*
Y880131D01*
X1539570Y879989D01*
X1539370D01*
Y881024D01*
X1539570D01*
G37*
G36*
G01Y883374D02*
X1539970Y883231D01*
Y882481D01*
X1539570Y882339D01*
X1539370D01*
Y883374D01*
X1539570D01*
G37*
G36*
G01X1539170Y878814D02*
X1538770Y878957D01*
Y879707D01*
X1539170Y879849D01*
X1539370D01*
Y878814D01*
X1539170D01*
G37*
G36*
G01Y881164D02*
X1538770Y881307D01*
Y882057D01*
X1539170Y882199D01*
X1539370D01*
Y881164D01*
X1539170D01*
G37*
G36*
G01Y883514D02*
X1538770Y883657D01*
Y884407D01*
X1539170Y884549D01*
X1539370D01*
Y883514D01*
X1539170D01*
G37*
G36*
G01Y869414D02*
X1538770Y869557D01*
Y870307D01*
X1539170Y870449D01*
X1539370D01*
Y869414D01*
X1539170D01*
G37*
G36*
G01X1539570Y871624D02*
X1539970Y871481D01*
Y870731D01*
X1539570Y870589D01*
X1539370D01*
Y871624D01*
X1539570D01*
G37*
G36*
G01Y873974D02*
X1539970Y873831D01*
Y873081D01*
X1539570Y872939D01*
X1539370D01*
Y873974D01*
X1539570D01*
G37*
G36*
G01Y876324D02*
X1539970Y876181D01*
Y875431D01*
X1539570Y875289D01*
X1539370D01*
Y876324D01*
X1539570D01*
G37*
G36*
G01X1539170Y871764D02*
X1538770Y871907D01*
Y872657D01*
X1539170Y872799D01*
X1539370D01*
Y871764D01*
X1539170D01*
G37*
G36*
G01Y874114D02*
X1538770Y874257D01*
Y875007D01*
X1539170Y875149D01*
X1539370D01*
Y874114D01*
X1539170D01*
G37*
G36*
G01Y876464D02*
X1538770Y876607D01*
Y877357D01*
X1539170Y877499D01*
X1539370D01*
Y876464D01*
X1539170D01*
G37*
G36*
G01X1539570Y869274D02*
X1539970Y869131D01*
Y868381D01*
X1539570Y868239D01*
X1539370D01*
Y869274D01*
X1539570D01*
G37*
G36*
G01X1536770Y883514D02*
X1536370Y883657D01*
Y884407D01*
X1536770Y884549D01*
X1536970D01*
Y883514D01*
X1536770D01*
G37*
G36*
G01X1537170Y883374D02*
X1537570Y883231D01*
Y882481D01*
X1537170Y882339D01*
X1536970D01*
Y883374D01*
X1537170D01*
G37*
G36*
G01Y869274D02*
X1537570Y869131D01*
Y868381D01*
X1537170Y868239D01*
X1536970D01*
Y869274D01*
X1537170D01*
G37*
G36*
G01X1536770Y881164D02*
X1536370Y881307D01*
Y882057D01*
X1536770Y882199D01*
X1536970D01*
Y881164D01*
X1536770D01*
G37*
G36*
G01Y878814D02*
X1536370Y878957D01*
Y879707D01*
X1536770Y879849D01*
X1536970D01*
Y878814D01*
X1536770D01*
G37*
G36*
G01Y876464D02*
X1536370Y876607D01*
Y877357D01*
X1536770Y877499D01*
X1536970D01*
Y876464D01*
X1536770D01*
G37*
G36*
G01Y874114D02*
X1536370Y874257D01*
Y875007D01*
X1536770Y875149D01*
X1536970D01*
Y874114D01*
X1536770D01*
G37*
G36*
G01Y871764D02*
X1536370Y871907D01*
Y872657D01*
X1536770Y872799D01*
X1536970D01*
Y871764D01*
X1536770D01*
G37*
G36*
G01X1537170Y881024D02*
X1537570Y880881D01*
Y880131D01*
X1537170Y879989D01*
X1536970D01*
Y881024D01*
X1537170D01*
G37*
G36*
G01Y878674D02*
X1537570Y878531D01*
Y877781D01*
X1537170Y877639D01*
X1536970D01*
Y878674D01*
X1537170D01*
G37*
G36*
G01Y876324D02*
X1537570Y876181D01*
Y875431D01*
X1537170Y875289D01*
X1536970D01*
Y876324D01*
X1537170D01*
G37*
G36*
G01Y873974D02*
X1537570Y873831D01*
Y873081D01*
X1537170Y872939D01*
X1536970D01*
Y873974D01*
X1537170D01*
G37*
G36*
G01Y871624D02*
X1537570Y871481D01*
Y870731D01*
X1537170Y870589D01*
X1536970D01*
Y871624D01*
X1537170D01*
G37*
G36*
G01X1536770Y869414D02*
X1536370Y869557D01*
Y870307D01*
X1536770Y870449D01*
X1536970D01*
Y869414D01*
X1536770D01*
G37*
G36*
G01X1537970Y883514D02*
X1537570Y883657D01*
Y884407D01*
X1537970Y884549D01*
X1538170D01*
Y883514D01*
X1537970D01*
G37*
G36*
G01X1538370Y883374D02*
X1538770Y883231D01*
Y882481D01*
X1538370Y882339D01*
X1538170D01*
Y883374D01*
X1538370D01*
G37*
G36*
G01Y869274D02*
X1538770Y869131D01*
Y868381D01*
X1538370Y868239D01*
X1538170D01*
Y869274D01*
X1538370D01*
G37*
G36*
G01Y876324D02*
X1538770Y876181D01*
Y875431D01*
X1538370Y875289D01*
X1538170D01*
Y876324D01*
X1538370D01*
G37*
G36*
G01Y873974D02*
X1538770Y873831D01*
Y873081D01*
X1538370Y872939D01*
X1538170D01*
Y873974D01*
X1538370D01*
G37*
G36*
G01X1537970Y881164D02*
X1537570Y881307D01*
Y882057D01*
X1537970Y882199D01*
X1538170D01*
Y881164D01*
X1537970D01*
G37*
G36*
G01Y878814D02*
X1537570Y878957D01*
Y879707D01*
X1537970Y879849D01*
X1538170D01*
Y878814D01*
X1537970D01*
G37*
G36*
G01Y876464D02*
X1537570Y876607D01*
Y877357D01*
X1537970Y877499D01*
X1538170D01*
Y876464D01*
X1537970D01*
G37*
G36*
G01Y874114D02*
X1537570Y874257D01*
Y875007D01*
X1537970Y875149D01*
X1538170D01*
Y874114D01*
X1537970D01*
G37*
G36*
G01Y871764D02*
X1537570Y871907D01*
Y872657D01*
X1537970Y872799D01*
X1538170D01*
Y871764D01*
X1537970D01*
G37*
G36*
G01X1538370Y871624D02*
X1538770Y871481D01*
Y870731D01*
X1538370Y870589D01*
X1538170D01*
Y871624D01*
X1538370D01*
G37*
G36*
G01X1537970Y869414D02*
X1537570Y869557D01*
Y870307D01*
X1537970Y870449D01*
X1538170D01*
Y869414D01*
X1537970D01*
G37*
G36*
G01X1538370Y881024D02*
X1538770Y880881D01*
Y880131D01*
X1538370Y879989D01*
X1538170D01*
Y881024D01*
X1538370D01*
G37*
G36*
G01Y878674D02*
X1538770Y878531D01*
Y877781D01*
X1538370Y877639D01*
X1538170D01*
Y878674D01*
X1538370D01*
G37*
G36*
G01X1535570Y883514D02*
X1535170Y883657D01*
Y884407D01*
X1535570Y884549D01*
X1535770D01*
Y883514D01*
X1535570D01*
G37*
G36*
G01X1535970Y883374D02*
X1536370Y883231D01*
Y882481D01*
X1535970Y882339D01*
X1535770D01*
Y883374D01*
X1535970D01*
G37*
G36*
G01Y869274D02*
X1536370Y869131D01*
Y868381D01*
X1535970Y868239D01*
X1535770D01*
Y869274D01*
X1535970D01*
G37*
G36*
G01Y881024D02*
X1536370Y880881D01*
Y880131D01*
X1535970Y879989D01*
X1535770D01*
Y881024D01*
X1535970D01*
G37*
G36*
G01Y878674D02*
X1536370Y878531D01*
Y877781D01*
X1535970Y877639D01*
X1535770D01*
Y878674D01*
X1535970D01*
G37*
G36*
G01Y876324D02*
X1536370Y876181D01*
Y875431D01*
X1535970Y875289D01*
X1535770D01*
Y876324D01*
X1535970D01*
G37*
G36*
G01Y873974D02*
X1536370Y873831D01*
Y873081D01*
X1535970Y872939D01*
X1535770D01*
Y873974D01*
X1535970D01*
G37*
G36*
G01X1535570Y881164D02*
X1535170Y881307D01*
Y882057D01*
X1535570Y882199D01*
X1535770D01*
Y881164D01*
X1535570D01*
G37*
G36*
G01Y878814D02*
X1535170Y878957D01*
Y879707D01*
X1535570Y879849D01*
X1535770D01*
Y878814D01*
X1535570D01*
G37*
G36*
G01Y876464D02*
X1535170Y876607D01*
Y877357D01*
X1535570Y877499D01*
X1535770D01*
Y876464D01*
X1535570D01*
G37*
G36*
G01Y874114D02*
X1535170Y874257D01*
Y875007D01*
X1535570Y875149D01*
X1535770D01*
Y874114D01*
X1535570D01*
G37*
G36*
G01Y871764D02*
X1535170Y871907D01*
Y872657D01*
X1535570Y872799D01*
X1535770D01*
Y871764D01*
X1535570D01*
G37*
G36*
G01X1535970Y871624D02*
X1536370Y871481D01*
Y870731D01*
X1535970Y870589D01*
X1535770D01*
Y871624D01*
X1535970D01*
G37*
G36*
G01X1535570Y869414D02*
X1535170Y869557D01*
Y870307D01*
X1535570Y870449D01*
X1535770D01*
Y869414D01*
X1535570D01*
G37*
G36*
G01X1529970Y874755D02*
X1530370Y874613D01*
Y873863D01*
X1529970Y873720D01*
X1529770D01*
Y874755D01*
X1529970D01*
G37*
G36*
G01X1529570Y881945D02*
X1529170Y882087D01*
Y882837D01*
X1529570Y882980D01*
X1529770D01*
Y881945D01*
X1529570D01*
G37*
G36*
G01Y879595D02*
X1529170Y879737D01*
Y880487D01*
X1529570Y880630D01*
X1529770D01*
Y879595D01*
X1529570D01*
G37*
G36*
G01Y877245D02*
X1529170Y877387D01*
Y878137D01*
X1529570Y878280D01*
X1529770D01*
Y877245D01*
X1529570D01*
G37*
G36*
G01Y874895D02*
X1529170Y875037D01*
Y875787D01*
X1529570Y875930D01*
X1529770D01*
Y874895D01*
X1529570D01*
G37*
G36*
G01Y872545D02*
X1529170Y872687D01*
Y873437D01*
X1529570Y873580D01*
X1529770D01*
Y872545D01*
X1529570D01*
G37*
G36*
G01X1529970Y872405D02*
X1530370Y872263D01*
Y871513D01*
X1529970Y871370D01*
X1529770D01*
Y872405D01*
X1529970D01*
G37*
G36*
G01X1529570Y870195D02*
X1529170Y870337D01*
Y871087D01*
X1529570Y871230D01*
X1529770D01*
Y870195D01*
X1529570D01*
G37*
G36*
G01X1529970Y870055D02*
X1530370Y869913D01*
Y869163D01*
X1529970Y869020D01*
X1529770D01*
Y870055D01*
X1529970D01*
G37*
G36*
G01Y884155D02*
X1530370Y884013D01*
Y883263D01*
X1529970Y883120D01*
X1529770D01*
Y884155D01*
X1529970D01*
G37*
G36*
G01Y881805D02*
X1530370Y881663D01*
Y880913D01*
X1529970Y880770D01*
X1529770D01*
Y881805D01*
X1529970D01*
G37*
G36*
G01Y879455D02*
X1530370Y879313D01*
Y878563D01*
X1529970Y878420D01*
X1529770D01*
Y879455D01*
X1529970D01*
G37*
G36*
G01Y877105D02*
X1530370Y876963D01*
Y876213D01*
X1529970Y876070D01*
X1529770D01*
Y877105D01*
X1529970D01*
G37*
G36*
G01X1527570Y870055D02*
X1527970Y869913D01*
Y869163D01*
X1527570Y869020D01*
X1527370D01*
Y870055D01*
X1527570D01*
G37*
G36*
G01X1527170Y870195D02*
X1526770Y870337D01*
Y871087D01*
X1527170Y871230D01*
X1527370D01*
Y870195D01*
X1527170D01*
G37*
G36*
G01X1527570Y872405D02*
X1527970Y872263D01*
Y871513D01*
X1527570Y871370D01*
X1527370D01*
Y872405D01*
X1527570D01*
G37*
G36*
G01Y874755D02*
X1527970Y874613D01*
Y873863D01*
X1527570Y873720D01*
X1527370D01*
Y874755D01*
X1527570D01*
G37*
G36*
G01Y877105D02*
X1527970Y876963D01*
Y876213D01*
X1527570Y876070D01*
X1527370D01*
Y877105D01*
X1527570D01*
G37*
G36*
G01Y879455D02*
X1527970Y879313D01*
Y878563D01*
X1527570Y878420D01*
X1527370D01*
Y879455D01*
X1527570D01*
G37*
G36*
G01Y881805D02*
X1527970Y881663D01*
Y880913D01*
X1527570Y880770D01*
X1527370D01*
Y881805D01*
X1527570D01*
G37*
G36*
G01Y884155D02*
X1527970Y884013D01*
Y883263D01*
X1527570Y883120D01*
X1527370D01*
Y884155D01*
X1527570D01*
G37*
G36*
G01X1527170Y872545D02*
X1526770Y872687D01*
Y873437D01*
X1527170Y873580D01*
X1527370D01*
Y872545D01*
X1527170D01*
G37*
G36*
G01Y874895D02*
X1526770Y875037D01*
Y875787D01*
X1527170Y875930D01*
X1527370D01*
Y874895D01*
X1527170D01*
G37*
G36*
G01Y877245D02*
X1526770Y877387D01*
Y878137D01*
X1527170Y878280D01*
X1527370D01*
Y877245D01*
X1527170D01*
G37*
G36*
G01Y879595D02*
X1526770Y879737D01*
Y880487D01*
X1527170Y880630D01*
X1527370D01*
Y879595D01*
X1527170D01*
G37*
G36*
G01Y881945D02*
X1526770Y882087D01*
Y882837D01*
X1527170Y882980D01*
X1527370D01*
Y881945D01*
X1527170D01*
G37*
G36*
G01X1528770Y877105D02*
X1529170Y876963D01*
Y876213D01*
X1528770Y876070D01*
X1528570D01*
Y877105D01*
X1528770D01*
G37*
G36*
G01Y874755D02*
X1529170Y874613D01*
Y873863D01*
X1528770Y873720D01*
X1528570D01*
Y874755D01*
X1528770D01*
G37*
G36*
G01Y872405D02*
X1529170Y872263D01*
Y871513D01*
X1528770Y871370D01*
X1528570D01*
Y872405D01*
X1528770D01*
G37*
G36*
G01Y870055D02*
X1529170Y869913D01*
Y869163D01*
X1528770Y869020D01*
X1528570D01*
Y870055D01*
X1528770D01*
G37*
G36*
G01X1528370Y881945D02*
X1527970Y882087D01*
Y882837D01*
X1528370Y882980D01*
X1528570D01*
Y881945D01*
X1528370D01*
G37*
G36*
G01Y879595D02*
X1527970Y879737D01*
Y880487D01*
X1528370Y880630D01*
X1528570D01*
Y879595D01*
X1528370D01*
G37*
G36*
G01Y877245D02*
X1527970Y877387D01*
Y878137D01*
X1528370Y878280D01*
X1528570D01*
Y877245D01*
X1528370D01*
G37*
G36*
G01Y874895D02*
X1527970Y875037D01*
Y875787D01*
X1528370Y875930D01*
X1528570D01*
Y874895D01*
X1528370D01*
G37*
G36*
G01Y872545D02*
X1527970Y872687D01*
Y873437D01*
X1528370Y873580D01*
X1528570D01*
Y872545D01*
X1528370D01*
G37*
G36*
G01Y870195D02*
X1527970Y870337D01*
Y871087D01*
X1528370Y871230D01*
X1528570D01*
Y870195D01*
X1528370D01*
G37*
G36*
G01X1528770Y884155D02*
X1529170Y884013D01*
Y883263D01*
X1528770Y883120D01*
X1528570D01*
Y884155D01*
X1528770D01*
G37*
G36*
G01Y881805D02*
X1529170Y881663D01*
Y880913D01*
X1528770Y880770D01*
X1528570D01*
Y881805D01*
X1528770D01*
G37*
G36*
G01Y879455D02*
X1529170Y879313D01*
Y878563D01*
X1528770Y878420D01*
X1528570D01*
Y879455D01*
X1528770D01*
G37*
G36*
G01X1526370Y884155D02*
X1526770Y884013D01*
Y883263D01*
X1526370Y883120D01*
X1526170D01*
Y884155D01*
X1526370D01*
G37*
G36*
G01Y881805D02*
X1526770Y881663D01*
Y880913D01*
X1526370Y880770D01*
X1526170D01*
Y881805D01*
X1526370D01*
G37*
G36*
G01Y879455D02*
X1526770Y879313D01*
Y878563D01*
X1526370Y878420D01*
X1526170D01*
Y879455D01*
X1526370D01*
G37*
G36*
G01Y877105D02*
X1526770Y876963D01*
Y876213D01*
X1526370Y876070D01*
X1526170D01*
Y877105D01*
X1526370D01*
G37*
G36*
G01Y874755D02*
X1526770Y874613D01*
Y873863D01*
X1526370Y873720D01*
X1526170D01*
Y874755D01*
X1526370D01*
G37*
G36*
G01Y872405D02*
X1526770Y872263D01*
Y871513D01*
X1526370Y871370D01*
X1526170D01*
Y872405D01*
X1526370D01*
G37*
G36*
G01Y870055D02*
X1526770Y869913D01*
Y869163D01*
X1526370Y869020D01*
X1526170D01*
Y870055D01*
X1526370D01*
G37*
G36*
G01X1525970Y881945D02*
X1525570Y882087D01*
Y882837D01*
X1525970Y882980D01*
X1526170D01*
Y881945D01*
X1525970D01*
G37*
G36*
G01Y879595D02*
X1525570Y879737D01*
Y880487D01*
X1525970Y880630D01*
X1526170D01*
Y879595D01*
X1525970D01*
G37*
G36*
G01Y877245D02*
X1525570Y877387D01*
Y878137D01*
X1525970Y878280D01*
X1526170D01*
Y877245D01*
X1525970D01*
G37*
G36*
G01Y874895D02*
X1525570Y875037D01*
Y875787D01*
X1525970Y875930D01*
X1526170D01*
Y874895D01*
X1525970D01*
G37*
G36*
G01Y872545D02*
X1525570Y872687D01*
Y873437D01*
X1525970Y873580D01*
X1526170D01*
Y872545D01*
X1525970D01*
G37*
G36*
G01Y870195D02*
X1525570Y870337D01*
Y871087D01*
X1525970Y871230D01*
X1526170D01*
Y870195D01*
X1525970D01*
G37*
G36*
G01X1542578Y899923D02*
X1542194Y899741D01*
X1541664Y900271D01*
X1541846Y900655D01*
X1541988Y900796D01*
X1542719Y900065D01*
X1542578Y899923D01*
G37*
G36*
G01X1540880Y898225D02*
X1540496Y898043D01*
X1539966Y898573D01*
X1540148Y898957D01*
X1540290Y899098D01*
X1541021Y898367D01*
X1540880Y898225D01*
G37*
G36*
G01X1541262Y898409D02*
X1541646Y898591D01*
X1542176Y898061D01*
X1541994Y897677D01*
X1541852Y897536D01*
X1541120Y898268D01*
X1541262Y898409D01*
G37*
G36*
G01X1539600Y900071D02*
X1539984Y900253D01*
X1540514Y899722D01*
X1540332Y899339D01*
X1540191Y899197D01*
X1539459Y899929D01*
X1539600Y900071D01*
G37*
G36*
G01X1539218Y899887D02*
X1538835Y899705D01*
X1538304Y900235D01*
X1538487Y900619D01*
X1538628Y900760D01*
X1539360Y900028D01*
X1539218Y899887D01*
G37*
G36*
G01X1540449Y900920D02*
X1540833Y901102D01*
X1541363Y900571D01*
X1541181Y900188D01*
X1541040Y900046D01*
X1540308Y900778D01*
X1540449Y900920D01*
G37*
G36*
G01X1541729Y899074D02*
X1541345Y898892D01*
X1540815Y899422D01*
X1540997Y899806D01*
X1541139Y899947D01*
X1541870Y899216D01*
X1541729Y899074D01*
G37*
G36*
G01X1541770Y885724D02*
X1542170Y885581D01*
Y884831D01*
X1541770Y884689D01*
X1541570D01*
Y885724D01*
X1541770D01*
G37*
G36*
G01X1541370Y892914D02*
X1540970Y893057D01*
Y893807D01*
X1541370Y893949D01*
X1541570D01*
Y892914D01*
X1541370D01*
G37*
G36*
G01X1541770Y892774D02*
X1542170Y892631D01*
Y891881D01*
X1541770Y891739D01*
X1541570D01*
Y892774D01*
X1541770D01*
G37*
G36*
G01Y895124D02*
X1542170Y894981D01*
Y894231D01*
X1541770Y894089D01*
X1541570D01*
Y895124D01*
X1541770D01*
G37*
G36*
G01Y888074D02*
X1542170Y887931D01*
Y887181D01*
X1541770Y887039D01*
X1541570D01*
Y888074D01*
X1541770D01*
G37*
G36*
G01X1541370Y885864D02*
X1540970Y886007D01*
Y886757D01*
X1541370Y886899D01*
X1541570D01*
Y885864D01*
X1541370D01*
G37*
G36*
G01Y890564D02*
X1540970Y890707D01*
Y891457D01*
X1541370Y891599D01*
X1541570D01*
Y890564D01*
X1541370D01*
G37*
G36*
G01Y888214D02*
X1540970Y888357D01*
Y889107D01*
X1541370Y889249D01*
X1541570D01*
Y888214D01*
X1541370D01*
G37*
G36*
G01X1541770Y890424D02*
X1542170Y890281D01*
Y889531D01*
X1541770Y889389D01*
X1541570D01*
Y890424D01*
X1541770D01*
G37*
G36*
G01X1538751Y899222D02*
X1539135Y899404D01*
X1539665Y898873D01*
X1539483Y898490D01*
X1539342Y898348D01*
X1538610Y899080D01*
X1538751Y899222D01*
G37*
G36*
G01X1537089Y900883D02*
X1537473Y901065D01*
X1538003Y900535D01*
X1537821Y900151D01*
X1537680Y900010D01*
X1536948Y900742D01*
X1537089Y900883D01*
G37*
G36*
G01X1540413Y897560D02*
X1540797Y897742D01*
X1541327Y897212D01*
X1541145Y896828D01*
X1541003Y896687D01*
X1540271Y897419D01*
X1540413Y897560D01*
G37*
G36*
G01X1539570Y885724D02*
X1539970Y885581D01*
Y884831D01*
X1539570Y884689D01*
X1539370D01*
Y885724D01*
X1539570D01*
G37*
G36*
G01X1539170Y885864D02*
X1538770Y886007D01*
Y886757D01*
X1539170Y886899D01*
X1539370D01*
Y885864D01*
X1539170D01*
G37*
G36*
G01X1537170Y885724D02*
X1537570Y885581D01*
Y884831D01*
X1537170Y884689D01*
X1536970D01*
Y885724D01*
X1537170D01*
G37*
G36*
G01X1536770Y885864D02*
X1536370Y886007D01*
Y886757D01*
X1536770Y886899D01*
X1536970D01*
Y885864D01*
X1536770D01*
G37*
G36*
G01X1538370Y885724D02*
X1538770Y885581D01*
Y884831D01*
X1538370Y884689D01*
X1538170D01*
Y885724D01*
X1538370D01*
G37*
G36*
G01X1537970Y885864D02*
X1537570Y886007D01*
Y886757D01*
X1537970Y886899D01*
X1538170D01*
Y885864D01*
X1537970D01*
G37*
G36*
G01X1535970Y885724D02*
X1536370Y885581D01*
Y884831D01*
X1535970Y884689D01*
X1535770D01*
Y885724D01*
X1535970D01*
G37*
G36*
G01X1535570Y885864D02*
X1535170Y886007D01*
Y886757D01*
X1535570Y886899D01*
X1535770D01*
Y885864D01*
X1535570D01*
G37*
G36*
G01X1529570Y884295D02*
X1529170Y884437D01*
Y885187D01*
X1529570Y885330D01*
X1529770D01*
Y884295D01*
X1529570D01*
G37*
G36*
G01X1527170D02*
X1526770Y884437D01*
Y885187D01*
X1527170Y885330D01*
X1527370D01*
Y884295D01*
X1527170D01*
G37*
G36*
G01X1528370D02*
X1527970Y884437D01*
Y885187D01*
X1528370Y885330D01*
X1528570D01*
Y884295D01*
X1528370D01*
G37*
G36*
G01X1539779Y916874D02*
X1540162Y917056D01*
X1540693Y916526D01*
X1540510Y916142D01*
X1540369Y916001D01*
X1539637Y916733D01*
X1539779Y916874D01*
G37*
G36*
G01X1539397Y916690D02*
X1539013Y916508D01*
X1538483Y917039D01*
X1538665Y917422D01*
X1538806Y917564D01*
X1539538Y916832D01*
X1539397Y916690D01*
G37*
G36*
G01X1541440Y915213D02*
X1541824Y915395D01*
X1542354Y914864D01*
X1542172Y914481D01*
X1542031Y914339D01*
X1541299Y915071D01*
X1541440Y915213D01*
G37*
G36*
G01X1541058Y915029D02*
X1540675Y914847D01*
X1540145Y915377D01*
X1540327Y915761D01*
X1540468Y915902D01*
X1541200Y915170D01*
X1541058Y915029D01*
G37*
G36*
G01X1536037Y916654D02*
X1535653Y916472D01*
X1535123Y917002D01*
X1535305Y917386D01*
X1535447Y917527D01*
X1536178Y916796D01*
X1536037Y916654D01*
G37*
G36*
G01X1537699Y914992D02*
X1537315Y914810D01*
X1536785Y915341D01*
X1536967Y915724D01*
X1537108Y915866D01*
X1537840Y915134D01*
X1537699Y914992D01*
G37*
G36*
G01X1536419Y916838D02*
X1536802Y917020D01*
X1537333Y916490D01*
X1537151Y916106D01*
X1537009Y915965D01*
X1536277Y916697D01*
X1536419Y916838D01*
G37*
G36*
G01X1539360Y913331D02*
X1538977Y913149D01*
X1538447Y913679D01*
X1538629Y914063D01*
X1538770Y914204D01*
X1539502Y913472D01*
X1539360Y913331D01*
G37*
G36*
G01X1538081Y915176D02*
X1538464Y915358D01*
X1538995Y914828D01*
X1538812Y914444D01*
X1538671Y914303D01*
X1537939Y915035D01*
X1538081Y915176D01*
G37*
G36*
G01X1539742Y913515D02*
X1540126Y913697D01*
X1540656Y913166D01*
X1540474Y912783D01*
X1540333Y912641D01*
X1539601Y913373D01*
X1539742Y913515D01*
G37*
G36*
G01X1541022Y911669D02*
X1540639Y911487D01*
X1540108Y912017D01*
X1540290Y912401D01*
X1540432Y912542D01*
X1541164Y911810D01*
X1541022Y911669D01*
G37*
G36*
G01X1541404Y911853D02*
X1541788Y912035D01*
X1542318Y911505D01*
X1542136Y911121D01*
X1541994Y910980D01*
X1541263Y911711D01*
X1541404Y911853D01*
G37*
G36*
G01X1538548Y915841D02*
X1538164Y915659D01*
X1537634Y916190D01*
X1537816Y916573D01*
X1537957Y916715D01*
X1538689Y915983D01*
X1538548Y915841D01*
G37*
G36*
G01X1538930Y916025D02*
X1539313Y916207D01*
X1539844Y915677D01*
X1539661Y915293D01*
X1539520Y915152D01*
X1538788Y915884D01*
X1538930Y916025D01*
G37*
G36*
G01X1540591Y914364D02*
X1540975Y914546D01*
X1541505Y914015D01*
X1541323Y913632D01*
X1541182Y913490D01*
X1540450Y914222D01*
X1540591Y914364D01*
G37*
G36*
G01X1541871Y912518D02*
X1541488Y912336D01*
X1540957Y912866D01*
X1541139Y913250D01*
X1541281Y913391D01*
X1542013Y912659D01*
X1541871Y912518D01*
G37*
G36*
G01X1540209Y914180D02*
X1539826Y913998D01*
X1539296Y914528D01*
X1539478Y914912D01*
X1539619Y915053D01*
X1540351Y914321D01*
X1540209Y914180D01*
G37*
G36*
G01X1533908Y917651D02*
X1534292Y917833D01*
X1534822Y917302D01*
X1534640Y916919D01*
X1534499Y916777D01*
X1533767Y917509D01*
X1533908Y917651D01*
G37*
G36*
G01X1535188Y915805D02*
X1534804Y915623D01*
X1534274Y916153D01*
X1534456Y916537D01*
X1534598Y916678D01*
X1535329Y915947D01*
X1535188Y915805D01*
G37*
G36*
G01X1541835Y909158D02*
X1541451Y908976D01*
X1540921Y909507D01*
X1541103Y909890D01*
X1541244Y910032D01*
X1541976Y909300D01*
X1541835Y909158D01*
G37*
G36*
G01X1538893Y912666D02*
X1539277Y912848D01*
X1539807Y912317D01*
X1539625Y911934D01*
X1539484Y911792D01*
X1538752Y912524D01*
X1538893Y912666D01*
G37*
G36*
G01X1540173Y910820D02*
X1539790Y910638D01*
X1539259Y911168D01*
X1539441Y911552D01*
X1539583Y911693D01*
X1540315Y910961D01*
X1540173Y910820D01*
G37*
G36*
G01X1535570Y915989D02*
X1535953Y916171D01*
X1536484Y915641D01*
X1536302Y915257D01*
X1536160Y915116D01*
X1535428Y915848D01*
X1535570Y915989D01*
G37*
G36*
G01X1536850Y914143D02*
X1536466Y913961D01*
X1535936Y914492D01*
X1536118Y914875D01*
X1536259Y915017D01*
X1536991Y914285D01*
X1536850Y914143D01*
G37*
G36*
G01X1538511Y912482D02*
X1538128Y912300D01*
X1537598Y912830D01*
X1537780Y913214D01*
X1537921Y913355D01*
X1538653Y912623D01*
X1538511Y912482D01*
G37*
G36*
G01X1537232Y914327D02*
X1537615Y914509D01*
X1538146Y913979D01*
X1537963Y913595D01*
X1537822Y913454D01*
X1537090Y914186D01*
X1537232Y914327D01*
G37*
G36*
G01X1540555Y911004D02*
X1540939Y911186D01*
X1541469Y910656D01*
X1541287Y910272D01*
X1541145Y910131D01*
X1540414Y910862D01*
X1540555Y911004D01*
G37*
G36*
G01X1532608Y909893D02*
X1532224Y909711D01*
X1531694Y910242D01*
X1531876Y910625D01*
X1532017Y910767D01*
X1532749Y910035D01*
X1532608Y909893D01*
G37*
G36*
G01X1534270Y908232D02*
X1533886Y908050D01*
X1533356Y908580D01*
X1533538Y908963D01*
X1533679Y909105D01*
X1534411Y908373D01*
X1534270Y908232D01*
G37*
G36*
G01X1532990Y910077D02*
X1533373Y910259D01*
X1533904Y909729D01*
X1533722Y909345D01*
X1533580Y909204D01*
X1532848Y909936D01*
X1532990Y910077D01*
G37*
G36*
G01X1534651Y908415D02*
X1535035Y908598D01*
X1535565Y908067D01*
X1535383Y907684D01*
X1535242Y907542D01*
X1534510Y908274D01*
X1534651Y908415D01*
G37*
G36*
G01X1535931Y906570D02*
X1535548Y906388D01*
X1535017Y906918D01*
X1535199Y907302D01*
X1535341Y907443D01*
X1536073Y906711D01*
X1535931Y906570D01*
G37*
G36*
G01X1540916Y901585D02*
X1540533Y901403D01*
X1540002Y901933D01*
X1540185Y902317D01*
X1540326Y902458D01*
X1541058Y901726D01*
X1540916Y901585D01*
G37*
G36*
G01X1541298Y901769D02*
X1541682Y901951D01*
X1542212Y901420D01*
X1542030Y901037D01*
X1541889Y900895D01*
X1541157Y901627D01*
X1541298Y901769D01*
G37*
G36*
G01X1539255Y903247D02*
X1538871Y903064D01*
X1538341Y903595D01*
X1538523Y903978D01*
X1538664Y904120D01*
X1539396Y903388D01*
X1539255Y903247D01*
G37*
G36*
G01X1539636Y903430D02*
X1540020Y903612D01*
X1540550Y903082D01*
X1540368Y902698D01*
X1540227Y902557D01*
X1539495Y903289D01*
X1539636Y903430D01*
G37*
G36*
G01X1537975Y905092D02*
X1538358Y905274D01*
X1538889Y904744D01*
X1538707Y904360D01*
X1538565Y904219D01*
X1537833Y904951D01*
X1537975Y905092D01*
G37*
G36*
G01X1537593Y904908D02*
X1537209Y904726D01*
X1536679Y905256D01*
X1536861Y905640D01*
X1537003Y905781D01*
X1537734Y905050D01*
X1537593Y904908D01*
G37*
G36*
G01X1536313Y906754D02*
X1536697Y906936D01*
X1537227Y906406D01*
X1537045Y906022D01*
X1536904Y905880D01*
X1536172Y906612D01*
X1536313Y906754D01*
G37*
G36*
G01X1534615Y905056D02*
X1534999Y905238D01*
X1535529Y904708D01*
X1535347Y904324D01*
X1535206Y904182D01*
X1534474Y904914D01*
X1534615Y905056D01*
G37*
G36*
G01X1534233Y904872D02*
X1533850Y904690D01*
X1533319Y905220D01*
X1533501Y905604D01*
X1533643Y905745D01*
X1534375Y905013D01*
X1534233Y904872D01*
G37*
G36*
G01X1532953Y906717D02*
X1533337Y906900D01*
X1533867Y906369D01*
X1533685Y905986D01*
X1533544Y905844D01*
X1532812Y906576D01*
X1532953Y906717D01*
G37*
G36*
G01X1532572Y906534D02*
X1532188Y906352D01*
X1531658Y906882D01*
X1531840Y907265D01*
X1531981Y907407D01*
X1532713Y906675D01*
X1532572Y906534D01*
G37*
G36*
G01X1531292Y908379D02*
X1531675Y908561D01*
X1532206Y908031D01*
X1532024Y907647D01*
X1531882Y907506D01*
X1531150Y908238D01*
X1531292Y908379D01*
G37*
G36*
G01X1535895Y903210D02*
X1535511Y903028D01*
X1534981Y903558D01*
X1535163Y903942D01*
X1535305Y904083D01*
X1536036Y903352D01*
X1535895Y903210D01*
G37*
G36*
G01X1537938Y901732D02*
X1538322Y901914D01*
X1538852Y901384D01*
X1538670Y901000D01*
X1538529Y900859D01*
X1537797Y901591D01*
X1537938Y901732D01*
G37*
G36*
G01X1537557Y901549D02*
X1537173Y901366D01*
X1536643Y901897D01*
X1536825Y902280D01*
X1536966Y902422D01*
X1537698Y901690D01*
X1537557Y901549D01*
G37*
G36*
G01X1536277Y903394D02*
X1536660Y903576D01*
X1537191Y903046D01*
X1537009Y902662D01*
X1536867Y902521D01*
X1536135Y903253D01*
X1536277Y903394D01*
G37*
G36*
G01X1535082Y905721D02*
X1534699Y905539D01*
X1534168Y906069D01*
X1534350Y906453D01*
X1534492Y906594D01*
X1535224Y905862D01*
X1535082Y905721D01*
G37*
G36*
G01X1532141Y909228D02*
X1532524Y909410D01*
X1533055Y908880D01*
X1532873Y908496D01*
X1532731Y908355D01*
X1531999Y909087D01*
X1532141Y909228D01*
G37*
G36*
G01X1533421Y907383D02*
X1533037Y907201D01*
X1532507Y907731D01*
X1532689Y908114D01*
X1532830Y908256D01*
X1533562Y907524D01*
X1533421Y907383D01*
G37*
G36*
G01X1533802Y907566D02*
X1534186Y907749D01*
X1534716Y907218D01*
X1534534Y906835D01*
X1534393Y906693D01*
X1533661Y907425D01*
X1533802Y907566D01*
G37*
G36*
G01X1540067Y900736D02*
X1539684Y900554D01*
X1539153Y901084D01*
X1539336Y901468D01*
X1539477Y901609D01*
X1540209Y900877D01*
X1540067Y900736D01*
G37*
G36*
G01X1538787Y902581D02*
X1539171Y902763D01*
X1539701Y902233D01*
X1539519Y901849D01*
X1539378Y901708D01*
X1538646Y902440D01*
X1538787Y902581D01*
G37*
G36*
G01X1538406Y902398D02*
X1538022Y902215D01*
X1537492Y902746D01*
X1537674Y903129D01*
X1537815Y903271D01*
X1538547Y902539D01*
X1538406Y902398D01*
G37*
G36*
G01X1535464Y905905D02*
X1535848Y906087D01*
X1536378Y905557D01*
X1536196Y905173D01*
X1536055Y905031D01*
X1535323Y905763D01*
X1535464Y905905D01*
G37*
G36*
G01X1537126Y904243D02*
X1537509Y904425D01*
X1538040Y903895D01*
X1537858Y903511D01*
X1537716Y903370D01*
X1536984Y904102D01*
X1537126Y904243D01*
G37*
G36*
G01X1536744Y904059D02*
X1536360Y903877D01*
X1535830Y904407D01*
X1536012Y904791D01*
X1536154Y904932D01*
X1536885Y904201D01*
X1536744Y904059D01*
G37*
G36*
G01X1532104Y905868D02*
X1532488Y906051D01*
X1533018Y905520D01*
X1532836Y905137D01*
X1532695Y904995D01*
X1531963Y905727D01*
X1532104Y905868D01*
G37*
G36*
G01X1533384Y904023D02*
X1533001Y903841D01*
X1532470Y904371D01*
X1532652Y904755D01*
X1532794Y904896D01*
X1533526Y904164D01*
X1533384Y904023D01*
G37*
G36*
G01X1531723Y905685D02*
X1531339Y905503D01*
X1530809Y906033D01*
X1530991Y906416D01*
X1531132Y906558D01*
X1531864Y905826D01*
X1531723Y905685D01*
G37*
G36*
G01X1533766Y904207D02*
X1534150Y904389D01*
X1534680Y903859D01*
X1534498Y903475D01*
X1534357Y903333D01*
X1533625Y904065D01*
X1533766Y904207D01*
G37*
G36*
G01X1530443Y907530D02*
X1530826Y907712D01*
X1531357Y907182D01*
X1531175Y906798D01*
X1531033Y906657D01*
X1530301Y907389D01*
X1530443Y907530D01*
G37*
G36*
G01X1535428Y902545D02*
X1535811Y902727D01*
X1536342Y902197D01*
X1536160Y901813D01*
X1536018Y901672D01*
X1535286Y902404D01*
X1535428Y902545D01*
G37*
G36*
G01X1539911Y933646D02*
X1540295Y933828D01*
X1540825Y933298D01*
X1540643Y932914D01*
X1540502Y932773D01*
X1539770Y933504D01*
X1539911Y933646D01*
G37*
G36*
G01X1541191Y931800D02*
X1540807Y931618D01*
X1540277Y932148D01*
X1540459Y932532D01*
X1540600Y932673D01*
X1541332Y931942D01*
X1541191Y931800D01*
G37*
G36*
G01X1541573Y931984D02*
X1541956Y932166D01*
X1542487Y931636D01*
X1542305Y931252D01*
X1542163Y931111D01*
X1541431Y931843D01*
X1541573Y931984D01*
G37*
G36*
G01X1538619Y925883D02*
X1538235Y925700D01*
X1537705Y926231D01*
X1537887Y926614D01*
X1538028Y926756D01*
X1538760Y926024D01*
X1538619Y925883D01*
G37*
G36*
G01X1539000Y926066D02*
X1539384Y926248D01*
X1539914Y925718D01*
X1539732Y925334D01*
X1539591Y925193D01*
X1538859Y925925D01*
X1539000Y926066D01*
G37*
G36*
G01X1540280Y924221D02*
X1539897Y924039D01*
X1539366Y924569D01*
X1539548Y924953D01*
X1539690Y925094D01*
X1540422Y924362D01*
X1540280Y924221D01*
G37*
G36*
G01X1541942Y922559D02*
X1541558Y922377D01*
X1541028Y922907D01*
X1541210Y923291D01*
X1541352Y923432D01*
X1542083Y922701D01*
X1541942Y922559D01*
G37*
G36*
G01X1540662Y924405D02*
X1541046Y924587D01*
X1541576Y924056D01*
X1541394Y923673D01*
X1541253Y923531D01*
X1540521Y924263D01*
X1540662Y924405D01*
G37*
G36*
G01X1536957Y927544D02*
X1536573Y927362D01*
X1536043Y927892D01*
X1536225Y928276D01*
X1536367Y928417D01*
X1537098Y927686D01*
X1536957Y927544D01*
G37*
G36*
G01X1537339Y927728D02*
X1537722Y927910D01*
X1538253Y927380D01*
X1538071Y926996D01*
X1537929Y926855D01*
X1537197Y927587D01*
X1537339Y927728D01*
G37*
G36*
G01X1535259Y925846D02*
X1534875Y925664D01*
X1534345Y926194D01*
X1534527Y926578D01*
X1534669Y926719D01*
X1535400Y925988D01*
X1535259Y925846D01*
G37*
G36*
G01X1535641Y926030D02*
X1536024Y926212D01*
X1536555Y925682D01*
X1536373Y925298D01*
X1536231Y925157D01*
X1535499Y925889D01*
X1535641Y926030D01*
G37*
G36*
G01X1536921Y924185D02*
X1536537Y924002D01*
X1536007Y924533D01*
X1536189Y924916D01*
X1536330Y925058D01*
X1537062Y924326D01*
X1536921Y924185D01*
G37*
G36*
G01X1537302Y924368D02*
X1537686Y924550D01*
X1538216Y924020D01*
X1538034Y923636D01*
X1537893Y923495D01*
X1537161Y924227D01*
X1537302Y924368D01*
G37*
G36*
G01X1538582Y922523D02*
X1538199Y922341D01*
X1537668Y922871D01*
X1537850Y923255D01*
X1537992Y923396D01*
X1538724Y922664D01*
X1538582Y922523D01*
G37*
G36*
G01X1538964Y922707D02*
X1539348Y922889D01*
X1539878Y922358D01*
X1539696Y921975D01*
X1539555Y921833D01*
X1538823Y922565D01*
X1538964Y922707D01*
G37*
G36*
G01X1540244Y920861D02*
X1539860Y920679D01*
X1539330Y921209D01*
X1539512Y921593D01*
X1539654Y921734D01*
X1540385Y921003D01*
X1540244Y920861D01*
G37*
G36*
G01X1540626Y921045D02*
X1541009Y921227D01*
X1541540Y920697D01*
X1541358Y920313D01*
X1541216Y920172D01*
X1540484Y920904D01*
X1540626Y921045D01*
G37*
G36*
G01X1541906Y919199D02*
X1541522Y919017D01*
X1540992Y919548D01*
X1541174Y919931D01*
X1541315Y920073D01*
X1542047Y919341D01*
X1541906Y919199D01*
G37*
G36*
G01X1534828Y928541D02*
X1535212Y928723D01*
X1535742Y928193D01*
X1535560Y927809D01*
X1535419Y927667D01*
X1534687Y928399D01*
X1534828Y928541D01*
G37*
G36*
G01X1539813Y923556D02*
X1540197Y923738D01*
X1540727Y923207D01*
X1540545Y922824D01*
X1540404Y922682D01*
X1539672Y923414D01*
X1539813Y923556D01*
G37*
G36*
G01X1539431Y923372D02*
X1539048Y923190D01*
X1538517Y923720D01*
X1538699Y924104D01*
X1538841Y924245D01*
X1539573Y923513D01*
X1539431Y923372D01*
G37*
G36*
G01X1536490Y926879D02*
X1536873Y927061D01*
X1537404Y926531D01*
X1537222Y926147D01*
X1537080Y926006D01*
X1536348Y926738D01*
X1536490Y926879D01*
G37*
G36*
G01X1536108Y926695D02*
X1535724Y926513D01*
X1535194Y927043D01*
X1535376Y927427D01*
X1535518Y927568D01*
X1536249Y926837D01*
X1536108Y926695D01*
G37*
G36*
G01X1537770Y925034D02*
X1537386Y924851D01*
X1536856Y925382D01*
X1537038Y925765D01*
X1537179Y925907D01*
X1537911Y925175D01*
X1537770Y925034D01*
G37*
G36*
G01X1538151Y925217D02*
X1538535Y925399D01*
X1539065Y924869D01*
X1538883Y924485D01*
X1538742Y924344D01*
X1538010Y925076D01*
X1538151Y925217D01*
G37*
G36*
G01X1541093Y921710D02*
X1540709Y921528D01*
X1540179Y922058D01*
X1540361Y922442D01*
X1540503Y922583D01*
X1541234Y921852D01*
X1541093Y921710D01*
G37*
G36*
G01X1541475Y921894D02*
X1541858Y922076D01*
X1542389Y921546D01*
X1542207Y921162D01*
X1542065Y921021D01*
X1541333Y921753D01*
X1541475Y921894D01*
G37*
G36*
G01X1534792Y925181D02*
X1535175Y925363D01*
X1535706Y924833D01*
X1535524Y924449D01*
X1535382Y924308D01*
X1534650Y925040D01*
X1534792Y925181D01*
G37*
G36*
G01X1534410Y924997D02*
X1534026Y924815D01*
X1533496Y925345D01*
X1533678Y925729D01*
X1533820Y925870D01*
X1534551Y925139D01*
X1534410Y924997D01*
G37*
G36*
G01X1541439Y918534D02*
X1541822Y918716D01*
X1542353Y918186D01*
X1542170Y917802D01*
X1542029Y917661D01*
X1541297Y918393D01*
X1541439Y918534D01*
G37*
G36*
G01X1536453Y923519D02*
X1536837Y923701D01*
X1537367Y923171D01*
X1537185Y922787D01*
X1537044Y922646D01*
X1536312Y923378D01*
X1536453Y923519D01*
G37*
G36*
G01X1536072Y923336D02*
X1535688Y923153D01*
X1535158Y923684D01*
X1535340Y924067D01*
X1535481Y924209D01*
X1536213Y923477D01*
X1536072Y923336D01*
G37*
G36*
G01X1537733Y921674D02*
X1537350Y921492D01*
X1536819Y922022D01*
X1537001Y922406D01*
X1537143Y922547D01*
X1537875Y921815D01*
X1537733Y921674D01*
G37*
G36*
G01X1541057Y918350D02*
X1540673Y918168D01*
X1540143Y918699D01*
X1540325Y919082D01*
X1540466Y919224D01*
X1541198Y918492D01*
X1541057Y918350D01*
G37*
G36*
G01X1538115Y921858D02*
X1538499Y922040D01*
X1539029Y921509D01*
X1538847Y921126D01*
X1538706Y920984D01*
X1537974Y921716D01*
X1538115Y921858D01*
G37*
G36*
G01X1539777Y920196D02*
X1540160Y920378D01*
X1540691Y919848D01*
X1540509Y919464D01*
X1540367Y919323D01*
X1539635Y920055D01*
X1539777Y920196D01*
G37*
G36*
G01X1539395Y920012D02*
X1539011Y919830D01*
X1538481Y920360D01*
X1538663Y920744D01*
X1538805Y920885D01*
X1539536Y920154D01*
X1539395Y920012D01*
G37*
G36*
G01X1533132Y923521D02*
X1533515Y923703D01*
X1534046Y923173D01*
X1533864Y922789D01*
X1533722Y922648D01*
X1532990Y923380D01*
X1533132Y923521D01*
G37*
G36*
G01X1532750Y923337D02*
X1532366Y923155D01*
X1531836Y923685D01*
X1532018Y924069D01*
X1532160Y924210D01*
X1532891Y923479D01*
X1532750Y923337D01*
G37*
G36*
G01X1534793Y921859D02*
X1535177Y922041D01*
X1535707Y921511D01*
X1535525Y921127D01*
X1535384Y920986D01*
X1534652Y921718D01*
X1534793Y921859D01*
G37*
G36*
G01X1534412Y921676D02*
X1534028Y921493D01*
X1533498Y922024D01*
X1533680Y922407D01*
X1533821Y922549D01*
X1534553Y921817D01*
X1534412Y921676D01*
G37*
G36*
G01X1538117Y918536D02*
X1538500Y918718D01*
X1539031Y918188D01*
X1538849Y917804D01*
X1538707Y917663D01*
X1537975Y918395D01*
X1538117Y918536D01*
G37*
G36*
G01X1537735Y918352D02*
X1537351Y918170D01*
X1536821Y918700D01*
X1537003Y919084D01*
X1537145Y919225D01*
X1537876Y918494D01*
X1537735Y918352D01*
G37*
G36*
G01X1536073Y920014D02*
X1535690Y919832D01*
X1535159Y920362D01*
X1535341Y920746D01*
X1535483Y920887D01*
X1536215Y920155D01*
X1536073Y920014D01*
G37*
G36*
G01X1536455Y920198D02*
X1536839Y920380D01*
X1537369Y919849D01*
X1537187Y919466D01*
X1537046Y919324D01*
X1536314Y920056D01*
X1536455Y920198D01*
G37*
G36*
G01X1534757Y918500D02*
X1535141Y918682D01*
X1535671Y918151D01*
X1535489Y917768D01*
X1535348Y917626D01*
X1534616Y918358D01*
X1534757Y918500D01*
G37*
G36*
G01X1532714Y919978D02*
X1532330Y919795D01*
X1531800Y920326D01*
X1531982Y920709D01*
X1532123Y920851D01*
X1532855Y920119D01*
X1532714Y919978D01*
G37*
G36*
G01X1531434Y921823D02*
X1531817Y922005D01*
X1532348Y921475D01*
X1532166Y921091D01*
X1532024Y920950D01*
X1531292Y921682D01*
X1531434Y921823D01*
G37*
G36*
G01X1533095Y920161D02*
X1533479Y920343D01*
X1534009Y919813D01*
X1533827Y919429D01*
X1533686Y919288D01*
X1532954Y920020D01*
X1533095Y920161D01*
G37*
G36*
G01X1534375Y918316D02*
X1533992Y918134D01*
X1533461Y918664D01*
X1533643Y919048D01*
X1533785Y919189D01*
X1534517Y918457D01*
X1534375Y918316D01*
G37*
G36*
G01X1532283Y922672D02*
X1532666Y922854D01*
X1533197Y922324D01*
X1533015Y921940D01*
X1532873Y921799D01*
X1532141Y922531D01*
X1532283Y922672D01*
G37*
G36*
G01X1533563Y920827D02*
X1533179Y920644D01*
X1532649Y921175D01*
X1532831Y921558D01*
X1532972Y921700D01*
X1533704Y920968D01*
X1533563Y920827D01*
G37*
G36*
G01X1533944Y921010D02*
X1534328Y921192D01*
X1534858Y920662D01*
X1534676Y920278D01*
X1534535Y920137D01*
X1533803Y920869D01*
X1533944Y921010D01*
G37*
G36*
G01X1535224Y919165D02*
X1534841Y918983D01*
X1534310Y919513D01*
X1534492Y919897D01*
X1534634Y920038D01*
X1535366Y919306D01*
X1535224Y919165D01*
G37*
G36*
G01X1536886Y917503D02*
X1536502Y917321D01*
X1535972Y917851D01*
X1536154Y918235D01*
X1536296Y918376D01*
X1537027Y917645D01*
X1536886Y917503D01*
G37*
G36*
G01X1537268Y917687D02*
X1537651Y917869D01*
X1538182Y917339D01*
X1538000Y916955D01*
X1537858Y916814D01*
X1537126Y917546D01*
X1537268Y917687D01*
G37*
G36*
G01X1535606Y919349D02*
X1535990Y919531D01*
X1536520Y919000D01*
X1536338Y918617D01*
X1536197Y918475D01*
X1535465Y919207D01*
X1535606Y919349D01*
G37*
G36*
G01X1533526Y917467D02*
X1533143Y917285D01*
X1532612Y917815D01*
X1532794Y918199D01*
X1532936Y918340D01*
X1533668Y917608D01*
X1533526Y917467D01*
G37*
G36*
G01X1532246Y919312D02*
X1532630Y919494D01*
X1533160Y918964D01*
X1532978Y918580D01*
X1532837Y918439D01*
X1532105Y919171D01*
X1532246Y919312D01*
G37*
G36*
G01X1531865Y919129D02*
X1531481Y918946D01*
X1530951Y919477D01*
X1531133Y919860D01*
X1531274Y920002D01*
X1532006Y919270D01*
X1531865Y919129D01*
G37*
G36*
G01X1542040Y932650D02*
X1541657Y932467D01*
X1541126Y932998D01*
X1541308Y933381D01*
X1541450Y933523D01*
X1542182Y932791D01*
X1542040Y932650D01*
G37*
G36*
G01X1541680Y945385D02*
X1542064Y945567D01*
X1542594Y945037D01*
X1542412Y944654D01*
X1542271Y944512D01*
X1541539Y945244D01*
X1541680Y945385D01*
G37*
G36*
G01X1537795Y945510D02*
X1537652Y945110D01*
X1536902D01*
X1536760Y945510D01*
Y945710D01*
X1537795D01*
Y945510D01*
G37*
G36*
G01X1540145D02*
X1540002Y945110D01*
X1539252D01*
X1539110Y945510D01*
Y945710D01*
X1540145D01*
Y945510D01*
G37*
G36*
G01X1537935Y945910D02*
X1538078Y946310D01*
X1538828D01*
X1538970Y945910D01*
Y945710D01*
X1537935D01*
Y945910D01*
G37*
G36*
G01Y943510D02*
X1538078Y943910D01*
X1538828D01*
X1538970Y943510D01*
Y943310D01*
X1537935D01*
Y943510D01*
G37*
G36*
G01X1537795Y943110D02*
X1537652Y942710D01*
X1536902D01*
X1536760Y943110D01*
Y943310D01*
X1537795D01*
Y943110D01*
G37*
G36*
G01X1535585Y943510D02*
X1535728Y943910D01*
X1536478D01*
X1536620Y943510D01*
Y943310D01*
X1535585D01*
Y943510D01*
G37*
G36*
G01X1541644Y942026D02*
X1542028Y942208D01*
X1542558Y941677D01*
X1542376Y941294D01*
X1542235Y941152D01*
X1541503Y941884D01*
X1541644Y942026D01*
G37*
G36*
G01X1541262Y941842D02*
X1540879Y941660D01*
X1540348Y942190D01*
X1540530Y942574D01*
X1540672Y942715D01*
X1541404Y941983D01*
X1541262Y941842D01*
G37*
G36*
G01X1542111Y942691D02*
X1541728Y942509D01*
X1541197Y943039D01*
X1541379Y943423D01*
X1541521Y943564D01*
X1542253Y942832D01*
X1542111Y942691D01*
G37*
G36*
G01X1537795Y944310D02*
X1537652Y943910D01*
X1536902D01*
X1536760Y944310D01*
Y944510D01*
X1537795D01*
Y944310D01*
G37*
G36*
G01X1535585Y944710D02*
X1535728Y945110D01*
X1536478D01*
X1536620Y944710D01*
Y944510D01*
X1535585D01*
Y944710D01*
G37*
G36*
G01X1537935D02*
X1538078Y945110D01*
X1538828D01*
X1538970Y944710D01*
Y944510D01*
X1537935D01*
Y944710D01*
G37*
G36*
G01X1535445Y941910D02*
X1535302Y941510D01*
X1534552D01*
X1534410Y941910D01*
Y942110D01*
X1535445D01*
Y941910D01*
G37*
G36*
G01X1540795Y941177D02*
X1541179Y941359D01*
X1541709Y940828D01*
X1541527Y940445D01*
X1541386Y940303D01*
X1540654Y941035D01*
X1540795Y941177D01*
G37*
G36*
G01X1542075Y939331D02*
X1541691Y939149D01*
X1541161Y939679D01*
X1541343Y940063D01*
X1541485Y940204D01*
X1542216Y939473D01*
X1542075Y939331D01*
G37*
G36*
G01X1537795Y941910D02*
X1537652Y941510D01*
X1536902D01*
X1536760Y941910D01*
Y942110D01*
X1537795D01*
Y941910D01*
G37*
G36*
G01X1537935Y942310D02*
X1538078Y942710D01*
X1538828D01*
X1538970Y942310D01*
Y942110D01*
X1537935D01*
Y942310D01*
G37*
G36*
G01X1535585D02*
X1535728Y942710D01*
X1536478D01*
X1536620Y942310D01*
Y942110D01*
X1535585D01*
Y942310D01*
G37*
G36*
G01X1533283Y938509D02*
X1533140Y938109D01*
X1532390D01*
X1532248Y938509D01*
Y938709D01*
X1533283D01*
Y938509D01*
G37*
G36*
G01X1535633D02*
X1535490Y938109D01*
X1534740D01*
X1534598Y938509D01*
Y938709D01*
X1535633D01*
Y938509D01*
G37*
G36*
G01X1533423Y938909D02*
X1533566Y939309D01*
X1534316D01*
X1534458Y938909D01*
Y938709D01*
X1533423D01*
Y938909D01*
G37*
G36*
G01X1541612Y935347D02*
X1541996Y935529D01*
X1542526Y934999D01*
X1542344Y934615D01*
X1542203Y934473D01*
X1541471Y935205D01*
X1541612Y935347D01*
G37*
G36*
G01X1535773Y938909D02*
X1535916Y939309D01*
X1536666D01*
X1536808Y938909D01*
Y938709D01*
X1535773D01*
Y938909D01*
G37*
G36*
G01X1539950Y937008D02*
X1540334Y937191D01*
X1540864Y936660D01*
X1540682Y936277D01*
X1540541Y936135D01*
X1539809Y936867D01*
X1539950Y937008D01*
G37*
G36*
G01X1539569Y936825D02*
X1539185Y936643D01*
X1538655Y937173D01*
X1538837Y937556D01*
X1538978Y937698D01*
X1539710Y936966D01*
X1539569Y936825D01*
G37*
G36*
G01X1541230Y935163D02*
X1540847Y934981D01*
X1540316Y935511D01*
X1540498Y935895D01*
X1540640Y936036D01*
X1541372Y935304D01*
X1541230Y935163D01*
G37*
G36*
G01X1533423Y936509D02*
X1533566Y936909D01*
X1534316D01*
X1534458Y936509D01*
Y936309D01*
X1533423D01*
Y936509D01*
G37*
G36*
G01X1533283Y936109D02*
X1533140Y935709D01*
X1532390D01*
X1532248Y936109D01*
Y936309D01*
X1533283D01*
Y936109D01*
G37*
G36*
G01X1535633D02*
X1535490Y935709D01*
X1534740D01*
X1534598Y936109D01*
Y936309D01*
X1535633D01*
Y936109D01*
G37*
G36*
G01X1538249Y935307D02*
X1538633Y935490D01*
X1539163Y934959D01*
X1538981Y934576D01*
X1538840Y934434D01*
X1538108Y935166D01*
X1538249Y935307D01*
G37*
G36*
G01X1539529Y933462D02*
X1539146Y933280D01*
X1538615Y933810D01*
X1538797Y934194D01*
X1538939Y934335D01*
X1539671Y933603D01*
X1539529Y933462D01*
G37*
G36*
G01X1535633Y939709D02*
X1535490Y939309D01*
X1534740D01*
X1534598Y939709D01*
Y939909D01*
X1535633D01*
Y939709D01*
G37*
G36*
G01X1533423Y940109D02*
X1533566Y940509D01*
X1534316D01*
X1534458Y940109D01*
Y939909D01*
X1533423D01*
Y940109D01*
G37*
G36*
G01X1540418Y937674D02*
X1540034Y937492D01*
X1539504Y938022D01*
X1539686Y938406D01*
X1539828Y938547D01*
X1540559Y937816D01*
X1540418Y937674D01*
G37*
G36*
G01X1540800Y937858D02*
X1541183Y938040D01*
X1541714Y937510D01*
X1541532Y937126D01*
X1541390Y936985D01*
X1540658Y937717D01*
X1540800Y937858D01*
G37*
G36*
G01X1539138Y939520D02*
X1539522Y939702D01*
X1540052Y939171D01*
X1539870Y938788D01*
X1539729Y938646D01*
X1538997Y939378D01*
X1539138Y939520D01*
G37*
G36*
G01X1542080Y936012D02*
X1541696Y935830D01*
X1541166Y936361D01*
X1541348Y936744D01*
X1541489Y936886D01*
X1542221Y936154D01*
X1542080Y936012D01*
G37*
G36*
G01X1535773Y940109D02*
X1535916Y940509D01*
X1536666D01*
X1536808Y940109D01*
Y939909D01*
X1535773D01*
Y940109D01*
G37*
G36*
G01X1540379Y934311D02*
X1539995Y934129D01*
X1539465Y934659D01*
X1539647Y935043D01*
X1539788Y935184D01*
X1540520Y934453D01*
X1540379Y934311D01*
G37*
G36*
G01X1540760Y934495D02*
X1541144Y934677D01*
X1541674Y934147D01*
X1541492Y933763D01*
X1541351Y933622D01*
X1540619Y934354D01*
X1540760Y934495D01*
G37*
G36*
G01X1535773Y937709D02*
X1535916Y938109D01*
X1536666D01*
X1536808Y937709D01*
Y937509D01*
X1535773D01*
Y937709D01*
G37*
G36*
G01X1538717Y935973D02*
X1538333Y935791D01*
X1537803Y936321D01*
X1537985Y936705D01*
X1538126Y936846D01*
X1538858Y936114D01*
X1538717Y935973D01*
G37*
G36*
G01X1539099Y936157D02*
X1539482Y936339D01*
X1540012Y935808D01*
X1539830Y935425D01*
X1539689Y935283D01*
X1538957Y936015D01*
X1539099Y936157D01*
G37*
G36*
G01X1531262Y960543D02*
X1530878Y960361D01*
X1530348Y960892D01*
X1530530Y961275D01*
X1530671Y961417D01*
X1531403Y960685D01*
X1531262Y960543D01*
G37*
G36*
G01X1531644Y960727D02*
X1532027Y960909D01*
X1532558Y960379D01*
X1532375Y959995D01*
X1532234Y959854D01*
X1531502Y960586D01*
X1531644Y960727D01*
G37*
G36*
G01X1534967Y957404D02*
X1535351Y957586D01*
X1535881Y957056D01*
X1535699Y956672D01*
X1535557Y956531D01*
X1534826Y957262D01*
X1534967Y957404D01*
G37*
G36*
G01X1533305Y959065D02*
X1533689Y959248D01*
X1534219Y958717D01*
X1534037Y958334D01*
X1533896Y958192D01*
X1533164Y958924D01*
X1533305Y959065D01*
G37*
G36*
G01X1534585Y957220D02*
X1534202Y957038D01*
X1533671Y957568D01*
X1533853Y957952D01*
X1533995Y958093D01*
X1534727Y957361D01*
X1534585Y957220D01*
G37*
G36*
G01X1532924Y958882D02*
X1532540Y958700D01*
X1532010Y959230D01*
X1532192Y959614D01*
X1532333Y959755D01*
X1533065Y959023D01*
X1532924Y958882D01*
G37*
G36*
G01X1541573Y955514D02*
X1541716Y955914D01*
X1542466D01*
X1542608Y955514D01*
Y955314D01*
X1541573D01*
Y955514D01*
G37*
G36*
G01X1541433Y955114D02*
X1541290Y954714D01*
X1540540D01*
X1540398Y955114D01*
Y955314D01*
X1541433D01*
Y955114D01*
G37*
G36*
G01X1539083D02*
X1538940Y954714D01*
X1538190D01*
X1538048Y955114D01*
Y955314D01*
X1539083D01*
Y955114D01*
G37*
G36*
G01X1539223Y955514D02*
X1539366Y955914D01*
X1540116D01*
X1540258Y955514D01*
Y955314D01*
X1539223D01*
Y955514D01*
G37*
G36*
G01X1536247Y955558D02*
X1535863Y955376D01*
X1535333Y955906D01*
X1535515Y956290D01*
X1535656Y956432D01*
X1536388Y955700D01*
X1536247Y955558D01*
G37*
G36*
G01X1534549Y953860D02*
X1534165Y953678D01*
X1533635Y954208D01*
X1533817Y954592D01*
X1533958Y954734D01*
X1534690Y954002D01*
X1534549Y953860D01*
G37*
G36*
G01X1531226Y957184D02*
X1530842Y957002D01*
X1530312Y957532D01*
X1530494Y957916D01*
X1530635Y958057D01*
X1531367Y957325D01*
X1531226Y957184D01*
G37*
G36*
G01X1532887Y955522D02*
X1532504Y955340D01*
X1531973Y955870D01*
X1532155Y956254D01*
X1532297Y956395D01*
X1533029Y955663D01*
X1532887Y955522D01*
G37*
G36*
G01X1531607Y957367D02*
X1531991Y957550D01*
X1532521Y957019D01*
X1532339Y956636D01*
X1532198Y956494D01*
X1531466Y957226D01*
X1531607Y957367D01*
G37*
G36*
G01X1533269Y955706D02*
X1533653Y955888D01*
X1534183Y955358D01*
X1534001Y954974D01*
X1533859Y954833D01*
X1533128Y955564D01*
X1533269Y955706D01*
G37*
G36*
G01X1529946Y959029D02*
X1530329Y959211D01*
X1530860Y958681D01*
X1530677Y958297D01*
X1530536Y958156D01*
X1529804Y958888D01*
X1529946Y959029D01*
G37*
G36*
G01X1541433Y952714D02*
X1541290Y952314D01*
X1540540D01*
X1540398Y952714D01*
Y952914D01*
X1541433D01*
Y952714D01*
G37*
G36*
G01X1539223Y953114D02*
X1539366Y953514D01*
X1540116D01*
X1540258Y953114D01*
Y952914D01*
X1539223D01*
Y953114D01*
G37*
G36*
G01X1536873D02*
X1537016Y953514D01*
X1537766D01*
X1537908Y953114D01*
Y952914D01*
X1536873D01*
Y953114D01*
G37*
G36*
G01X1541573D02*
X1541716Y953514D01*
X1542466D01*
X1542608Y953114D01*
Y952914D01*
X1541573D01*
Y953114D01*
G37*
G36*
G01X1539083Y952714D02*
X1538940Y952314D01*
X1538190D01*
X1538048Y952714D01*
Y952914D01*
X1539083D01*
Y952714D01*
G37*
G36*
G01X1534118Y956555D02*
X1534502Y956737D01*
X1535032Y956207D01*
X1534850Y955823D01*
X1534708Y955682D01*
X1533977Y956413D01*
X1534118Y956555D01*
G37*
G36*
G01X1532075Y958033D02*
X1531691Y957851D01*
X1531161Y958381D01*
X1531343Y958765D01*
X1531484Y958906D01*
X1532216Y958174D01*
X1532075Y958033D01*
G37*
G36*
G01X1535398Y954709D02*
X1535014Y954527D01*
X1534484Y955057D01*
X1534666Y955441D01*
X1534807Y955583D01*
X1535539Y954851D01*
X1535398Y954709D01*
G37*
G36*
G01X1533736Y956371D02*
X1533353Y956189D01*
X1532822Y956719D01*
X1533004Y957103D01*
X1533146Y957244D01*
X1533878Y956512D01*
X1533736Y956371D01*
G37*
G36*
G01X1530795Y959878D02*
X1531178Y960060D01*
X1531709Y959530D01*
X1531526Y959146D01*
X1531385Y959005D01*
X1530653Y959737D01*
X1530795Y959878D01*
G37*
G36*
G01X1532456Y958216D02*
X1532840Y958399D01*
X1533370Y957868D01*
X1533188Y957485D01*
X1533047Y957343D01*
X1532315Y958075D01*
X1532456Y958216D01*
G37*
G36*
G01X1541573Y954314D02*
X1541716Y954714D01*
X1542466D01*
X1542608Y954314D01*
Y954114D01*
X1541573D01*
Y954314D01*
G37*
G36*
G01X1539083Y953914D02*
X1538940Y953514D01*
X1538190D01*
X1538048Y953914D01*
Y954114D01*
X1539083D01*
Y953914D01*
G37*
G36*
G01X1541433D02*
X1541290Y953514D01*
X1540540D01*
X1540398Y953914D01*
Y954114D01*
X1541433D01*
Y953914D01*
G37*
G36*
G01X1539223Y954314D02*
X1539366Y954714D01*
X1540116D01*
X1540258Y954314D01*
Y954114D01*
X1539223D01*
Y954314D01*
G37*
G36*
G01X1536873D02*
X1537016Y954714D01*
X1537766D01*
X1537908Y954314D01*
Y954114D01*
X1536873D01*
Y954314D01*
G37*
G36*
G01X1534082Y953195D02*
X1534465Y953377D01*
X1534996Y952847D01*
X1534814Y952463D01*
X1534672Y952322D01*
X1533940Y953054D01*
X1534082Y953195D01*
G37*
G36*
G01X1532420Y954857D02*
X1532804Y955039D01*
X1533334Y954509D01*
X1533152Y954125D01*
X1533010Y953984D01*
X1532279Y954715D01*
X1532420Y954857D01*
G37*
G36*
G01X1533700Y953011D02*
X1533316Y952829D01*
X1532786Y953359D01*
X1532968Y953743D01*
X1533109Y953885D01*
X1533841Y953153D01*
X1533700Y953011D01*
G37*
G36*
G01X1530758Y956518D02*
X1531142Y956701D01*
X1531672Y956170D01*
X1531490Y955787D01*
X1531349Y955645D01*
X1530617Y956377D01*
X1530758Y956518D01*
G37*
G36*
G01X1532038Y954673D02*
X1531655Y954491D01*
X1531124Y955021D01*
X1531306Y955405D01*
X1531448Y955546D01*
X1532180Y954814D01*
X1532038Y954673D01*
G37*
G36*
G01X1530377Y956335D02*
X1529993Y956153D01*
X1529463Y956683D01*
X1529645Y957067D01*
X1529786Y957208D01*
X1530518Y956476D01*
X1530377Y956335D01*
G37*
G36*
G01X1541433Y951514D02*
X1541290Y951114D01*
X1540540D01*
X1540398Y951514D01*
Y951714D01*
X1541433D01*
Y951514D01*
G37*
G36*
G01X1539083D02*
X1538940Y951114D01*
X1538190D01*
X1538048Y951514D01*
Y951714D01*
X1539083D01*
Y951514D01*
G37*
G36*
G01X1541573Y951914D02*
X1541716Y952314D01*
X1542466D01*
X1542608Y951914D01*
Y951714D01*
X1541573D01*
Y951914D01*
G37*
G36*
G01X1539223D02*
X1539366Y952314D01*
X1540116D01*
X1540258Y951914D01*
Y951714D01*
X1539223D01*
Y951914D01*
G37*
G36*
G01X1536873D02*
X1537016Y952314D01*
X1537766D01*
X1537908Y951914D01*
Y951714D01*
X1536873D01*
Y951914D01*
G37*
G36*
G01X1542104Y980188D02*
X1541962Y979788D01*
X1541212D01*
X1541070Y980188D01*
Y980388D01*
X1542104D01*
Y980188D01*
G37*
G36*
G01X1539754D02*
X1539612Y979788D01*
X1538862D01*
X1538720Y980188D01*
Y980388D01*
X1539754D01*
Y980188D01*
G37*
G36*
G01X1539894Y980588D02*
X1540037Y980988D01*
X1540787D01*
X1540930Y980588D01*
Y980388D01*
X1539894D01*
Y980588D01*
G37*
G36*
G01X1537544D02*
X1537687Y980988D01*
X1538437D01*
X1538580Y980588D01*
Y980388D01*
X1537544D01*
Y980588D01*
G37*
G36*
G01X1537404Y980188D02*
X1537262Y979788D01*
X1536512D01*
X1536370Y980188D01*
Y980388D01*
X1537404D01*
Y980188D01*
G37*
G36*
G01X1542104Y978988D02*
X1541962Y978588D01*
X1541212D01*
X1541070Y978988D01*
Y979188D01*
X1542104D01*
Y978988D01*
G37*
G36*
G01X1539754D02*
X1539612Y978588D01*
X1538862D01*
X1538720Y978988D01*
Y979188D01*
X1539754D01*
Y978988D01*
G37*
G36*
G01X1539894Y979388D02*
X1540037Y979788D01*
X1540787D01*
X1540930Y979388D01*
Y979188D01*
X1539894D01*
Y979388D01*
G37*
G36*
G01X1537544D02*
X1537687Y979788D01*
X1538437D01*
X1538580Y979388D01*
Y979188D01*
X1537544D01*
Y979388D01*
G37*
G36*
G01X1537404Y978988D02*
X1537262Y978588D01*
X1536512D01*
X1536370Y978988D01*
Y979188D01*
X1537404D01*
Y978988D01*
G37*
G36*
G01X1542104Y977788D02*
X1541962Y977388D01*
X1541212D01*
X1541070Y977788D01*
Y977988D01*
X1542104D01*
Y977788D01*
G37*
G36*
G01X1539754D02*
X1539612Y977388D01*
X1538862D01*
X1538720Y977788D01*
Y977988D01*
X1539754D01*
Y977788D01*
G37*
G36*
G01X1539894Y978188D02*
X1540037Y978588D01*
X1540787D01*
X1540930Y978188D01*
Y977988D01*
X1539894D01*
Y978188D01*
G37*
G36*
G01X1537544D02*
X1537687Y978588D01*
X1538437D01*
X1538580Y978188D01*
Y977988D01*
X1537544D01*
Y978188D01*
G37*
G36*
G01X1537404Y977788D02*
X1537262Y977388D01*
X1536512D01*
X1536370Y977788D01*
Y977988D01*
X1537404D01*
Y977788D01*
G37*
G36*
G01X1535194Y978188D02*
X1535337Y978588D01*
X1536087D01*
X1536230Y978188D01*
Y977988D01*
X1535194D01*
Y978188D01*
G37*
G36*
G01X1539894Y976988D02*
X1540037Y977388D01*
X1540787D01*
X1540930Y976988D01*
Y976788D01*
X1539894D01*
Y976988D01*
G37*
G36*
G01X1537544D02*
X1537687Y977388D01*
X1538437D01*
X1538580Y976988D01*
Y976788D01*
X1537544D01*
Y976988D01*
G37*
G36*
G01X1535194D02*
X1535337Y977388D01*
X1536087D01*
X1536230Y976988D01*
Y976788D01*
X1535194D01*
Y976988D01*
G37*
G36*
G01X1542104Y976588D02*
X1541962Y976188D01*
X1541212D01*
X1541070Y976588D01*
Y976788D01*
X1542104D01*
Y976588D01*
G37*
G36*
G01X1539754D02*
X1539612Y976188D01*
X1538862D01*
X1538720Y976588D01*
Y976788D01*
X1539754D01*
Y976588D01*
G37*
G36*
G01X1537404D02*
X1537262Y976188D01*
X1536512D01*
X1536370Y976588D01*
Y976788D01*
X1537404D01*
Y976588D01*
G37*
G36*
G01X1535054Y975388D02*
X1534912Y974988D01*
X1534162D01*
X1534020Y975388D01*
Y975588D01*
X1535054D01*
Y975388D01*
G37*
G36*
G01X1539754D02*
X1539612Y974988D01*
X1538862D01*
X1538720Y975388D01*
Y975588D01*
X1539754D01*
Y975388D01*
G37*
G36*
G01X1542104D02*
X1541962Y974988D01*
X1541212D01*
X1541070Y975388D01*
Y975588D01*
X1542104D01*
Y975388D01*
G37*
G36*
G01X1539894Y975788D02*
X1540037Y976188D01*
X1540787D01*
X1540930Y975788D01*
Y975588D01*
X1539894D01*
Y975788D01*
G37*
G36*
G01X1537544D02*
X1537687Y976188D01*
X1538437D01*
X1538580Y975788D01*
Y975588D01*
X1537544D01*
Y975788D01*
G37*
G36*
G01X1537404Y975388D02*
X1537262Y974988D01*
X1536512D01*
X1536370Y975388D01*
Y975588D01*
X1537404D01*
Y975388D01*
G37*
G36*
G01X1535194Y975788D02*
X1535337Y976188D01*
X1536087D01*
X1536230Y975788D01*
Y975588D01*
X1535194D01*
Y975788D01*
G37*
G36*
G01X1535054Y974188D02*
X1534912Y973788D01*
X1534162D01*
X1534020Y974188D01*
Y974388D01*
X1535054D01*
Y974188D01*
G37*
G36*
G01X1539754D02*
X1539612Y973788D01*
X1538862D01*
X1538720Y974188D01*
Y974388D01*
X1539754D01*
Y974188D01*
G37*
G36*
G01X1542104D02*
X1541962Y973788D01*
X1541212D01*
X1541070Y974188D01*
Y974388D01*
X1542104D01*
Y974188D01*
G37*
G36*
G01X1537544Y974588D02*
X1537687Y974988D01*
X1538437D01*
X1538580Y974588D01*
Y974388D01*
X1537544D01*
Y974588D01*
G37*
G36*
G01X1539894D02*
X1540037Y974988D01*
X1540787D01*
X1540930Y974588D01*
Y974388D01*
X1539894D01*
Y974588D01*
G37*
G36*
G01X1537404Y974188D02*
X1537262Y973788D01*
X1536512D01*
X1536370Y974188D01*
Y974388D01*
X1537404D01*
Y974188D01*
G37*
G36*
G01X1535194Y974588D02*
X1535337Y974988D01*
X1536087D01*
X1536230Y974588D01*
Y974388D01*
X1535194D01*
Y974588D01*
G37*
G36*
G01X1535054Y972988D02*
X1534912Y972588D01*
X1534162D01*
X1534020Y972988D01*
Y973188D01*
X1535054D01*
Y972988D01*
G37*
G36*
G01X1532844Y973388D02*
X1532987Y973788D01*
X1533737D01*
X1533880Y973388D01*
Y973188D01*
X1532844D01*
Y973388D01*
G37*
G36*
G01X1539754Y972988D02*
X1539612Y972588D01*
X1538862D01*
X1538720Y972988D01*
Y973188D01*
X1539754D01*
Y972988D01*
G37*
G36*
G01X1542104D02*
X1541962Y972588D01*
X1541212D01*
X1541070Y972988D01*
Y973188D01*
X1542104D01*
Y972988D01*
G37*
G36*
G01X1537544Y973388D02*
X1537687Y973788D01*
X1538437D01*
X1538580Y973388D01*
Y973188D01*
X1537544D01*
Y973388D01*
G37*
G36*
G01X1539894D02*
X1540037Y973788D01*
X1540787D01*
X1540930Y973388D01*
Y973188D01*
X1539894D01*
Y973388D01*
G37*
G36*
G01X1537404Y972988D02*
X1537262Y972588D01*
X1536512D01*
X1536370Y972988D01*
Y973188D01*
X1537404D01*
Y972988D01*
G37*
G36*
G01X1535194Y973388D02*
X1535337Y973788D01*
X1536087D01*
X1536230Y973388D01*
Y973188D01*
X1535194D01*
Y973388D01*
G37*
G36*
G01X1532844Y970988D02*
X1532987Y971388D01*
X1533737D01*
X1533880Y970988D01*
Y970788D01*
X1532844D01*
Y970988D01*
G37*
G36*
G01X1535054Y970588D02*
X1534912Y970188D01*
X1534162D01*
X1534020Y970588D01*
Y970788D01*
X1535054D01*
Y970588D01*
G37*
G36*
G01X1532704D02*
X1532562Y970188D01*
X1531812D01*
X1531670Y970588D01*
Y970788D01*
X1532704D01*
Y970588D01*
G37*
G36*
G01X1539754D02*
X1539612Y970188D01*
X1538862D01*
X1538720Y970588D01*
Y970788D01*
X1539754D01*
Y970588D01*
G37*
G36*
G01X1542104D02*
X1541962Y970188D01*
X1541212D01*
X1541070Y970588D01*
Y970788D01*
X1542104D01*
Y970588D01*
G37*
G36*
G01X1537544Y970988D02*
X1537687Y971388D01*
X1538437D01*
X1538580Y970988D01*
Y970788D01*
X1537544D01*
Y970988D01*
G37*
G36*
G01X1539894D02*
X1540037Y971388D01*
X1540787D01*
X1540930Y970988D01*
Y970788D01*
X1539894D01*
Y970988D01*
G37*
G36*
G01X1537404Y970588D02*
X1537262Y970188D01*
X1536512D01*
X1536370Y970588D01*
Y970788D01*
X1537404D01*
Y970588D01*
G37*
G36*
G01X1535194Y970988D02*
X1535337Y971388D01*
X1536087D01*
X1536230Y970988D01*
Y970788D01*
X1535194D01*
Y970988D01*
G37*
G36*
G01X1535054Y968188D02*
X1534912Y967788D01*
X1534162D01*
X1534020Y968188D01*
Y968388D01*
X1535054D01*
Y968188D01*
G37*
G36*
G01X1530354D02*
X1530212Y967788D01*
X1529462D01*
X1529320Y968188D01*
Y968388D01*
X1530354D01*
Y968188D01*
G37*
G36*
G01X1532704D02*
X1532562Y967788D01*
X1531812D01*
X1531670Y968188D01*
Y968388D01*
X1532704D01*
Y968188D01*
G37*
G36*
G01X1532844Y968588D02*
X1532987Y968988D01*
X1533737D01*
X1533880Y968588D01*
Y968388D01*
X1532844D01*
Y968588D01*
G37*
G36*
G01X1530494D02*
X1530637Y968988D01*
X1531387D01*
X1531530Y968588D01*
Y968388D01*
X1530494D01*
Y968588D01*
G37*
G36*
G01X1537404Y968188D02*
X1537262Y967788D01*
X1536512D01*
X1536370Y968188D01*
Y968388D01*
X1537404D01*
Y968188D01*
G37*
G36*
G01X1535194Y968588D02*
X1535337Y968988D01*
X1536087D01*
X1536230Y968588D01*
Y968388D01*
X1535194D01*
Y968588D01*
G37*
G36*
G01X1537544D02*
X1537687Y968988D01*
X1538437D01*
X1538580Y968588D01*
Y968388D01*
X1537544D01*
Y968588D01*
G37*
G36*
G01X1532844Y969788D02*
X1532987Y970188D01*
X1533737D01*
X1533880Y969788D01*
Y969588D01*
X1532844D01*
Y969788D01*
G37*
G36*
G01X1535054Y969388D02*
X1534912Y968988D01*
X1534162D01*
X1534020Y969388D01*
Y969588D01*
X1535054D01*
Y969388D01*
G37*
G36*
G01X1532704D02*
X1532562Y968988D01*
X1531812D01*
X1531670Y969388D01*
Y969588D01*
X1532704D01*
Y969388D01*
G37*
G36*
G01X1530494Y969788D02*
X1530637Y970188D01*
X1531387D01*
X1531530Y969788D01*
Y969588D01*
X1530494D01*
Y969788D01*
G37*
G36*
G01X1539754Y969388D02*
X1539612Y968988D01*
X1538862D01*
X1538720Y969388D01*
Y969588D01*
X1539754D01*
Y969388D01*
G37*
G36*
G01X1537544Y969788D02*
X1537687Y970188D01*
X1538437D01*
X1538580Y969788D01*
Y969588D01*
X1537544D01*
Y969788D01*
G37*
G36*
G01X1539894D02*
X1540037Y970188D01*
X1540787D01*
X1540930Y969788D01*
Y969588D01*
X1539894D01*
Y969788D01*
G37*
G36*
G01X1537404Y969388D02*
X1537262Y968988D01*
X1536512D01*
X1536370Y969388D01*
Y969588D01*
X1537404D01*
Y969388D01*
G37*
G36*
G01X1535194Y969788D02*
X1535337Y970188D01*
X1536087D01*
X1536230Y969788D01*
Y969588D01*
X1535194D01*
Y969788D01*
G37*
G36*
G01X1532844Y967388D02*
X1532987Y967788D01*
X1533737D01*
X1533880Y967388D01*
Y967188D01*
X1532844D01*
Y967388D01*
G37*
G36*
G01X1535054Y966988D02*
X1534912Y966588D01*
X1534162D01*
X1534020Y966988D01*
Y967188D01*
X1535054D01*
Y966988D01*
G37*
G36*
G01X1530354D02*
X1530212Y966588D01*
X1529462D01*
X1529320Y966988D01*
Y967188D01*
X1530354D01*
Y966988D01*
G37*
G36*
G01X1530494Y967388D02*
X1530637Y967788D01*
X1531387D01*
X1531530Y967388D01*
Y967188D01*
X1530494D01*
Y967388D01*
G37*
G36*
G01X1532704Y966988D02*
X1532562Y966588D01*
X1531812D01*
X1531670Y966988D01*
Y967188D01*
X1532704D01*
Y966988D01*
G37*
G36*
G01X1537404D02*
X1537262Y966588D01*
X1536512D01*
X1536370Y966988D01*
Y967188D01*
X1537404D01*
Y966988D01*
G37*
G36*
G01X1535194Y967388D02*
X1535337Y967788D01*
X1536087D01*
X1536230Y967388D01*
Y967188D01*
X1535194D01*
Y967388D01*
G37*
G36*
G01X1532844Y972188D02*
X1532987Y972588D01*
X1533737D01*
X1533880Y972188D01*
Y971988D01*
X1532844D01*
Y972188D01*
G37*
G36*
G01X1535054Y971788D02*
X1534912Y971388D01*
X1534162D01*
X1534020Y971788D01*
Y971988D01*
X1535054D01*
Y971788D01*
G37*
G36*
G01X1539754D02*
X1539612Y971388D01*
X1538862D01*
X1538720Y971788D01*
Y971988D01*
X1539754D01*
Y971788D01*
G37*
G36*
G01X1542104D02*
X1541962Y971388D01*
X1541212D01*
X1541070Y971788D01*
Y971988D01*
X1542104D01*
Y971788D01*
G37*
G36*
G01X1537544Y972188D02*
X1537687Y972588D01*
X1538437D01*
X1538580Y972188D01*
Y971988D01*
X1537544D01*
Y972188D01*
G37*
G36*
G01X1539894D02*
X1540037Y972588D01*
X1540787D01*
X1540930Y972188D01*
Y971988D01*
X1539894D01*
Y972188D01*
G37*
G36*
G01X1537404Y971788D02*
X1537262Y971388D01*
X1536512D01*
X1536370Y971788D01*
Y971988D01*
X1537404D01*
Y971788D01*
G37*
G36*
G01X1535194Y972188D02*
X1535337Y972588D01*
X1536087D01*
X1536230Y972188D01*
Y971988D01*
X1535194D01*
Y972188D01*
G37*
G36*
G01X1533924Y1009155D02*
X1533742Y1009539D01*
X1534272Y1010069D01*
X1534656Y1009887D01*
X1534797Y1009745D01*
X1534066Y1009014D01*
X1533924Y1009155D01*
G37*
G36*
G01X1535770Y1010435D02*
X1535952Y1010051D01*
X1535421Y1009521D01*
X1535038Y1009703D01*
X1534896Y1009844D01*
X1535628Y1010576D01*
X1535770Y1010435D01*
G37*
G36*
G01X1534109Y1008774D02*
X1534291Y1008390D01*
X1533760Y1007860D01*
X1533377Y1008042D01*
X1533235Y1008183D01*
X1533967Y1008915D01*
X1534109Y1008774D01*
G37*
G36*
G01X1538909Y1014140D02*
X1538727Y1014524D01*
X1539258Y1015054D01*
X1539641Y1014872D01*
X1539783Y1014731D01*
X1539051Y1013999D01*
X1538909Y1014140D01*
G37*
G36*
G01X1539093Y1013758D02*
X1539275Y1013375D01*
X1538745Y1012844D01*
X1538361Y1013026D01*
X1538220Y1013168D01*
X1538952Y1013900D01*
X1539093Y1013758D01*
G37*
G36*
G01X1537248Y1012478D02*
X1537065Y1012862D01*
X1537596Y1013392D01*
X1537979Y1013210D01*
X1538121Y1013069D01*
X1537389Y1012337D01*
X1537248Y1012478D01*
G37*
G36*
G01X1535586Y1010817D02*
X1535404Y1011200D01*
X1535934Y1011731D01*
X1536318Y1011549D01*
X1536459Y1011407D01*
X1535727Y1010675D01*
X1535586Y1010817D01*
G37*
G36*
G01X1537431Y1012097D02*
X1537613Y1011713D01*
X1537083Y1011183D01*
X1536700Y1011365D01*
X1536558Y1011506D01*
X1537290Y1012238D01*
X1537431Y1012097D01*
G37*
G36*
G01X1534773Y1008306D02*
X1534591Y1008690D01*
X1535121Y1009220D01*
X1535505Y1009038D01*
X1535646Y1008896D01*
X1534915Y1008165D01*
X1534773Y1008306D01*
G37*
G36*
G01X1534958Y1007925D02*
X1535140Y1007541D01*
X1534609Y1007011D01*
X1534226Y1007193D01*
X1534084Y1007334D01*
X1534816Y1008066D01*
X1534958Y1007925D01*
G37*
G36*
G01X1539758Y1013291D02*
X1539576Y1013675D01*
X1540107Y1014205D01*
X1540490Y1014023D01*
X1540632Y1013882D01*
X1539900Y1013150D01*
X1539758Y1013291D01*
G37*
G36*
G01X1541604Y1014571D02*
X1541786Y1014187D01*
X1541256Y1013657D01*
X1540872Y1013839D01*
X1540731Y1013981D01*
X1541462Y1014712D01*
X1541604Y1014571D01*
G37*
G36*
G01X1538097Y1011629D02*
X1537914Y1012013D01*
X1538445Y1012543D01*
X1538828Y1012361D01*
X1538970Y1012220D01*
X1538238Y1011488D01*
X1538097Y1011629D01*
G37*
G36*
G01X1538280Y1011248D02*
X1538462Y1010864D01*
X1537932Y1010334D01*
X1537549Y1010516D01*
X1537407Y1010657D01*
X1538139Y1011389D01*
X1538280Y1011248D01*
G37*
G36*
G01X1536435Y1009968D02*
X1536253Y1010351D01*
X1536783Y1010882D01*
X1537167Y1010700D01*
X1537308Y1010558D01*
X1536576Y1009826D01*
X1536435Y1009968D01*
G37*
G36*
G01X1536619Y1009586D02*
X1536801Y1009202D01*
X1536270Y1008672D01*
X1535887Y1008854D01*
X1535745Y1008995D01*
X1536477Y1009727D01*
X1536619Y1009586D01*
G37*
G36*
G01X1539942Y1012909D02*
X1540124Y1012526D01*
X1539594Y1011995D01*
X1539210Y1012177D01*
X1539069Y1012319D01*
X1539801Y1013051D01*
X1539942Y1012909D01*
G37*
G36*
G01X1535807Y1007076D02*
X1535989Y1006692D01*
X1535458Y1006162D01*
X1535075Y1006344D01*
X1534933Y1006485D01*
X1535665Y1007217D01*
X1535807Y1007076D01*
G37*
G36*
G01X1533961Y1005796D02*
X1533779Y1006180D01*
X1534309Y1006710D01*
X1534693Y1006528D01*
X1534834Y1006386D01*
X1534103Y1005655D01*
X1533961Y1005796D01*
G37*
G36*
G01X1539129Y1010399D02*
X1539311Y1010015D01*
X1538781Y1009485D01*
X1538398Y1009667D01*
X1538256Y1009808D01*
X1538988Y1010540D01*
X1539129Y1010399D01*
G37*
G36*
G01X1538946Y1010780D02*
X1538763Y1011164D01*
X1539294Y1011694D01*
X1539677Y1011512D01*
X1539819Y1011371D01*
X1539087Y1010639D01*
X1538946Y1010780D01*
G37*
G36*
G01X1537284Y1009119D02*
X1537102Y1009502D01*
X1537632Y1010033D01*
X1538016Y1009851D01*
X1538157Y1009709D01*
X1537425Y1008977D01*
X1537284Y1009119D01*
G37*
G36*
G01X1540607Y1012442D02*
X1540425Y1012826D01*
X1540956Y1013356D01*
X1541339Y1013174D01*
X1541481Y1013033D01*
X1540749Y1012301D01*
X1540607Y1012442D01*
G37*
G36*
G01X1540791Y1012060D02*
X1540973Y1011677D01*
X1540443Y1011146D01*
X1540059Y1011328D01*
X1539918Y1011470D01*
X1540650Y1012202D01*
X1540791Y1012060D01*
G37*
G36*
G01X1537468Y1008737D02*
X1537650Y1008353D01*
X1537119Y1007823D01*
X1536736Y1008005D01*
X1536594Y1008146D01*
X1537326Y1008878D01*
X1537468Y1008737D01*
G37*
G36*
G01X1535622Y1007457D02*
X1535440Y1007841D01*
X1535970Y1008371D01*
X1536354Y1008189D01*
X1536495Y1008047D01*
X1535764Y1007316D01*
X1535622Y1007457D01*
G37*
G36*
G01X1534810Y1004947D02*
X1534628Y1005331D01*
X1535158Y1005861D01*
X1535542Y1005679D01*
X1535683Y1005537D01*
X1534952Y1004806D01*
X1534810Y1004947D01*
G37*
G36*
G01X1538133Y1008270D02*
X1537951Y1008653D01*
X1538481Y1009184D01*
X1538865Y1009002D01*
X1539006Y1008860D01*
X1538274Y1008128D01*
X1538133Y1008270D01*
G37*
G36*
G01X1539978Y1009550D02*
X1540160Y1009166D01*
X1539630Y1008636D01*
X1539247Y1008818D01*
X1539105Y1008959D01*
X1539837Y1009691D01*
X1539978Y1009550D01*
G37*
G36*
G01X1541640Y1011211D02*
X1541822Y1010828D01*
X1541292Y1010297D01*
X1540908Y1010479D01*
X1540767Y1010621D01*
X1541499Y1011353D01*
X1541640Y1011211D01*
G37*
G36*
G01X1539795Y1009931D02*
X1539612Y1010315D01*
X1540143Y1010845D01*
X1540526Y1010663D01*
X1540668Y1010522D01*
X1539936Y1009790D01*
X1539795Y1009931D01*
G37*
G36*
G01X1541456Y1011593D02*
X1541274Y1011977D01*
X1541805Y1012507D01*
X1542188Y1012325D01*
X1542330Y1012184D01*
X1541598Y1011452D01*
X1541456Y1011593D01*
G37*
G36*
G01X1538317Y1007888D02*
X1538499Y1007504D01*
X1537968Y1006974D01*
X1537585Y1007156D01*
X1537443Y1007297D01*
X1538175Y1008029D01*
X1538317Y1007888D01*
G37*
G36*
G01X1536656Y1006227D02*
X1536838Y1005843D01*
X1536307Y1005313D01*
X1535924Y1005495D01*
X1535782Y1005636D01*
X1536514Y1006368D01*
X1536656Y1006227D01*
G37*
G36*
G01X1536471Y1006608D02*
X1536289Y1006992D01*
X1536819Y1007522D01*
X1537203Y1007340D01*
X1537344Y1007198D01*
X1536613Y1006467D01*
X1536471Y1006608D01*
G37*
G36*
G01X1535843Y1003716D02*
X1536025Y1003332D01*
X1535494Y1002802D01*
X1535111Y1002984D01*
X1534969Y1003125D01*
X1535701Y1003857D01*
X1535843Y1003716D01*
G37*
G36*
G01X1540644Y1009082D02*
X1540461Y1009466D01*
X1540992Y1009996D01*
X1541375Y1009814D01*
X1541517Y1009673D01*
X1540785Y1008941D01*
X1540644Y1009082D01*
G37*
G36*
G01X1540827Y1008701D02*
X1541009Y1008317D01*
X1540479Y1007787D01*
X1540096Y1007969D01*
X1539954Y1008110D01*
X1540686Y1008842D01*
X1540827Y1008701D01*
G37*
G36*
G01X1542489Y1010362D02*
X1542671Y1009979D01*
X1542141Y1009448D01*
X1541757Y1009630D01*
X1541616Y1009772D01*
X1542348Y1010504D01*
X1542489Y1010362D01*
G37*
G36*
G01X1539166Y1007039D02*
X1539348Y1006655D01*
X1538817Y1006125D01*
X1538434Y1006307D01*
X1538292Y1006448D01*
X1539024Y1007180D01*
X1539166Y1007039D01*
G37*
G36*
G01X1538982Y1007421D02*
X1538800Y1007804D01*
X1539330Y1008335D01*
X1539714Y1008153D01*
X1539855Y1008011D01*
X1539123Y1007279D01*
X1538982Y1007421D01*
G37*
G36*
G01X1537504Y1005378D02*
X1537686Y1004994D01*
X1537156Y1004464D01*
X1536773Y1004646D01*
X1536631Y1004787D01*
X1537363Y1005519D01*
X1537504Y1005378D01*
G37*
G36*
G01X1535659Y1004098D02*
X1535477Y1004481D01*
X1536007Y1005012D01*
X1536391Y1004830D01*
X1536532Y1004688D01*
X1535800Y1003956D01*
X1535659Y1004098D01*
G37*
G36*
G01X1537320Y1005759D02*
X1537138Y1006143D01*
X1537668Y1006673D01*
X1538052Y1006491D01*
X1538193Y1006349D01*
X1537462Y1005618D01*
X1537320Y1005759D01*
G37*
G36*
G01X1541493Y1008233D02*
X1541310Y1008617D01*
X1541841Y1009147D01*
X1542224Y1008965D01*
X1542366Y1008824D01*
X1541634Y1008092D01*
X1541493Y1008233D01*
G37*
G36*
G01X1538169Y1004910D02*
X1537987Y1005294D01*
X1538517Y1005824D01*
X1538901Y1005642D01*
X1539042Y1005500D01*
X1538311Y1004769D01*
X1538169Y1004910D01*
G37*
G36*
G01X1536692Y1002867D02*
X1536874Y1002484D01*
X1536344Y1001953D01*
X1535960Y1002135D01*
X1535819Y1002277D01*
X1536551Y1003009D01*
X1536692Y1002867D01*
G37*
G36*
G01X1538353Y1004528D02*
X1538535Y1004145D01*
X1538005Y1003614D01*
X1537621Y1003796D01*
X1537480Y1003938D01*
X1538212Y1004670D01*
X1538353Y1004528D01*
G37*
G36*
G01X1536508Y1003249D02*
X1536326Y1003633D01*
X1536856Y1004163D01*
X1537240Y1003981D01*
X1537381Y1003839D01*
X1536650Y1003108D01*
X1536508Y1003249D01*
G37*
G36*
G01X1539831Y1006572D02*
X1539649Y1006955D01*
X1540179Y1007486D01*
X1540563Y1007304D01*
X1540704Y1007162D01*
X1539972Y1006430D01*
X1539831Y1006572D01*
G37*
G36*
G01X1540015Y1006190D02*
X1540197Y1005806D01*
X1539666Y1005276D01*
X1539283Y1005458D01*
X1539141Y1005599D01*
X1539873Y1006331D01*
X1540015Y1006190D01*
G37*
G36*
G01X1541676Y1007852D02*
X1541858Y1007468D01*
X1541328Y1006938D01*
X1540945Y1007120D01*
X1540803Y1007261D01*
X1541535Y1007993D01*
X1541676Y1007852D01*
G37*
G36*
G01X1537540Y1002017D02*
X1537722Y1001634D01*
X1537192Y1001104D01*
X1536808Y1001286D01*
X1536667Y1001427D01*
X1537399Y1002159D01*
X1537540Y1002017D01*
G37*
G36*
G01X1542525Y1007003D02*
X1542707Y1006619D01*
X1542177Y1006089D01*
X1541794Y1006271D01*
X1541652Y1006412D01*
X1542384Y1007144D01*
X1542525Y1007003D01*
G37*
G36*
G01X1540680Y1005723D02*
X1540498Y1006106D01*
X1541028Y1006637D01*
X1541412Y1006455D01*
X1541553Y1006313D01*
X1540821Y1005581D01*
X1540680Y1005723D01*
G37*
G36*
G01X1540864Y1005341D02*
X1541046Y1004957D01*
X1540515Y1004427D01*
X1540132Y1004609D01*
X1539990Y1004750D01*
X1540722Y1005482D01*
X1540864Y1005341D01*
G37*
G36*
G01X1537356Y1002399D02*
X1537174Y1002783D01*
X1537705Y1003313D01*
X1538088Y1003131D01*
X1538230Y1002990D01*
X1537498Y1002258D01*
X1537356Y1002399D01*
G37*
G36*
G01X1539202Y1003679D02*
X1539384Y1003296D01*
X1538854Y1002765D01*
X1538470Y1002947D01*
X1538329Y1003089D01*
X1539061Y1003821D01*
X1539202Y1003679D01*
G37*
G36*
G01X1539018Y1004061D02*
X1538836Y1004445D01*
X1539366Y1004975D01*
X1539750Y1004793D01*
X1539891Y1004651D01*
X1539160Y1003920D01*
X1539018Y1004061D01*
G37*
G36*
G01X1532189Y1014213D02*
X1532007Y1014597D01*
X1532538Y1015127D01*
X1532921Y1014945D01*
X1533063Y1014804D01*
X1532331Y1014072D01*
X1532189Y1014213D01*
G37*
G36*
G01X1535733Y1013795D02*
X1535915Y1013411D01*
X1535385Y1012881D01*
X1535002Y1013063D01*
X1534860Y1013204D01*
X1535592Y1013936D01*
X1535733Y1013795D01*
G37*
G36*
G01X1534072Y1012133D02*
X1534254Y1011749D01*
X1533723Y1011219D01*
X1533340Y1011401D01*
X1533198Y1011542D01*
X1533930Y1012274D01*
X1534072Y1012133D01*
G37*
G36*
G01X1533888Y1012515D02*
X1533706Y1012898D01*
X1534236Y1013429D01*
X1534620Y1013247D01*
X1534761Y1013105D01*
X1534029Y1012373D01*
X1533888Y1012515D01*
G37*
G36*
G01X1535550Y1014176D02*
X1535367Y1014560D01*
X1535898Y1015090D01*
X1536281Y1014908D01*
X1536423Y1014767D01*
X1535691Y1014035D01*
X1535550Y1014176D01*
G37*
G36*
G01X1534884Y1014644D02*
X1535066Y1014260D01*
X1534536Y1013730D01*
X1534153Y1013912D01*
X1534011Y1014053D01*
X1534743Y1014785D01*
X1534884Y1014644D01*
G37*
G36*
G01X1533039Y1013364D02*
X1532857Y1013747D01*
X1533387Y1014278D01*
X1533771Y1014096D01*
X1533912Y1013954D01*
X1533180Y1013222D01*
X1533039Y1013364D01*
G37*
G36*
G01X1533223Y1012982D02*
X1533405Y1012598D01*
X1532874Y1012068D01*
X1532491Y1012250D01*
X1532349Y1012391D01*
X1533081Y1013123D01*
X1533223Y1012982D01*
G37*
G36*
G01X1534921Y1011284D02*
X1535103Y1010900D01*
X1534572Y1010370D01*
X1534189Y1010552D01*
X1534047Y1010693D01*
X1534779Y1011425D01*
X1534921Y1011284D01*
G37*
G36*
G01X1534737Y1011666D02*
X1534555Y1012049D01*
X1535085Y1012580D01*
X1535469Y1012398D01*
X1535610Y1012256D01*
X1534878Y1011524D01*
X1534737Y1011666D01*
G37*
G36*
G01X1533075Y1010004D02*
X1532893Y1010388D01*
X1533423Y1010918D01*
X1533807Y1010736D01*
X1533948Y1010594D01*
X1533217Y1009863D01*
X1533075Y1010004D01*
G37*
G36*
G01X1536399Y1013327D02*
X1536216Y1013711D01*
X1536747Y1014241D01*
X1537130Y1014059D01*
X1537272Y1013918D01*
X1536540Y1013186D01*
X1536399Y1013327D01*
G37*
G36*
G01X1538244Y1014607D02*
X1538426Y1014224D01*
X1537896Y1013693D01*
X1537512Y1013875D01*
X1537371Y1014017D01*
X1538103Y1014749D01*
X1538244Y1014607D01*
G37*
G36*
G01X1536582Y1012946D02*
X1536764Y1012562D01*
X1536234Y1012032D01*
X1535851Y1012214D01*
X1535709Y1012355D01*
X1536441Y1013087D01*
X1536582Y1012946D01*
G37*
G36*
G01X1540051Y1002830D02*
X1540233Y1002447D01*
X1539703Y1001916D01*
X1539319Y1002098D01*
X1539178Y1002240D01*
X1539910Y1002972D01*
X1540051Y1002830D01*
G37*
G36*
G01X1539867Y1003212D02*
X1539685Y1003596D01*
X1540215Y1004126D01*
X1540599Y1003944D01*
X1540740Y1003802D01*
X1540009Y1003071D01*
X1539867Y1003212D01*
G37*
G36*
G01X1541529Y1004874D02*
X1541347Y1005257D01*
X1541877Y1005788D01*
X1542261Y1005606D01*
X1542402Y1005464D01*
X1541670Y1004732D01*
X1541529Y1004874D01*
G37*
G36*
G01X1541713Y1004492D02*
X1541895Y1004108D01*
X1541364Y1003578D01*
X1540981Y1003760D01*
X1540839Y1003901D01*
X1541571Y1004633D01*
X1541713Y1004492D01*
G37*
G36*
G01X1538205Y1001550D02*
X1538023Y1001934D01*
X1538554Y1002464D01*
X1538937Y1002282D01*
X1539079Y1002141D01*
X1538347Y1001409D01*
X1538205Y1001550D01*
G37*
G36*
G01X1536544Y999889D02*
X1536362Y1000272D01*
X1536892Y1000803D01*
X1537276Y1000620D01*
X1537417Y1000479D01*
X1536685Y999747D01*
X1536544Y999889D01*
G37*
G36*
G01X1538389Y1001168D02*
X1538571Y1000785D01*
X1538041Y1000255D01*
X1537657Y1000437D01*
X1537516Y1000578D01*
X1538248Y1001310D01*
X1538389Y1001168D01*
G37*
G36*
G01X1540755Y1015420D02*
X1540937Y1015036D01*
X1540407Y1014506D01*
X1540023Y1014688D01*
X1539882Y1014830D01*
X1540613Y1015561D01*
X1540755Y1015420D01*
G37*
G36*
G01X1533475Y1026223D02*
X1533657Y1025839D01*
X1533127Y1025309D01*
X1532743Y1025491D01*
X1532602Y1025633D01*
X1533334Y1026365D01*
X1533475Y1026223D01*
G37*
G36*
G01X1534953Y1028267D02*
X1534771Y1028650D01*
X1535301Y1029181D01*
X1535685Y1028998D01*
X1535826Y1028857D01*
X1535094Y1028125D01*
X1534953Y1028267D01*
G37*
G36*
G01X1535137Y1027885D02*
X1535319Y1027501D01*
X1534788Y1026971D01*
X1534405Y1027153D01*
X1534263Y1027294D01*
X1534995Y1028026D01*
X1535137Y1027885D01*
G37*
G36*
G01X1533291Y1026605D02*
X1533109Y1026989D01*
X1533639Y1027519D01*
X1534023Y1027337D01*
X1534164Y1027195D01*
X1533433Y1026464D01*
X1533291Y1026605D01*
G37*
G36*
G01X1536798Y1029546D02*
X1536980Y1029163D01*
X1536450Y1028633D01*
X1536066Y1028815D01*
X1535925Y1028956D01*
X1536657Y1029688D01*
X1536798Y1029546D01*
G37*
G36*
G01X1536614Y1029928D02*
X1536432Y1030312D01*
X1536963Y1030842D01*
X1537346Y1030660D01*
X1537488Y1030519D01*
X1536756Y1029787D01*
X1536614Y1029928D01*
G37*
G36*
G01X1538460Y1031208D02*
X1538642Y1030825D01*
X1538112Y1030294D01*
X1537728Y1030476D01*
X1537587Y1030618D01*
X1538319Y1031350D01*
X1538460Y1031208D01*
G37*
G36*
G01X1534989Y1024907D02*
X1534807Y1025291D01*
X1535337Y1025821D01*
X1535721Y1025639D01*
X1535862Y1025497D01*
X1535131Y1024766D01*
X1534989Y1024907D01*
G37*
G36*
G01X1535173Y1024525D02*
X1535355Y1024141D01*
X1534825Y1023611D01*
X1534441Y1023793D01*
X1534300Y1023935D01*
X1535032Y1024667D01*
X1535173Y1024525D01*
G37*
G36*
G01X1538312Y1028230D02*
X1538130Y1028614D01*
X1538661Y1029144D01*
X1539044Y1028962D01*
X1539186Y1028821D01*
X1538454Y1028089D01*
X1538312Y1028230D01*
G37*
G36*
G01X1540158Y1029510D02*
X1540340Y1029127D01*
X1539810Y1028596D01*
X1539426Y1028778D01*
X1539285Y1028920D01*
X1540017Y1029652D01*
X1540158Y1029510D01*
G37*
G36*
G01X1541820Y1031172D02*
X1542002Y1030788D01*
X1541471Y1030258D01*
X1541088Y1030440D01*
X1540946Y1030581D01*
X1541678Y1031313D01*
X1541820Y1031172D01*
G37*
G36*
G01X1539974Y1029892D02*
X1539792Y1030276D01*
X1540322Y1030806D01*
X1540706Y1030624D01*
X1540847Y1030482D01*
X1540116Y1029751D01*
X1539974Y1029892D01*
G37*
G36*
G01X1536835Y1026187D02*
X1537017Y1025803D01*
X1536486Y1025273D01*
X1536103Y1025455D01*
X1535961Y1025596D01*
X1536693Y1026328D01*
X1536835Y1026187D01*
G37*
G36*
G01X1538496Y1027848D02*
X1538678Y1027465D01*
X1538148Y1026935D01*
X1537764Y1027117D01*
X1537623Y1027258D01*
X1538355Y1027990D01*
X1538496Y1027848D01*
G37*
G36*
G01X1536651Y1026569D02*
X1536469Y1026952D01*
X1536999Y1027483D01*
X1537383Y1027300D01*
X1537524Y1027159D01*
X1536792Y1026427D01*
X1536651Y1026569D01*
G37*
G36*
G01X1534324Y1025374D02*
X1534506Y1024990D01*
X1533976Y1024460D01*
X1533592Y1024642D01*
X1533451Y1024784D01*
X1534183Y1025516D01*
X1534324Y1025374D01*
G37*
G36*
G01X1534140Y1025756D02*
X1533958Y1026140D01*
X1534488Y1026670D01*
X1534872Y1026488D01*
X1535013Y1026346D01*
X1534282Y1025615D01*
X1534140Y1025756D01*
G37*
G36*
G01X1539309Y1030359D02*
X1539491Y1029976D01*
X1538961Y1029445D01*
X1538577Y1029627D01*
X1538436Y1029769D01*
X1539168Y1030501D01*
X1539309Y1030359D01*
G37*
G36*
G01X1537463Y1029079D02*
X1537281Y1029463D01*
X1537812Y1029993D01*
X1538195Y1029811D01*
X1538337Y1029670D01*
X1537605Y1028938D01*
X1537463Y1029079D01*
G37*
G36*
G01X1539125Y1030741D02*
X1538943Y1031125D01*
X1539473Y1031655D01*
X1539857Y1031473D01*
X1539998Y1031331D01*
X1539267Y1030600D01*
X1539125Y1030741D01*
G37*
G36*
G01X1535986Y1027036D02*
X1536168Y1026652D01*
X1535637Y1026122D01*
X1535254Y1026304D01*
X1535112Y1026445D01*
X1535844Y1027177D01*
X1535986Y1027036D01*
G37*
G36*
G01X1537647Y1028697D02*
X1537829Y1028314D01*
X1537299Y1027784D01*
X1536915Y1027966D01*
X1536774Y1028107D01*
X1537506Y1028839D01*
X1537647Y1028697D01*
G37*
G36*
G01X1535802Y1027418D02*
X1535620Y1027801D01*
X1536150Y1028332D01*
X1536534Y1028149D01*
X1536675Y1028008D01*
X1535943Y1027276D01*
X1535802Y1027418D01*
G37*
G36*
G01X1540823Y1029043D02*
X1540641Y1029427D01*
X1541171Y1029957D01*
X1541555Y1029775D01*
X1541696Y1029633D01*
X1540965Y1028902D01*
X1540823Y1029043D01*
G37*
G36*
G01X1539161Y1027381D02*
X1538979Y1027765D01*
X1539510Y1028295D01*
X1539893Y1028113D01*
X1540035Y1027972D01*
X1539303Y1027240D01*
X1539161Y1027381D01*
G37*
G36*
G01X1539345Y1026999D02*
X1539527Y1026616D01*
X1538997Y1026086D01*
X1538613Y1026268D01*
X1538472Y1026409D01*
X1539204Y1027141D01*
X1539345Y1026999D01*
G37*
G36*
G01X1541007Y1028661D02*
X1541189Y1028278D01*
X1540659Y1027747D01*
X1540275Y1027929D01*
X1540134Y1028071D01*
X1540866Y1028803D01*
X1541007Y1028661D01*
G37*
G36*
G01X1537500Y1025720D02*
X1537318Y1026103D01*
X1537848Y1026634D01*
X1538232Y1026451D01*
X1538373Y1026310D01*
X1537641Y1025578D01*
X1537500Y1025720D01*
G37*
G36*
G01X1535838Y1024058D02*
X1535656Y1024442D01*
X1536186Y1024972D01*
X1536570Y1024790D01*
X1536711Y1024648D01*
X1535980Y1023917D01*
X1535838Y1024058D01*
G37*
G36*
G01X1536022Y1023676D02*
X1536204Y1023292D01*
X1535674Y1022762D01*
X1535290Y1022944D01*
X1535149Y1023086D01*
X1535881Y1023818D01*
X1536022Y1023676D01*
G37*
G36*
G01X1537684Y1025338D02*
X1537866Y1024954D01*
X1537335Y1024424D01*
X1536952Y1024606D01*
X1536810Y1024747D01*
X1537542Y1025479D01*
X1537684Y1025338D01*
G37*
G36*
G01X1535697Y1017155D02*
X1535879Y1016771D01*
X1535348Y1016241D01*
X1534965Y1016423D01*
X1534823Y1016564D01*
X1535555Y1017296D01*
X1535697Y1017155D01*
G37*
G36*
G01X1534035Y1015493D02*
X1534217Y1015109D01*
X1533687Y1014579D01*
X1533303Y1014761D01*
X1533162Y1014903D01*
X1533893Y1015634D01*
X1534035Y1015493D01*
G37*
G36*
G01X1533851Y1015875D02*
X1533669Y1016259D01*
X1534199Y1016789D01*
X1534583Y1016607D01*
X1534724Y1016465D01*
X1533992Y1015733D01*
X1533851Y1015875D01*
G37*
G36*
G01X1538836Y1020860D02*
X1538654Y1021244D01*
X1539184Y1021774D01*
X1539568Y1021592D01*
X1539709Y1021450D01*
X1538978Y1020719D01*
X1538836Y1020860D01*
G37*
G36*
G01X1539020Y1020478D02*
X1539202Y1020095D01*
X1538672Y1019564D01*
X1538288Y1019746D01*
X1538147Y1019888D01*
X1538879Y1020620D01*
X1539020Y1020478D01*
G37*
G36*
G01X1537174Y1019198D02*
X1536992Y1019582D01*
X1537523Y1020112D01*
X1537906Y1019930D01*
X1538048Y1019789D01*
X1537316Y1019057D01*
X1537174Y1019198D01*
G37*
G36*
G01X1535513Y1017537D02*
X1535331Y1017920D01*
X1535861Y1018451D01*
X1536245Y1018268D01*
X1536386Y1018127D01*
X1535654Y1017395D01*
X1535513Y1017537D01*
G37*
G36*
G01X1537358Y1018816D02*
X1537540Y1018433D01*
X1537010Y1017903D01*
X1536626Y1018085D01*
X1536485Y1018226D01*
X1537217Y1018958D01*
X1537358Y1018816D01*
G37*
G36*
G01X1538873Y1017500D02*
X1538691Y1017883D01*
X1539221Y1018414D01*
X1539605Y1018232D01*
X1539746Y1018090D01*
X1539014Y1017358D01*
X1538873Y1017500D01*
G37*
G36*
G01X1539057Y1017118D02*
X1539239Y1016734D01*
X1538709Y1016204D01*
X1538325Y1016386D01*
X1538184Y1016528D01*
X1538915Y1017259D01*
X1539057Y1017118D01*
G37*
G36*
G01X1540719Y1018780D02*
X1540901Y1018396D01*
X1540370Y1017866D01*
X1539987Y1018048D01*
X1539845Y1018189D01*
X1540577Y1018921D01*
X1540719Y1018780D01*
G37*
G36*
G01X1537395Y1015456D02*
X1537577Y1015073D01*
X1537047Y1014542D01*
X1536663Y1014724D01*
X1536522Y1014866D01*
X1537254Y1015598D01*
X1537395Y1015456D01*
G37*
G36*
G01X1537211Y1015838D02*
X1537029Y1016222D01*
X1537560Y1016752D01*
X1537943Y1016570D01*
X1538085Y1016429D01*
X1537353Y1015697D01*
X1537211Y1015838D01*
G37*
G36*
G01X1534701Y1015025D02*
X1534518Y1015409D01*
X1535049Y1015939D01*
X1535432Y1015757D01*
X1535574Y1015616D01*
X1534842Y1014884D01*
X1534701Y1015025D01*
G37*
G36*
G01X1539870Y1019629D02*
X1540052Y1019245D01*
X1539521Y1018715D01*
X1539138Y1018897D01*
X1538996Y1019038D01*
X1539728Y1019770D01*
X1539870Y1019629D01*
G37*
G36*
G01X1538024Y1018349D02*
X1537842Y1018732D01*
X1538372Y1019263D01*
X1538756Y1019081D01*
X1538897Y1018939D01*
X1538165Y1018207D01*
X1538024Y1018349D01*
G37*
G36*
G01X1538208Y1017967D02*
X1538390Y1017583D01*
X1537860Y1017053D01*
X1537476Y1017235D01*
X1537335Y1017377D01*
X1538066Y1018108D01*
X1538208Y1017967D01*
G37*
G36*
G01X1536546Y1016305D02*
X1536728Y1015922D01*
X1536198Y1015391D01*
X1535814Y1015573D01*
X1535673Y1015715D01*
X1536405Y1016447D01*
X1536546Y1016305D01*
G37*
G36*
G01X1536362Y1016687D02*
X1536180Y1017071D01*
X1536711Y1017601D01*
X1537094Y1017419D01*
X1537236Y1017278D01*
X1536504Y1016546D01*
X1536362Y1016687D01*
G37*
G36*
G01X1539906Y1016269D02*
X1540088Y1015885D01*
X1539558Y1015355D01*
X1539174Y1015537D01*
X1539033Y1015679D01*
X1539764Y1016410D01*
X1539906Y1016269D01*
G37*
G36*
G01X1539722Y1016651D02*
X1539540Y1017034D01*
X1540070Y1017565D01*
X1540454Y1017383D01*
X1540595Y1017241D01*
X1539863Y1016509D01*
X1539722Y1016651D01*
G37*
G36*
G01X1538060Y1014989D02*
X1537878Y1015373D01*
X1538409Y1015903D01*
X1538792Y1015721D01*
X1538934Y1015580D01*
X1538202Y1014848D01*
X1538060Y1014989D01*
G37*
G36*
G01X1533249Y1039585D02*
X1533431Y1039201D01*
X1532901Y1038671D01*
X1532518Y1038853D01*
X1532376Y1038994D01*
X1533108Y1039726D01*
X1533249Y1039585D01*
G37*
G36*
G01X1533066Y1039966D02*
X1532883Y1040350D01*
X1533414Y1040880D01*
X1533797Y1040698D01*
X1533939Y1040557D01*
X1533207Y1039825D01*
X1533066Y1039966D01*
G37*
G36*
G01X1529926Y1036261D02*
X1530108Y1035878D01*
X1529578Y1035347D01*
X1529194Y1035529D01*
X1529053Y1035671D01*
X1529785Y1036403D01*
X1529926Y1036261D01*
G37*
G36*
G01X1531588Y1037923D02*
X1531770Y1037539D01*
X1531239Y1037009D01*
X1530856Y1037191D01*
X1530714Y1037332D01*
X1531446Y1038064D01*
X1531588Y1037923D01*
G37*
G36*
G01X1534727Y1041628D02*
X1534545Y1042012D01*
X1535075Y1042542D01*
X1535459Y1042360D01*
X1535601Y1042219D01*
X1534869Y1041487D01*
X1534727Y1041628D01*
G37*
G36*
G01X1534911Y1041246D02*
X1535093Y1040863D01*
X1534563Y1040332D01*
X1534179Y1040514D01*
X1534038Y1040656D01*
X1534770Y1041388D01*
X1534911Y1041246D01*
G37*
G36*
G01X1536573Y1042908D02*
X1536755Y1042524D01*
X1536225Y1041994D01*
X1535841Y1042176D01*
X1535700Y1042318D01*
X1536431Y1043049D01*
X1536573Y1042908D01*
G37*
G36*
G01X1539712Y1046613D02*
X1539530Y1046997D01*
X1540061Y1047527D01*
X1540444Y1047345D01*
X1540586Y1047204D01*
X1539854Y1046472D01*
X1539712Y1046613D01*
G37*
G36*
G01X1538051Y1044951D02*
X1537869Y1045335D01*
X1538399Y1045865D01*
X1538783Y1045683D01*
X1538924Y1045542D01*
X1538192Y1044810D01*
X1538051Y1044951D01*
G37*
G36*
G01X1539896Y1046231D02*
X1540078Y1045848D01*
X1539548Y1045317D01*
X1539164Y1045499D01*
X1539023Y1045641D01*
X1539755Y1046373D01*
X1539896Y1046231D01*
G37*
G36*
G01X1538234Y1044570D02*
X1538417Y1044186D01*
X1537886Y1043656D01*
X1537503Y1043838D01*
X1537361Y1043979D01*
X1538093Y1044711D01*
X1538234Y1044570D01*
G37*
G36*
G01X1536389Y1043290D02*
X1536207Y1043673D01*
X1536737Y1044204D01*
X1537121Y1044022D01*
X1537262Y1043880D01*
X1536530Y1043148D01*
X1536389Y1043290D01*
G37*
G36*
G01X1531624Y1034563D02*
X1531806Y1034180D01*
X1531276Y1033649D01*
X1530892Y1033831D01*
X1530751Y1033973D01*
X1531483Y1034705D01*
X1531624Y1034563D01*
G37*
G36*
G01X1534947Y1037887D02*
X1535129Y1037503D01*
X1534599Y1036973D01*
X1534216Y1037155D01*
X1534074Y1037296D01*
X1534806Y1038028D01*
X1534947Y1037887D01*
G37*
G36*
G01X1534764Y1038268D02*
X1534581Y1038652D01*
X1535112Y1039182D01*
X1535495Y1039000D01*
X1535637Y1038859D01*
X1534905Y1038127D01*
X1534764Y1038268D01*
G37*
G36*
G01X1533286Y1036225D02*
X1533468Y1035841D01*
X1532937Y1035311D01*
X1532554Y1035493D01*
X1532412Y1035634D01*
X1533144Y1036366D01*
X1533286Y1036225D01*
G37*
G36*
G01X1533102Y1036607D02*
X1532920Y1036990D01*
X1533450Y1037521D01*
X1533834Y1037339D01*
X1533975Y1037197D01*
X1533243Y1036465D01*
X1533102Y1036607D01*
G37*
G36*
G01X1531440Y1034945D02*
X1531258Y1035329D01*
X1531788Y1035859D01*
X1532172Y1035677D01*
X1532313Y1035535D01*
X1531582Y1034804D01*
X1531440Y1034945D01*
G37*
G36*
G01X1541594Y1044533D02*
X1541776Y1044150D01*
X1541246Y1043619D01*
X1540862Y1043801D01*
X1540721Y1043943D01*
X1541453Y1044675D01*
X1541594Y1044533D01*
G37*
G36*
G01X1539749Y1043253D02*
X1539567Y1043637D01*
X1540097Y1044167D01*
X1540481Y1043985D01*
X1540622Y1043844D01*
X1539890Y1043112D01*
X1539749Y1043253D01*
G37*
G36*
G01X1539932Y1042872D02*
X1540115Y1042488D01*
X1539584Y1041958D01*
X1539201Y1042140D01*
X1539059Y1042281D01*
X1539791Y1043013D01*
X1539932Y1042872D01*
G37*
G36*
G01X1536425Y1039930D02*
X1536243Y1040314D01*
X1536773Y1040844D01*
X1537157Y1040662D01*
X1537299Y1040521D01*
X1536567Y1039789D01*
X1536425Y1039930D01*
G37*
G36*
G01X1536609Y1039548D02*
X1536791Y1039165D01*
X1536261Y1038634D01*
X1535877Y1038816D01*
X1535736Y1038958D01*
X1536468Y1039690D01*
X1536609Y1039548D01*
G37*
G36*
G01X1538271Y1041210D02*
X1538453Y1040826D01*
X1537923Y1040296D01*
X1537539Y1040478D01*
X1537398Y1040620D01*
X1538129Y1041351D01*
X1538271Y1041210D01*
G37*
G36*
G01X1538087Y1041592D02*
X1537905Y1041975D01*
X1538435Y1042506D01*
X1538819Y1042324D01*
X1538960Y1042182D01*
X1538228Y1041450D01*
X1538087Y1041592D01*
G37*
G36*
G01X1541410Y1044915D02*
X1541228Y1045299D01*
X1541759Y1045829D01*
X1542142Y1045647D01*
X1542284Y1045506D01*
X1541552Y1044774D01*
X1541410Y1044915D01*
G37*
G36*
G01X1530775Y1035412D02*
X1530957Y1035029D01*
X1530427Y1034498D01*
X1530043Y1034680D01*
X1529902Y1034822D01*
X1530634Y1035554D01*
X1530775Y1035412D01*
G37*
G36*
G01X1530591Y1035794D02*
X1530409Y1036178D01*
X1530939Y1036708D01*
X1531323Y1036526D01*
X1531464Y1036384D01*
X1530733Y1035653D01*
X1530591Y1035794D01*
G37*
G36*
G01X1532437Y1037074D02*
X1532619Y1036690D01*
X1532088Y1036160D01*
X1531705Y1036342D01*
X1531563Y1036483D01*
X1532295Y1037215D01*
X1532437Y1037074D01*
G37*
G36*
G01X1532253Y1037456D02*
X1532071Y1037839D01*
X1532601Y1038370D01*
X1532985Y1038188D01*
X1533126Y1038046D01*
X1532394Y1037314D01*
X1532253Y1037456D01*
G37*
G36*
G01X1533915Y1039117D02*
X1533732Y1039501D01*
X1534263Y1040031D01*
X1534646Y1039849D01*
X1534788Y1039708D01*
X1534056Y1038976D01*
X1533915Y1039117D01*
G37*
G36*
G01X1535760Y1040397D02*
X1535942Y1040014D01*
X1535412Y1039483D01*
X1535028Y1039665D01*
X1534887Y1039807D01*
X1535619Y1040539D01*
X1535760Y1040397D01*
G37*
G36*
G01X1534098Y1038736D02*
X1534280Y1038352D01*
X1533750Y1037822D01*
X1533367Y1038004D01*
X1533225Y1038145D01*
X1533957Y1038877D01*
X1534098Y1038736D01*
G37*
G36*
G01X1542407Y1047044D02*
X1542589Y1046660D01*
X1542059Y1046130D01*
X1541675Y1046312D01*
X1541534Y1046454D01*
X1542265Y1047185D01*
X1542407Y1047044D01*
G37*
G36*
G01X1535576Y1040779D02*
X1535394Y1041163D01*
X1535924Y1041693D01*
X1536308Y1041511D01*
X1536450Y1041370D01*
X1535718Y1040638D01*
X1535576Y1040779D01*
G37*
G36*
G01X1537422Y1042059D02*
X1537604Y1041675D01*
X1537074Y1041145D01*
X1536690Y1041327D01*
X1536549Y1041469D01*
X1537280Y1042200D01*
X1537422Y1042059D01*
G37*
G36*
G01X1537238Y1042441D02*
X1537056Y1042824D01*
X1537586Y1043355D01*
X1537970Y1043173D01*
X1538111Y1043031D01*
X1537379Y1042299D01*
X1537238Y1042441D01*
G37*
G36*
G01X1540561Y1045764D02*
X1540379Y1046148D01*
X1540910Y1046678D01*
X1541293Y1046496D01*
X1541435Y1046355D01*
X1540703Y1045623D01*
X1540561Y1045764D01*
G37*
G36*
G01X1538900Y1044102D02*
X1538718Y1044486D01*
X1539248Y1045016D01*
X1539632Y1044834D01*
X1539773Y1044693D01*
X1539041Y1043961D01*
X1538900Y1044102D01*
G37*
G36*
G01X1540745Y1045382D02*
X1540927Y1044999D01*
X1540397Y1044468D01*
X1540013Y1044650D01*
X1539872Y1044792D01*
X1540604Y1045524D01*
X1540745Y1045382D01*
G37*
G36*
G01X1539083Y1043721D02*
X1539266Y1043337D01*
X1538735Y1042807D01*
X1538352Y1042989D01*
X1538210Y1043130D01*
X1538942Y1043862D01*
X1539083Y1043721D01*
G37*
G36*
G01X1532473Y1033714D02*
X1532655Y1033331D01*
X1532125Y1032800D01*
X1531741Y1032982D01*
X1531600Y1033124D01*
X1532332Y1033856D01*
X1532473Y1033714D01*
G37*
G36*
G01X1532289Y1034096D02*
X1532107Y1034480D01*
X1532637Y1035010D01*
X1533021Y1034828D01*
X1533162Y1034686D01*
X1532431Y1033955D01*
X1532289Y1034096D01*
G37*
G36*
G01X1534135Y1035376D02*
X1534317Y1034992D01*
X1533786Y1034462D01*
X1533403Y1034644D01*
X1533261Y1034785D01*
X1533993Y1035517D01*
X1534135Y1035376D01*
G37*
G36*
G01X1533951Y1035758D02*
X1533769Y1036141D01*
X1534299Y1036672D01*
X1534683Y1036490D01*
X1534824Y1036348D01*
X1534092Y1035616D01*
X1533951Y1035758D01*
G37*
G36*
G01X1535796Y1037038D02*
X1535978Y1036654D01*
X1535448Y1036124D01*
X1535065Y1036306D01*
X1534923Y1036447D01*
X1535655Y1037179D01*
X1535796Y1037038D01*
G37*
G36*
G01X1540781Y1042023D02*
X1540964Y1041639D01*
X1540433Y1041109D01*
X1540050Y1041291D01*
X1539908Y1041432D01*
X1540640Y1042164D01*
X1540781Y1042023D01*
G37*
G36*
G01X1542443Y1043684D02*
X1542625Y1043301D01*
X1542095Y1042770D01*
X1541711Y1042952D01*
X1541570Y1043094D01*
X1542302Y1043826D01*
X1542443Y1043684D01*
G37*
G36*
G01X1538936Y1040743D02*
X1538754Y1041126D01*
X1539284Y1041657D01*
X1539668Y1041475D01*
X1539809Y1041333D01*
X1539077Y1040601D01*
X1538936Y1040743D01*
G37*
G36*
G01X1539120Y1040361D02*
X1539302Y1039977D01*
X1538772Y1039447D01*
X1538388Y1039629D01*
X1538247Y1039771D01*
X1538978Y1040502D01*
X1539120Y1040361D01*
G37*
G36*
G01X1537274Y1039081D02*
X1537092Y1039465D01*
X1537622Y1039995D01*
X1538006Y1039813D01*
X1538148Y1039672D01*
X1537416Y1038940D01*
X1537274Y1039081D01*
G37*
G36*
G01X1540598Y1042404D02*
X1540416Y1042788D01*
X1540946Y1043318D01*
X1541330Y1043136D01*
X1541471Y1042995D01*
X1540739Y1042263D01*
X1540598Y1042404D01*
G37*
G36*
G01X1535613Y1037419D02*
X1535430Y1037803D01*
X1535961Y1038333D01*
X1536344Y1038151D01*
X1536486Y1038010D01*
X1535754Y1037278D01*
X1535613Y1037419D01*
G37*
G36*
G01X1537458Y1038699D02*
X1537640Y1038316D01*
X1537110Y1037785D01*
X1536726Y1037967D01*
X1536585Y1038109D01*
X1537317Y1038841D01*
X1537458Y1038699D01*
G37*
G36*
G01X1540122Y1032870D02*
X1540304Y1032486D01*
X1539773Y1031956D01*
X1539390Y1032138D01*
X1539248Y1032279D01*
X1539980Y1033011D01*
X1540122Y1032870D01*
G37*
G36*
G01X1538276Y1031590D02*
X1538094Y1031974D01*
X1538624Y1032504D01*
X1539008Y1032322D01*
X1539149Y1032180D01*
X1538418Y1031449D01*
X1538276Y1031590D01*
G37*
G36*
G01X1539938Y1033252D02*
X1539756Y1033635D01*
X1540286Y1034166D01*
X1540670Y1033984D01*
X1540811Y1033842D01*
X1540079Y1033110D01*
X1539938Y1033252D01*
G37*
G36*
G01X1541783Y1034532D02*
X1541966Y1034148D01*
X1541435Y1033618D01*
X1541052Y1033800D01*
X1540910Y1033941D01*
X1541642Y1034673D01*
X1541783Y1034532D01*
G37*
G36*
G01X1541600Y1034913D02*
X1541418Y1035297D01*
X1541948Y1035827D01*
X1542331Y1035645D01*
X1542473Y1035504D01*
X1541741Y1034772D01*
X1541600Y1034913D01*
G37*
G36*
G01X1541636Y1031554D02*
X1541454Y1031937D01*
X1541984Y1032468D01*
X1542368Y1032286D01*
X1542509Y1032144D01*
X1541777Y1031412D01*
X1541636Y1031554D01*
G37*
G36*
G01X1540971Y1032021D02*
X1541153Y1031637D01*
X1540622Y1031107D01*
X1540239Y1031289D01*
X1540097Y1031430D01*
X1540829Y1032162D01*
X1540971Y1032021D01*
G37*
G36*
G01X1540787Y1032403D02*
X1540605Y1032786D01*
X1541135Y1033317D01*
X1541519Y1033135D01*
X1541660Y1032993D01*
X1540928Y1032261D01*
X1540787Y1032403D01*
G37*
G36*
G01X1530686Y1045669D02*
X1530504Y1046053D01*
X1531034Y1046583D01*
X1531418Y1046401D01*
X1531560Y1046260D01*
X1530828Y1045528D01*
X1530686Y1045669D01*
G37*
G36*
G01X1530870Y1045287D02*
X1531052Y1044904D01*
X1530522Y1044373D01*
X1530138Y1044555D01*
X1529997Y1044697D01*
X1530729Y1045429D01*
X1530870Y1045287D01*
G37*
G36*
G01X1532532Y1046949D02*
X1532714Y1046565D01*
X1532184Y1046035D01*
X1531800Y1046217D01*
X1531659Y1046359D01*
X1532390Y1047090D01*
X1532532Y1046949D01*
G37*
G36*
G01X1532569Y1043589D02*
X1532751Y1043205D01*
X1532220Y1042675D01*
X1531837Y1042857D01*
X1531695Y1042998D01*
X1532427Y1043730D01*
X1532569Y1043589D01*
G37*
G36*
G01X1532385Y1043971D02*
X1532203Y1044354D01*
X1532733Y1044885D01*
X1533117Y1044702D01*
X1533258Y1044561D01*
X1532526Y1043829D01*
X1532385Y1043971D01*
G37*
G36*
G01X1534046Y1045632D02*
X1533864Y1046016D01*
X1534395Y1046546D01*
X1534778Y1046364D01*
X1534920Y1046223D01*
X1534188Y1045491D01*
X1534046Y1045632D01*
G37*
G36*
G01X1534230Y1045250D02*
X1534412Y1044867D01*
X1533882Y1044337D01*
X1533498Y1044519D01*
X1533357Y1044660D01*
X1534089Y1045392D01*
X1534230Y1045250D01*
G37*
G36*
G01X1535892Y1046912D02*
X1536074Y1046529D01*
X1535544Y1045998D01*
X1535160Y1046180D01*
X1535019Y1046322D01*
X1535751Y1047054D01*
X1535892Y1046912D01*
G37*
G36*
G01X1531535Y1044820D02*
X1531353Y1045204D01*
X1531883Y1045734D01*
X1532267Y1045552D01*
X1532409Y1045411D01*
X1531677Y1044679D01*
X1531535Y1044820D01*
G37*
G36*
G01X1533381Y1046100D02*
X1533563Y1045716D01*
X1533033Y1045186D01*
X1532649Y1045368D01*
X1532508Y1045510D01*
X1533239Y1046241D01*
X1533381Y1046100D01*
G37*
G36*
G01X1531719Y1044438D02*
X1531901Y1044055D01*
X1531371Y1043524D01*
X1530987Y1043706D01*
X1530846Y1043848D01*
X1531578Y1044580D01*
X1531719Y1044438D01*
G37*
G36*
G01X1533197Y1046482D02*
X1533015Y1046865D01*
X1533545Y1047396D01*
X1533929Y1047214D01*
X1534070Y1047072D01*
X1533338Y1046340D01*
X1533197Y1046482D01*
G37*
G36*
G01X1535042Y1047762D02*
X1535225Y1047378D01*
X1534694Y1046848D01*
X1534311Y1047030D01*
X1534169Y1047171D01*
X1534901Y1047903D01*
X1535042Y1047762D01*
G37*
G36*
G01X1533418Y1042739D02*
X1533600Y1042356D01*
X1533070Y1041825D01*
X1532686Y1042007D01*
X1532545Y1042149D01*
X1533277Y1042881D01*
X1533418Y1042739D01*
G37*
G36*
G01X1534896Y1044783D02*
X1534714Y1045166D01*
X1535244Y1045697D01*
X1535628Y1045515D01*
X1535769Y1045373D01*
X1535037Y1044641D01*
X1534896Y1044783D01*
G37*
G36*
G01X1533234Y1043121D02*
X1533052Y1043505D01*
X1533582Y1044035D01*
X1533966Y1043853D01*
X1534108Y1043712D01*
X1533376Y1042980D01*
X1533234Y1043121D01*
G37*
G36*
G01X1535080Y1044401D02*
X1535262Y1044017D01*
X1534732Y1043487D01*
X1534348Y1043669D01*
X1534207Y1043811D01*
X1534938Y1044542D01*
X1535080Y1044401D01*
G37*
G36*
G01X1536558Y1046444D02*
X1536376Y1046828D01*
X1536906Y1047358D01*
X1537290Y1047176D01*
X1537431Y1047035D01*
X1536699Y1046303D01*
X1536558Y1046444D01*
G37*
G36*
G01X1536741Y1046063D02*
X1536924Y1045679D01*
X1536393Y1045149D01*
X1536010Y1045331D01*
X1535868Y1045472D01*
X1536600Y1046204D01*
X1536741Y1046063D01*
G37*
G36*
G01X1538403Y1047724D02*
X1538585Y1047341D01*
X1538055Y1046810D01*
X1537671Y1046992D01*
X1537530Y1047134D01*
X1538262Y1047866D01*
X1538403Y1047724D01*
G37*
G36*
G01X1541374Y1048275D02*
X1541192Y1048658D01*
X1541722Y1049189D01*
X1542106Y1049007D01*
X1542247Y1048865D01*
X1541515Y1048133D01*
X1541374Y1048275D01*
G37*
G36*
G01X1541558Y1047893D02*
X1541740Y1047509D01*
X1541210Y1046979D01*
X1540826Y1047161D01*
X1540685Y1047303D01*
X1541416Y1048034D01*
X1541558Y1047893D01*
G37*
G36*
G01X1533505Y1061652D02*
X1533687Y1061268D01*
X1533157Y1060738D01*
X1532773Y1060920D01*
X1532632Y1061062D01*
X1533363Y1061793D01*
X1533505Y1061652D01*
G37*
G36*
G01X1531843Y1059990D02*
X1532025Y1059607D01*
X1531495Y1059076D01*
X1531111Y1059258D01*
X1530970Y1059400D01*
X1531702Y1060132D01*
X1531843Y1059990D01*
G37*
G36*
G01X1530181Y1058329D02*
X1530363Y1057945D01*
X1529833Y1057415D01*
X1529450Y1057597D01*
X1529308Y1057738D01*
X1530040Y1058470D01*
X1530181Y1058329D01*
G37*
G36*
G01X1528520Y1056667D02*
X1528702Y1056283D01*
X1528171Y1055753D01*
X1527788Y1055935D01*
X1527646Y1056076D01*
X1528378Y1056808D01*
X1528520Y1056667D01*
G37*
G36*
G01X1533321Y1062034D02*
X1533139Y1062417D01*
X1533669Y1062948D01*
X1534053Y1062766D01*
X1534194Y1062624D01*
X1533462Y1061892D01*
X1533321Y1062034D01*
G37*
G36*
G01X1535167Y1063314D02*
X1535349Y1062930D01*
X1534818Y1062400D01*
X1534435Y1062582D01*
X1534293Y1062723D01*
X1535025Y1063455D01*
X1535167Y1063314D01*
G37*
G36*
G01X1528372Y1053689D02*
X1528190Y1054072D01*
X1528720Y1054603D01*
X1529104Y1054421D01*
X1529245Y1054279D01*
X1528513Y1053547D01*
X1528372Y1053689D01*
G37*
G36*
G01X1530034Y1055350D02*
X1529852Y1055734D01*
X1530382Y1056264D01*
X1530765Y1056082D01*
X1530907Y1055941D01*
X1530175Y1055209D01*
X1530034Y1055350D01*
G37*
G36*
G01X1531695Y1057012D02*
X1531513Y1057396D01*
X1532044Y1057926D01*
X1532427Y1057744D01*
X1532569Y1057603D01*
X1531837Y1056871D01*
X1531695Y1057012D01*
G37*
G36*
G01X1530217Y1054969D02*
X1530400Y1054585D01*
X1529869Y1054055D01*
X1529486Y1054237D01*
X1529344Y1054378D01*
X1530076Y1055110D01*
X1530217Y1054969D01*
G37*
G36*
G01X1531879Y1056630D02*
X1532061Y1056247D01*
X1531531Y1055716D01*
X1531147Y1055898D01*
X1531006Y1056040D01*
X1531738Y1056772D01*
X1531879Y1056630D01*
G37*
G36*
G01X1533541Y1058292D02*
X1533723Y1057908D01*
X1533193Y1057378D01*
X1532809Y1057560D01*
X1532668Y1057702D01*
X1533399Y1058433D01*
X1533541Y1058292D01*
G37*
G36*
G01X1533357Y1058674D02*
X1533175Y1059057D01*
X1533705Y1059588D01*
X1534089Y1059406D01*
X1534230Y1059264D01*
X1533498Y1058532D01*
X1533357Y1058674D01*
G37*
G36*
G01X1535019Y1060336D02*
X1534837Y1060719D01*
X1535367Y1061249D01*
X1535751Y1061067D01*
X1535892Y1060926D01*
X1535160Y1060194D01*
X1535019Y1060336D01*
G37*
G36*
G01X1535203Y1059954D02*
X1535385Y1059570D01*
X1534854Y1059040D01*
X1534471Y1059222D01*
X1534329Y1059363D01*
X1535061Y1060095D01*
X1535203Y1059954D01*
G37*
G36*
G01X1538526Y1063277D02*
X1538708Y1062893D01*
X1538178Y1062363D01*
X1537794Y1062545D01*
X1537653Y1062687D01*
X1538385Y1063419D01*
X1538526Y1063277D01*
G37*
G36*
G01X1536864Y1061615D02*
X1537046Y1061232D01*
X1536516Y1060701D01*
X1536132Y1060884D01*
X1535991Y1061025D01*
X1536723Y1061757D01*
X1536864Y1061615D01*
G37*
G36*
G01X1536680Y1061997D02*
X1536498Y1062381D01*
X1537029Y1062911D01*
X1537412Y1062729D01*
X1537554Y1062588D01*
X1536822Y1061856D01*
X1536680Y1061997D01*
G37*
G36*
G01X1530846Y1057861D02*
X1530664Y1058245D01*
X1531195Y1058775D01*
X1531578Y1058593D01*
X1531720Y1058452D01*
X1530988Y1057720D01*
X1530846Y1057861D01*
G37*
G36*
G01X1532692Y1059141D02*
X1532874Y1058758D01*
X1532344Y1058227D01*
X1531960Y1058409D01*
X1531819Y1058551D01*
X1532551Y1059283D01*
X1532692Y1059141D01*
G37*
G36*
G01X1532508Y1059523D02*
X1532326Y1059907D01*
X1532856Y1060437D01*
X1533240Y1060255D01*
X1533381Y1060113D01*
X1532650Y1059382D01*
X1532508Y1059523D01*
G37*
G36*
G01X1529185Y1056200D02*
X1529003Y1056583D01*
X1529533Y1057114D01*
X1529917Y1056931D01*
X1530058Y1056790D01*
X1529326Y1056058D01*
X1529185Y1056200D01*
G37*
G36*
G01X1529369Y1055818D02*
X1529551Y1055434D01*
X1529020Y1054904D01*
X1528637Y1055086D01*
X1528495Y1055227D01*
X1529227Y1055959D01*
X1529369Y1055818D01*
G37*
G36*
G01X1531030Y1057479D02*
X1531212Y1057096D01*
X1530682Y1056565D01*
X1530298Y1056748D01*
X1530157Y1056889D01*
X1530889Y1057621D01*
X1531030Y1057479D01*
G37*
G36*
G01X1534170Y1061185D02*
X1533988Y1061568D01*
X1534518Y1062099D01*
X1534902Y1061917D01*
X1535043Y1061775D01*
X1534311Y1061043D01*
X1534170Y1061185D01*
G37*
G36*
G01X1534354Y1060803D02*
X1534536Y1060419D01*
X1534005Y1059889D01*
X1533622Y1060071D01*
X1533480Y1060212D01*
X1534212Y1060944D01*
X1534354Y1060803D01*
G37*
G36*
G01X1536015Y1062465D02*
X1536197Y1062081D01*
X1535667Y1061551D01*
X1535284Y1061733D01*
X1535142Y1061874D01*
X1535874Y1062606D01*
X1536015Y1062465D01*
G37*
G36*
G01X1535832Y1062846D02*
X1535649Y1063230D01*
X1536180Y1063760D01*
X1536563Y1063578D01*
X1536705Y1063437D01*
X1535973Y1062705D01*
X1535832Y1062846D01*
G37*
G36*
G01X1530882Y1054501D02*
X1530700Y1054885D01*
X1531231Y1055415D01*
X1531614Y1055233D01*
X1531756Y1055092D01*
X1531024Y1054360D01*
X1530882Y1054501D01*
G37*
G36*
G01X1532544Y1056163D02*
X1532362Y1056547D01*
X1532892Y1057077D01*
X1533276Y1056895D01*
X1533417Y1056753D01*
X1532686Y1056022D01*
X1532544Y1056163D01*
G37*
G36*
G01X1531066Y1054119D02*
X1531248Y1053736D01*
X1530718Y1053206D01*
X1530334Y1053388D01*
X1530193Y1053529D01*
X1530925Y1054261D01*
X1531066Y1054119D01*
G37*
G36*
G01X1532728Y1055781D02*
X1532910Y1055398D01*
X1532380Y1054867D01*
X1531996Y1055049D01*
X1531855Y1055191D01*
X1532587Y1055923D01*
X1532728Y1055781D01*
G37*
G36*
G01X1534206Y1057825D02*
X1534024Y1058208D01*
X1534554Y1058739D01*
X1534938Y1058557D01*
X1535079Y1058415D01*
X1534347Y1057683D01*
X1534206Y1057825D01*
G37*
G36*
G01X1534390Y1057443D02*
X1534572Y1057059D01*
X1534041Y1056529D01*
X1533658Y1056711D01*
X1533516Y1056852D01*
X1534248Y1057584D01*
X1534390Y1057443D01*
G37*
G36*
G01X1541036Y1064090D02*
X1541219Y1063706D01*
X1540688Y1063176D01*
X1540305Y1063358D01*
X1540163Y1063499D01*
X1540895Y1064231D01*
X1541036Y1064090D01*
G37*
G36*
G01X1536051Y1059105D02*
X1536233Y1058721D01*
X1535703Y1058191D01*
X1535320Y1058373D01*
X1535178Y1058514D01*
X1535910Y1059246D01*
X1536051Y1059105D01*
G37*
G36*
G01X1539375Y1062428D02*
X1539557Y1062044D01*
X1539027Y1061514D01*
X1538643Y1061696D01*
X1538502Y1061838D01*
X1539233Y1062569D01*
X1539375Y1062428D01*
G37*
G36*
G01X1539191Y1062810D02*
X1539009Y1063193D01*
X1539539Y1063724D01*
X1539923Y1063542D01*
X1540064Y1063400D01*
X1539332Y1062668D01*
X1539191Y1062810D01*
G37*
G36*
G01X1537529Y1061148D02*
X1537347Y1061532D01*
X1537877Y1062062D01*
X1538261Y1061880D01*
X1538403Y1061739D01*
X1537671Y1061007D01*
X1537529Y1061148D01*
G37*
G36*
G01X1537713Y1060766D02*
X1537895Y1060383D01*
X1537365Y1059852D01*
X1536981Y1060034D01*
X1536840Y1060176D01*
X1537572Y1060908D01*
X1537713Y1060766D01*
G37*
G36*
G01X1535868Y1059486D02*
X1535685Y1059870D01*
X1536216Y1060400D01*
X1536599Y1060218D01*
X1536741Y1060077D01*
X1536009Y1059345D01*
X1535868Y1059486D01*
G37*
G36*
G01X1532348Y1047331D02*
X1532166Y1047714D01*
X1532696Y1048245D01*
X1533080Y1048063D01*
X1533221Y1047921D01*
X1532489Y1047189D01*
X1532348Y1047331D01*
G37*
G36*
G01X1534010Y1048992D02*
X1533828Y1049376D01*
X1534358Y1049906D01*
X1534742Y1049724D01*
X1534883Y1049583D01*
X1534151Y1048851D01*
X1534010Y1048992D01*
G37*
G36*
G01X1534193Y1048611D02*
X1534376Y1048227D01*
X1533845Y1047697D01*
X1533462Y1047879D01*
X1533320Y1048020D01*
X1534052Y1048752D01*
X1534193Y1048611D01*
G37*
G36*
G01X1535855Y1050272D02*
X1536037Y1049889D01*
X1535507Y1049358D01*
X1535123Y1049540D01*
X1534982Y1049682D01*
X1535714Y1050414D01*
X1535855Y1050272D01*
G37*
G36*
G01X1535671Y1050654D02*
X1535489Y1051038D01*
X1536020Y1051568D01*
X1536403Y1051386D01*
X1536545Y1051245D01*
X1535813Y1050513D01*
X1535671Y1050654D01*
G37*
G36*
G01X1537517Y1051934D02*
X1537699Y1051550D01*
X1537169Y1051020D01*
X1536785Y1051202D01*
X1536644Y1051344D01*
X1537375Y1052075D01*
X1537517Y1051934D01*
G37*
G36*
G01X1538995Y1053978D02*
X1538813Y1054361D01*
X1539343Y1054892D01*
X1539727Y1054709D01*
X1539868Y1054568D01*
X1539136Y1053836D01*
X1538995Y1053978D01*
G37*
G36*
G01X1540656Y1055639D02*
X1540474Y1056023D01*
X1541005Y1056553D01*
X1541388Y1056371D01*
X1541530Y1056230D01*
X1540798Y1055498D01*
X1540656Y1055639D01*
G37*
G36*
G01X1537333Y1052316D02*
X1537151Y1052699D01*
X1537681Y1053230D01*
X1538065Y1053048D01*
X1538206Y1052906D01*
X1537474Y1052174D01*
X1537333Y1052316D01*
G37*
G36*
G01X1539179Y1053596D02*
X1539361Y1053212D01*
X1538830Y1052682D01*
X1538447Y1052864D01*
X1538305Y1053005D01*
X1539037Y1053737D01*
X1539179Y1053596D01*
G37*
G36*
G01X1540840Y1055257D02*
X1541022Y1054874D01*
X1540492Y1054344D01*
X1540108Y1054526D01*
X1539967Y1054667D01*
X1540699Y1055399D01*
X1540840Y1055257D01*
G37*
G36*
G01X1542502Y1056919D02*
X1542684Y1056536D01*
X1542154Y1056005D01*
X1541770Y1056187D01*
X1541629Y1056329D01*
X1542361Y1057061D01*
X1542502Y1056919D01*
G37*
G36*
G01X1539215Y1050236D02*
X1539397Y1049852D01*
X1538867Y1049322D01*
X1538484Y1049504D01*
X1538342Y1049645D01*
X1539074Y1050377D01*
X1539215Y1050236D01*
G37*
G36*
G01X1539032Y1050617D02*
X1538849Y1051001D01*
X1539380Y1051531D01*
X1539763Y1051349D01*
X1539905Y1051208D01*
X1539173Y1050476D01*
X1539032Y1050617D01*
G37*
G36*
G01X1537370Y1048956D02*
X1537188Y1049339D01*
X1537718Y1049870D01*
X1538102Y1049688D01*
X1538243Y1049546D01*
X1537511Y1048814D01*
X1537370Y1048956D01*
G37*
G36*
G01X1540877Y1051897D02*
X1541059Y1051514D01*
X1540529Y1050983D01*
X1540145Y1051165D01*
X1540004Y1051307D01*
X1540736Y1052039D01*
X1540877Y1051897D01*
G37*
G36*
G01X1535708Y1047294D02*
X1535526Y1047678D01*
X1536056Y1048208D01*
X1536440Y1048026D01*
X1536581Y1047884D01*
X1535850Y1047153D01*
X1535708Y1047294D01*
G37*
G36*
G01X1537554Y1048574D02*
X1537736Y1048190D01*
X1537205Y1047660D01*
X1536822Y1047842D01*
X1536680Y1047983D01*
X1537412Y1048715D01*
X1537554Y1048574D01*
G37*
G36*
G01X1540693Y1052279D02*
X1540511Y1052663D01*
X1541041Y1053193D01*
X1541425Y1053011D01*
X1541567Y1052870D01*
X1540835Y1052138D01*
X1540693Y1052279D01*
G37*
G36*
G01X1542539Y1053559D02*
X1542721Y1053175D01*
X1542191Y1052645D01*
X1541807Y1052827D01*
X1541666Y1052969D01*
X1542397Y1053700D01*
X1542539Y1053559D01*
G37*
G36*
G01X1534859Y1048143D02*
X1534677Y1048527D01*
X1535207Y1049057D01*
X1535591Y1048875D01*
X1535732Y1048734D01*
X1535000Y1048002D01*
X1534859Y1048143D01*
G37*
G36*
G01X1536520Y1049805D02*
X1536338Y1050189D01*
X1536869Y1050719D01*
X1537252Y1050537D01*
X1537394Y1050396D01*
X1536662Y1049664D01*
X1536520Y1049805D01*
G37*
G36*
G01X1536704Y1049423D02*
X1536886Y1049040D01*
X1536356Y1048509D01*
X1535972Y1048691D01*
X1535831Y1048833D01*
X1536563Y1049565D01*
X1536704Y1049423D01*
G37*
G36*
G01X1538182Y1051467D02*
X1538000Y1051850D01*
X1538530Y1052381D01*
X1538914Y1052199D01*
X1539055Y1052057D01*
X1538323Y1051325D01*
X1538182Y1051467D01*
G37*
G36*
G01X1538366Y1051085D02*
X1538548Y1050701D01*
X1538018Y1050171D01*
X1537634Y1050353D01*
X1537493Y1050495D01*
X1538224Y1051226D01*
X1538366Y1051085D01*
G37*
G36*
G01X1539844Y1053129D02*
X1539662Y1053512D01*
X1540192Y1054043D01*
X1540576Y1053860D01*
X1540717Y1053719D01*
X1539985Y1052987D01*
X1539844Y1053129D01*
G37*
G36*
G01X1541505Y1054790D02*
X1541323Y1055174D01*
X1541854Y1055704D01*
X1542237Y1055522D01*
X1542379Y1055381D01*
X1541647Y1054649D01*
X1541505Y1054790D01*
G37*
G36*
G01X1540028Y1052747D02*
X1540210Y1052363D01*
X1539679Y1051833D01*
X1539296Y1052015D01*
X1539154Y1052156D01*
X1539886Y1052888D01*
X1540028Y1052747D01*
G37*
G36*
G01X1541689Y1054408D02*
X1541871Y1054025D01*
X1541341Y1053495D01*
X1540957Y1053677D01*
X1540816Y1053818D01*
X1541548Y1054550D01*
X1541689Y1054408D01*
G37*
G36*
G01X1539881Y1049768D02*
X1539699Y1050151D01*
X1540229Y1050682D01*
X1540613Y1050500D01*
X1540754Y1050358D01*
X1540022Y1049626D01*
X1539881Y1049768D01*
G37*
G36*
G01X1541727Y1051048D02*
X1541909Y1050664D01*
X1541378Y1050134D01*
X1540995Y1050316D01*
X1540853Y1050457D01*
X1541585Y1051189D01*
X1541727Y1051048D01*
G37*
G36*
G01X1541543Y1051430D02*
X1541361Y1051813D01*
X1541891Y1052344D01*
X1542275Y1052161D01*
X1542416Y1052020D01*
X1541684Y1051288D01*
X1541543Y1051430D01*
G37*
G36*
G01X1538219Y1048106D02*
X1538037Y1048490D01*
X1538568Y1049020D01*
X1538951Y1048838D01*
X1539093Y1048697D01*
X1538361Y1047965D01*
X1538219Y1048106D01*
G37*
G36*
G01X1540065Y1049386D02*
X1540247Y1049002D01*
X1539717Y1048472D01*
X1539333Y1048654D01*
X1539192Y1048796D01*
X1539923Y1049527D01*
X1540065Y1049386D01*
G37*
G36*
G01X1532992Y1079773D02*
X1533174Y1079389D01*
X1532644Y1078859D01*
X1532260Y1079041D01*
X1532119Y1079183D01*
X1532850Y1079914D01*
X1532992Y1079773D01*
G37*
G36*
G01X1531146Y1078493D02*
X1530964Y1078877D01*
X1531494Y1079407D01*
X1531878Y1079225D01*
X1532020Y1079084D01*
X1531288Y1078352D01*
X1531146Y1078493D01*
G37*
G36*
G01X1533842Y1078923D02*
X1534024Y1078539D01*
X1533494Y1078009D01*
X1533110Y1078191D01*
X1532969Y1078333D01*
X1533700Y1079064D01*
X1533842Y1078923D01*
G37*
G36*
G01X1533658Y1079305D02*
X1533476Y1079688D01*
X1534006Y1080219D01*
X1534390Y1080037D01*
X1534531Y1079895D01*
X1533799Y1079163D01*
X1533658Y1079305D01*
G37*
G36*
G01X1530773Y1067906D02*
X1530591Y1068290D01*
X1531121Y1068820D01*
X1531505Y1068638D01*
X1531646Y1068497D01*
X1530915Y1067765D01*
X1530773Y1067906D01*
G37*
G36*
G01X1530957Y1067525D02*
X1531139Y1067141D01*
X1530609Y1066611D01*
X1530225Y1066793D01*
X1530084Y1066934D01*
X1530815Y1067666D01*
X1530957Y1067525D01*
G37*
G36*
G01X1532619Y1069186D02*
X1532801Y1068803D01*
X1532271Y1068272D01*
X1531887Y1068454D01*
X1531746Y1068596D01*
X1532477Y1069328D01*
X1532619Y1069186D01*
G37*
G36*
G01X1532435Y1069568D02*
X1532253Y1069951D01*
X1532783Y1070482D01*
X1533167Y1070300D01*
X1533308Y1070158D01*
X1532577Y1069426D01*
X1532435Y1069568D01*
G37*
G36*
G01X1534281Y1070848D02*
X1534463Y1070464D01*
X1533933Y1069934D01*
X1533549Y1070116D01*
X1533408Y1070257D01*
X1534139Y1070989D01*
X1534281Y1070848D01*
G37*
G36*
G01X1534097Y1071229D02*
X1533915Y1071613D01*
X1534445Y1072143D01*
X1534829Y1071961D01*
X1534970Y1071820D01*
X1534239Y1071088D01*
X1534097Y1071229D01*
G37*
G36*
G01X1542591Y1079155D02*
X1542773Y1078771D01*
X1542242Y1078241D01*
X1541859Y1078423D01*
X1541717Y1078564D01*
X1542449Y1079296D01*
X1542591Y1079155D01*
G37*
G36*
G01X1535759Y1072891D02*
X1535577Y1073274D01*
X1536107Y1073805D01*
X1536491Y1073623D01*
X1536632Y1073481D01*
X1535900Y1072749D01*
X1535759Y1072891D01*
G37*
G36*
G01X1540929Y1077493D02*
X1541111Y1077110D01*
X1540580Y1076579D01*
X1540197Y1076761D01*
X1540055Y1076903D01*
X1540787Y1077635D01*
X1540929Y1077493D01*
G37*
G36*
G01X1540745Y1077875D02*
X1540563Y1078259D01*
X1541093Y1078789D01*
X1541477Y1078607D01*
X1541618Y1078465D01*
X1540886Y1077734D01*
X1540745Y1077875D01*
G37*
G36*
G01X1539083Y1076214D02*
X1538901Y1076597D01*
X1539431Y1077127D01*
X1539815Y1076945D01*
X1539956Y1076804D01*
X1539224Y1076072D01*
X1539083Y1076214D01*
G37*
G36*
G01X1539267Y1075832D02*
X1539449Y1075448D01*
X1538918Y1074918D01*
X1538535Y1075100D01*
X1538393Y1075241D01*
X1539125Y1075973D01*
X1539267Y1075832D01*
G37*
G36*
G01X1537605Y1074170D02*
X1537787Y1073787D01*
X1537257Y1073256D01*
X1536873Y1073439D01*
X1536731Y1073580D01*
X1537463Y1074312D01*
X1537605Y1074170D01*
G37*
G36*
G01X1537421Y1074552D02*
X1537239Y1074936D01*
X1537769Y1075466D01*
X1538153Y1075284D01*
X1538294Y1075143D01*
X1537562Y1074411D01*
X1537421Y1074552D01*
G37*
G36*
G01X1535943Y1072509D02*
X1536125Y1072125D01*
X1535595Y1071595D01*
X1535211Y1071777D01*
X1535070Y1071919D01*
X1535801Y1072650D01*
X1535943Y1072509D01*
G37*
G36*
G01X1530811Y1064544D02*
X1530629Y1064928D01*
X1531160Y1065458D01*
X1531543Y1065276D01*
X1531685Y1065135D01*
X1530953Y1064403D01*
X1530811Y1064544D01*
G37*
G36*
G01X1532473Y1066206D02*
X1532291Y1066590D01*
X1532821Y1067120D01*
X1533205Y1066938D01*
X1533346Y1066796D01*
X1532615Y1066065D01*
X1532473Y1066206D01*
G37*
G36*
G01X1532657Y1065824D02*
X1532839Y1065440D01*
X1532309Y1064910D01*
X1531925Y1065092D01*
X1531784Y1065234D01*
X1532516Y1065966D01*
X1532657Y1065824D01*
G37*
G36*
G01X1534135Y1067868D02*
X1533953Y1068251D01*
X1534483Y1068782D01*
X1534867Y1068599D01*
X1535008Y1068458D01*
X1534276Y1067726D01*
X1534135Y1067868D01*
G37*
G36*
G01X1534319Y1067486D02*
X1534501Y1067102D01*
X1533970Y1066572D01*
X1533587Y1066754D01*
X1533445Y1066895D01*
X1534177Y1067627D01*
X1534319Y1067486D01*
G37*
G36*
G01X1540782Y1074514D02*
X1540600Y1074898D01*
X1541130Y1075428D01*
X1541513Y1075246D01*
X1541655Y1075105D01*
X1540923Y1074373D01*
X1540782Y1074514D01*
G37*
G36*
G01X1539120Y1072853D02*
X1538938Y1073236D01*
X1539468Y1073767D01*
X1539852Y1073585D01*
X1539993Y1073443D01*
X1539261Y1072711D01*
X1539120Y1072853D01*
G37*
G36*
G01X1540965Y1074133D02*
X1541148Y1073749D01*
X1540617Y1073219D01*
X1540234Y1073401D01*
X1540092Y1073542D01*
X1540824Y1074274D01*
X1540965Y1074133D01*
G37*
G36*
G01X1535980Y1069147D02*
X1536162Y1068764D01*
X1535632Y1068234D01*
X1535248Y1068416D01*
X1535107Y1068557D01*
X1535839Y1069289D01*
X1535980Y1069147D01*
G37*
G36*
G01X1539304Y1072471D02*
X1539486Y1072087D01*
X1538955Y1071557D01*
X1538572Y1071739D01*
X1538430Y1071880D01*
X1539162Y1072612D01*
X1539304Y1072471D01*
G37*
G36*
G01X1535796Y1069529D02*
X1535614Y1069913D01*
X1536145Y1070443D01*
X1536528Y1070261D01*
X1536670Y1070120D01*
X1535938Y1069388D01*
X1535796Y1069529D01*
G37*
G36*
G01X1537642Y1070809D02*
X1537824Y1070426D01*
X1537294Y1069895D01*
X1536910Y1070077D01*
X1536769Y1070219D01*
X1537501Y1070951D01*
X1537642Y1070809D01*
G37*
G36*
G01X1537458Y1071191D02*
X1537276Y1071575D01*
X1537806Y1072105D01*
X1538190Y1071923D01*
X1538331Y1071781D01*
X1537600Y1071050D01*
X1537458Y1071191D01*
G37*
G36*
G01X1533470Y1068335D02*
X1533652Y1067951D01*
X1533122Y1067421D01*
X1532738Y1067603D01*
X1532596Y1067744D01*
X1533328Y1068476D01*
X1533470Y1068335D01*
G37*
G36*
G01X1531624Y1067055D02*
X1531442Y1067439D01*
X1531972Y1067969D01*
X1532356Y1067787D01*
X1532498Y1067646D01*
X1531766Y1066914D01*
X1531624Y1067055D01*
G37*
G36*
G01X1531808Y1066673D02*
X1531990Y1066290D01*
X1531460Y1065759D01*
X1531076Y1065941D01*
X1530935Y1066083D01*
X1531667Y1066815D01*
X1531808Y1066673D01*
G37*
G36*
G01X1533286Y1068717D02*
X1533104Y1069100D01*
X1533634Y1069631D01*
X1534018Y1069449D01*
X1534159Y1069307D01*
X1533427Y1068575D01*
X1533286Y1068717D01*
G37*
G36*
G01X1534948Y1070378D02*
X1534766Y1070762D01*
X1535296Y1071292D01*
X1535679Y1071110D01*
X1535821Y1070969D01*
X1535089Y1070237D01*
X1534948Y1070378D01*
G37*
G36*
G01X1535131Y1069997D02*
X1535314Y1069613D01*
X1534783Y1069083D01*
X1534400Y1069265D01*
X1534258Y1069406D01*
X1534990Y1070138D01*
X1535131Y1069997D01*
G37*
G36*
G01X1536609Y1072040D02*
X1536427Y1072424D01*
X1536958Y1072954D01*
X1537341Y1072772D01*
X1537483Y1072631D01*
X1536751Y1071899D01*
X1536609Y1072040D01*
G37*
G36*
G01X1538455Y1073320D02*
X1538637Y1072936D01*
X1538107Y1072406D01*
X1537723Y1072588D01*
X1537582Y1072730D01*
X1538313Y1073461D01*
X1538455Y1073320D01*
G37*
G36*
G01X1541594Y1077025D02*
X1541412Y1077409D01*
X1541943Y1077939D01*
X1542326Y1077757D01*
X1542468Y1077616D01*
X1541736Y1076884D01*
X1541594Y1077025D01*
G37*
G36*
G01X1539933Y1075364D02*
X1539751Y1075747D01*
X1540281Y1076278D01*
X1540665Y1076095D01*
X1540806Y1075954D01*
X1540074Y1075222D01*
X1539933Y1075364D01*
G37*
G36*
G01X1541778Y1076643D02*
X1541960Y1076260D01*
X1541430Y1075729D01*
X1541046Y1075912D01*
X1540905Y1076053D01*
X1541637Y1076785D01*
X1541778Y1076643D01*
G37*
G36*
G01X1538271Y1073702D02*
X1538089Y1074085D01*
X1538619Y1074616D01*
X1539003Y1074434D01*
X1539144Y1074292D01*
X1538412Y1073560D01*
X1538271Y1073702D01*
G37*
G36*
G01X1540117Y1074982D02*
X1540299Y1074598D01*
X1539768Y1074068D01*
X1539385Y1074250D01*
X1539243Y1074391D01*
X1539975Y1075123D01*
X1540117Y1074982D01*
G37*
G36*
G01X1536793Y1071658D02*
X1536975Y1071275D01*
X1536445Y1070744D01*
X1536061Y1070926D01*
X1535920Y1071068D01*
X1536652Y1071800D01*
X1536793Y1071658D01*
G37*
G36*
G01X1533506Y1064974D02*
X1533688Y1064591D01*
X1533158Y1064061D01*
X1532774Y1064243D01*
X1532633Y1064384D01*
X1533365Y1065116D01*
X1533506Y1064974D01*
G37*
G36*
G01X1531661Y1063695D02*
X1531479Y1064078D01*
X1532009Y1064609D01*
X1532393Y1064426D01*
X1532534Y1064285D01*
X1531802Y1063553D01*
X1531661Y1063695D01*
G37*
G36*
G01X1533322Y1065356D02*
X1533140Y1065740D01*
X1533671Y1066270D01*
X1534054Y1066088D01*
X1534196Y1065947D01*
X1533464Y1065215D01*
X1533322Y1065356D01*
G37*
G36*
G01X1534984Y1067018D02*
X1534802Y1067402D01*
X1535332Y1067932D01*
X1535716Y1067750D01*
X1535857Y1067608D01*
X1535126Y1066877D01*
X1534984Y1067018D01*
G37*
G36*
G01X1535168Y1066636D02*
X1535350Y1066253D01*
X1534820Y1065722D01*
X1534436Y1065904D01*
X1534295Y1066046D01*
X1535027Y1066778D01*
X1535168Y1066636D01*
G37*
G36*
G01X1536830Y1068298D02*
X1537012Y1067914D01*
X1536481Y1067384D01*
X1536098Y1067566D01*
X1535956Y1067707D01*
X1536688Y1068439D01*
X1536830Y1068298D01*
G37*
G36*
G01X1539969Y1072003D02*
X1539787Y1072387D01*
X1540317Y1072917D01*
X1540701Y1072735D01*
X1540843Y1072594D01*
X1540111Y1071862D01*
X1539969Y1072003D01*
G37*
G36*
G01X1541815Y1073283D02*
X1541997Y1072899D01*
X1541467Y1072369D01*
X1541083Y1072551D01*
X1540942Y1072693D01*
X1541673Y1073424D01*
X1541815Y1073283D01*
G37*
G36*
G01X1541631Y1073665D02*
X1541449Y1074048D01*
X1541979Y1074579D01*
X1542363Y1074397D01*
X1542504Y1074255D01*
X1541772Y1073523D01*
X1541631Y1073665D01*
G37*
G36*
G01X1538308Y1070341D02*
X1538125Y1070725D01*
X1538656Y1071255D01*
X1539039Y1071073D01*
X1539181Y1070932D01*
X1538449Y1070200D01*
X1538308Y1070341D01*
G37*
G36*
G01X1538491Y1069960D02*
X1538673Y1069576D01*
X1538143Y1069046D01*
X1537760Y1069228D01*
X1537618Y1069369D01*
X1538350Y1070101D01*
X1538491Y1069960D01*
G37*
G36*
G01X1540153Y1071621D02*
X1540335Y1071238D01*
X1539805Y1070707D01*
X1539421Y1070889D01*
X1539280Y1071031D01*
X1540012Y1071763D01*
X1540153Y1071621D01*
G37*
G36*
G01X1536646Y1068680D02*
X1536464Y1069063D01*
X1536994Y1069594D01*
X1537378Y1069412D01*
X1537519Y1069270D01*
X1536787Y1068538D01*
X1536646Y1068680D01*
G37*
G36*
G01X1534983Y1063696D02*
X1534801Y1064079D01*
X1535331Y1064609D01*
X1535715Y1064427D01*
X1535856Y1064286D01*
X1535124Y1063554D01*
X1534983Y1063696D01*
G37*
G36*
G01X1540152Y1068299D02*
X1540334Y1067915D01*
X1539803Y1067385D01*
X1539420Y1067567D01*
X1539278Y1067708D01*
X1540010Y1068440D01*
X1540152Y1068299D01*
G37*
G36*
G01X1538306Y1067019D02*
X1538124Y1067403D01*
X1538654Y1067933D01*
X1539038Y1067751D01*
X1539179Y1067609D01*
X1538447Y1066877D01*
X1538306Y1067019D01*
G37*
G36*
G01X1538490Y1066637D02*
X1538672Y1066253D01*
X1538142Y1065723D01*
X1537758Y1065905D01*
X1537617Y1066047D01*
X1538348Y1066778D01*
X1538490Y1066637D01*
G37*
G36*
G01X1536644Y1065357D02*
X1536462Y1065741D01*
X1536993Y1066271D01*
X1537376Y1066089D01*
X1537518Y1065948D01*
X1536786Y1065216D01*
X1536644Y1065357D01*
G37*
G36*
G01X1536828Y1064975D02*
X1537010Y1064592D01*
X1536480Y1064061D01*
X1536096Y1064244D01*
X1535955Y1064385D01*
X1536687Y1065117D01*
X1536828Y1064975D01*
G37*
G36*
G01X1541629Y1070342D02*
X1541447Y1070726D01*
X1541978Y1071256D01*
X1542361Y1071074D01*
X1542503Y1070933D01*
X1541771Y1070201D01*
X1541629Y1070342D01*
G37*
G36*
G01X1541813Y1069960D02*
X1541995Y1069577D01*
X1541465Y1069047D01*
X1541081Y1069229D01*
X1540940Y1069370D01*
X1541672Y1070102D01*
X1541813Y1069960D01*
G37*
G36*
G01X1539968Y1068681D02*
X1539786Y1069064D01*
X1540316Y1069595D01*
X1540700Y1069412D01*
X1540841Y1069271D01*
X1540109Y1068539D01*
X1539968Y1068681D01*
G37*
G36*
G01X1541665Y1066982D02*
X1541483Y1067366D01*
X1542014Y1067896D01*
X1542397Y1067714D01*
X1542539Y1067573D01*
X1541807Y1066841D01*
X1541665Y1066982D01*
G37*
G36*
G01X1541849Y1066600D02*
X1542031Y1066217D01*
X1541501Y1065687D01*
X1541117Y1065869D01*
X1540976Y1066010D01*
X1541708Y1066742D01*
X1541849Y1066600D01*
G37*
G36*
G01X1540004Y1065321D02*
X1539822Y1065704D01*
X1540352Y1066235D01*
X1540736Y1066052D01*
X1540877Y1065911D01*
X1540145Y1065179D01*
X1540004Y1065321D01*
G37*
G36*
G01X1538342Y1063659D02*
X1538160Y1064043D01*
X1538690Y1064573D01*
X1539074Y1064391D01*
X1539215Y1064249D01*
X1538484Y1063518D01*
X1538342Y1063659D01*
G37*
G36*
G01X1540188Y1064939D02*
X1540370Y1064555D01*
X1539839Y1064025D01*
X1539456Y1064207D01*
X1539314Y1064348D01*
X1540046Y1065080D01*
X1540188Y1064939D01*
G37*
G36*
G01X1541000Y1067450D02*
X1541183Y1067066D01*
X1540652Y1066536D01*
X1540269Y1066718D01*
X1540127Y1066859D01*
X1540859Y1067591D01*
X1541000Y1067450D01*
G37*
G36*
G01X1539155Y1066170D02*
X1538973Y1066553D01*
X1539503Y1067084D01*
X1539887Y1066902D01*
X1540028Y1066760D01*
X1539296Y1066028D01*
X1539155Y1066170D01*
G37*
G36*
G01X1539339Y1065788D02*
X1539521Y1065404D01*
X1538991Y1064874D01*
X1538607Y1065056D01*
X1538466Y1065198D01*
X1539197Y1065929D01*
X1539339Y1065788D01*
G37*
G36*
G01X1537493Y1064508D02*
X1537311Y1064892D01*
X1537841Y1065422D01*
X1538225Y1065240D01*
X1538367Y1065099D01*
X1537635Y1064367D01*
X1537493Y1064508D01*
G37*
G36*
G01X1540817Y1067831D02*
X1540635Y1068215D01*
X1541165Y1068745D01*
X1541548Y1068563D01*
X1541690Y1068422D01*
X1540958Y1067690D01*
X1540817Y1067831D01*
G37*
G36*
G01X1537677Y1064126D02*
X1537859Y1063743D01*
X1537329Y1063212D01*
X1536945Y1063394D01*
X1536804Y1063536D01*
X1537536Y1064268D01*
X1537677Y1064126D01*
G37*
G36*
G01X1540853Y1064471D02*
X1540671Y1064855D01*
X1541201Y1065385D01*
X1541585Y1065203D01*
X1541726Y1065062D01*
X1540994Y1064330D01*
X1540853Y1064471D01*
G37*
G36*
G01X1534617Y1084794D02*
X1534799Y1084411D01*
X1534269Y1083880D01*
X1533885Y1084063D01*
X1533744Y1084204D01*
X1534476Y1084936D01*
X1534617Y1084794D01*
G37*
G36*
G01X1532772Y1083514D02*
X1532590Y1083898D01*
X1533120Y1084428D01*
X1533504Y1084246D01*
X1533645Y1084105D01*
X1532913Y1083373D01*
X1532772Y1083514D01*
G37*
G36*
G01X1532955Y1083133D02*
X1533138Y1082749D01*
X1532607Y1082219D01*
X1532224Y1082401D01*
X1532082Y1082542D01*
X1532814Y1083274D01*
X1532955Y1083133D01*
G37*
G36*
G01X1531294Y1081471D02*
X1531476Y1081087D01*
X1530946Y1080557D01*
X1530562Y1080739D01*
X1530421Y1080881D01*
X1531152Y1081612D01*
X1531294Y1081471D01*
G37*
G36*
G01X1531110Y1081853D02*
X1530928Y1082236D01*
X1531458Y1082767D01*
X1531842Y1082585D01*
X1531983Y1082443D01*
X1531251Y1081711D01*
X1531110Y1081853D01*
G37*
G36*
G01X1534433Y1085176D02*
X1534251Y1085560D01*
X1534782Y1086090D01*
X1535165Y1085908D01*
X1535307Y1085767D01*
X1534575Y1085035D01*
X1534433Y1085176D01*
G37*
G36*
G01X1537660Y1094275D02*
X1538024Y1094057D01*
X1537877Y1093322D01*
X1537457Y1093260D01*
X1537261Y1093300D01*
X1537464Y1094315D01*
X1537660Y1094275D01*
G37*
G36*
G01X1536835Y1092187D02*
X1536470Y1092405D01*
X1536617Y1093140D01*
X1537038Y1093202D01*
X1537234Y1093162D01*
X1537031Y1092147D01*
X1536835Y1092187D01*
G37*
G36*
G01X1535914Y1087578D02*
X1535550Y1087796D01*
X1535697Y1088531D01*
X1536117Y1088593D01*
X1536313Y1088553D01*
X1536110Y1087538D01*
X1535914Y1087578D01*
G37*
G36*
G01X1536374Y1089882D02*
X1536010Y1090100D01*
X1536157Y1090836D01*
X1536577Y1090897D01*
X1536774Y1090858D01*
X1536571Y1089843D01*
X1536374Y1089882D01*
G37*
G36*
G01X1536740Y1089666D02*
X1537104Y1089448D01*
X1536957Y1088713D01*
X1536537Y1088651D01*
X1536340Y1088691D01*
X1536543Y1089706D01*
X1536740Y1089666D01*
G37*
G36*
G01X1537200Y1091971D02*
X1537564Y1091753D01*
X1537417Y1091017D01*
X1536997Y1090956D01*
X1536801Y1090995D01*
X1537004Y1092010D01*
X1537200Y1091971D01*
G37*
G36*
G01X1538120Y1096580D02*
X1538484Y1096362D01*
X1538337Y1095626D01*
X1537917Y1095565D01*
X1537721Y1095604D01*
X1537924Y1096619D01*
X1538120Y1096580D01*
G37*
G36*
G01X1537295Y1094491D02*
X1536931Y1094709D01*
X1537078Y1095445D01*
X1537498Y1095506D01*
X1537694Y1095467D01*
X1537491Y1094452D01*
X1537295Y1094491D01*
G37*
G36*
G01X1534470Y1081816D02*
X1534288Y1082200D01*
X1534818Y1082730D01*
X1535202Y1082548D01*
X1535343Y1082407D01*
X1534611Y1081675D01*
X1534470Y1081816D01*
G37*
G36*
G01X1532808Y1080155D02*
X1532626Y1080538D01*
X1533156Y1081069D01*
X1533540Y1080887D01*
X1533681Y1080745D01*
X1532949Y1080013D01*
X1532808Y1080155D01*
G37*
G36*
G01X1534653Y1081435D02*
X1534836Y1081051D01*
X1534305Y1080521D01*
X1533922Y1080703D01*
X1533780Y1080844D01*
X1534512Y1081576D01*
X1534653Y1081435D01*
G37*
G36*
G01X1536315Y1083096D02*
X1536497Y1082713D01*
X1535967Y1082182D01*
X1535583Y1082365D01*
X1535442Y1082506D01*
X1536174Y1083238D01*
X1536315Y1083096D01*
G37*
G36*
G01X1536131Y1083478D02*
X1535949Y1083862D01*
X1536480Y1084392D01*
X1536863Y1084210D01*
X1537005Y1084069D01*
X1536273Y1083337D01*
X1536131Y1083478D01*
G37*
G36*
G01X1539654Y1094020D02*
X1539289Y1094238D01*
X1539436Y1094974D01*
X1539857Y1095035D01*
X1540053Y1094996D01*
X1539850Y1093981D01*
X1539654Y1094020D01*
G37*
G36*
G01X1540018Y1093804D02*
X1540383Y1093586D01*
X1540236Y1092851D01*
X1539816Y1092790D01*
X1539619Y1092829D01*
X1539822Y1093844D01*
X1540018Y1093804D01*
G37*
G36*
G01X1540479Y1096109D02*
X1540843Y1095891D01*
X1540696Y1095155D01*
X1540276Y1095094D01*
X1540080Y1095133D01*
X1540283Y1096148D01*
X1540479Y1096109D01*
G37*
G36*
G01X1538272Y1087107D02*
X1537907Y1087325D01*
X1538054Y1088061D01*
X1538475Y1088122D01*
X1538671Y1088083D01*
X1538468Y1087068D01*
X1538272Y1087107D01*
G37*
G36*
G01X1538732Y1089411D02*
X1538368Y1089629D01*
X1538515Y1090365D01*
X1538935Y1090426D01*
X1539131Y1090387D01*
X1538928Y1089372D01*
X1538732Y1089411D01*
G37*
G36*
G01X1539193Y1091716D02*
X1538829Y1091934D01*
X1538976Y1092669D01*
X1539396Y1092731D01*
X1539592Y1092691D01*
X1539389Y1091677D01*
X1539193Y1091716D01*
G37*
G36*
G01X1538636Y1086891D02*
X1539001Y1086673D01*
X1538854Y1085938D01*
X1538434Y1085876D01*
X1538237Y1085915D01*
X1538440Y1086930D01*
X1538636Y1086891D01*
G37*
G36*
G01X1539097Y1089196D02*
X1539461Y1088978D01*
X1539314Y1088242D01*
X1538894Y1088181D01*
X1538698Y1088220D01*
X1538901Y1089235D01*
X1539097Y1089196D01*
G37*
G36*
G01X1539558Y1091500D02*
X1539922Y1091282D01*
X1539775Y1090547D01*
X1539355Y1090485D01*
X1539159Y1090524D01*
X1539362Y1091539D01*
X1539558Y1091500D01*
G37*
G36*
G01X1535466Y1083945D02*
X1535648Y1083562D01*
X1535118Y1083031D01*
X1534734Y1083214D01*
X1534593Y1083355D01*
X1535325Y1084087D01*
X1535466Y1083945D01*
G37*
G36*
G01X1533621Y1082665D02*
X1533439Y1083049D01*
X1533969Y1083579D01*
X1534353Y1083397D01*
X1534494Y1083256D01*
X1533762Y1082524D01*
X1533621Y1082665D01*
G37*
G36*
G01X1533804Y1082284D02*
X1533987Y1081900D01*
X1533456Y1081370D01*
X1533073Y1081552D01*
X1532931Y1081693D01*
X1533663Y1082425D01*
X1533804Y1082284D01*
G37*
G36*
G01X1532143Y1080622D02*
X1532325Y1080238D01*
X1531795Y1079708D01*
X1531411Y1079890D01*
X1531270Y1080032D01*
X1532001Y1080763D01*
X1532143Y1080622D01*
G37*
G36*
G01X1531959Y1081004D02*
X1531777Y1081387D01*
X1532307Y1081918D01*
X1532691Y1081736D01*
X1532832Y1081594D01*
X1532100Y1080862D01*
X1531959Y1081004D01*
G37*
G36*
G01X1535282Y1084327D02*
X1535100Y1084711D01*
X1535631Y1085241D01*
X1536014Y1085059D01*
X1536156Y1084918D01*
X1535424Y1084186D01*
X1535282Y1084327D01*
G37*
G36*
G01X1539301Y1096344D02*
X1539665Y1096126D01*
X1539518Y1095391D01*
X1539098Y1095329D01*
X1538902Y1095368D01*
X1539105Y1096383D01*
X1539301Y1096344D01*
G37*
G36*
G01X1538475Y1094256D02*
X1538111Y1094474D01*
X1538258Y1095209D01*
X1538678Y1095270D01*
X1538874Y1095231D01*
X1538671Y1094216D01*
X1538475Y1094256D01*
G37*
G36*
G01X1538840Y1094040D02*
X1539204Y1093822D01*
X1539057Y1093086D01*
X1538637Y1093025D01*
X1538441Y1093064D01*
X1538644Y1094079D01*
X1538840Y1094040D01*
G37*
G36*
G01X1538379Y1091735D02*
X1538743Y1091517D01*
X1538596Y1090782D01*
X1538176Y1090721D01*
X1537980Y1090760D01*
X1538183Y1091775D01*
X1538379Y1091735D01*
G37*
G36*
G01X1538014Y1091951D02*
X1537650Y1092169D01*
X1537797Y1092905D01*
X1538217Y1092966D01*
X1538413Y1092927D01*
X1538210Y1091912D01*
X1538014Y1091951D01*
G37*
G36*
G01X1537553Y1089647D02*
X1537189Y1089865D01*
X1537336Y1090600D01*
X1537756Y1090662D01*
X1537952Y1090622D01*
X1537749Y1089608D01*
X1537553Y1089647D01*
G37*
G36*
G01X1537918Y1089431D02*
X1538282Y1089213D01*
X1538135Y1088478D01*
X1537715Y1088416D01*
X1537519Y1088455D01*
X1537722Y1089470D01*
X1537918Y1089431D01*
G37*
G36*
G01X1537092Y1087342D02*
X1536728Y1087561D01*
X1536875Y1088296D01*
X1537295Y1088357D01*
X1537491Y1088318D01*
X1537288Y1087303D01*
X1537092Y1087342D01*
G37*
G36*
G01X1535503Y1080585D02*
X1535686Y1080201D01*
X1535155Y1079671D01*
X1534772Y1079853D01*
X1534630Y1079994D01*
X1535362Y1080726D01*
X1535503Y1080585D01*
G37*
G36*
G01X1537165Y1082246D02*
X1537347Y1081863D01*
X1536817Y1081332D01*
X1536433Y1081515D01*
X1536292Y1081656D01*
X1537024Y1082388D01*
X1537165Y1082246D01*
G37*
G36*
G01X1536981Y1082628D02*
X1536799Y1083012D01*
X1537330Y1083542D01*
X1537713Y1083360D01*
X1537855Y1083219D01*
X1537123Y1082487D01*
X1536981Y1082628D01*
G37*
G36*
G01X1538827Y1083908D02*
X1539009Y1083524D01*
X1538479Y1082994D01*
X1538095Y1083176D01*
X1537954Y1083318D01*
X1538685Y1084049D01*
X1538827Y1083908D01*
G37*
G36*
G01X1535320Y1080966D02*
X1535138Y1081350D01*
X1535668Y1081880D01*
X1536052Y1081698D01*
X1536193Y1081557D01*
X1535461Y1080825D01*
X1535320Y1080966D01*
G37*
G36*
G01X1540737Y1091265D02*
X1541101Y1091046D01*
X1540954Y1090311D01*
X1540534Y1090250D01*
X1540338Y1090289D01*
X1540541Y1091304D01*
X1540737Y1091265D01*
G37*
G36*
G01X1540277Y1088960D02*
X1540641Y1088742D01*
X1540494Y1088007D01*
X1540074Y1087945D01*
X1539878Y1087984D01*
X1540080Y1088999D01*
X1540277Y1088960D01*
G37*
G36*
G01X1540372Y1091480D02*
X1540008Y1091698D01*
X1540155Y1092434D01*
X1540575Y1092495D01*
X1540771Y1092456D01*
X1540568Y1091441D01*
X1540372Y1091480D01*
G37*
G36*
G01X1539816Y1086656D02*
X1540181Y1086438D01*
X1540034Y1085702D01*
X1539613Y1085641D01*
X1539417Y1085680D01*
X1539620Y1086695D01*
X1539816Y1086656D01*
G37*
G36*
G01X1539912Y1089176D02*
X1539547Y1089394D01*
X1539694Y1090129D01*
X1540115Y1090191D01*
X1540311Y1090152D01*
X1540108Y1089137D01*
X1539912Y1089176D01*
G37*
G36*
G01X1539451Y1086871D02*
X1539087Y1087089D01*
X1539234Y1087825D01*
X1539654Y1087886D01*
X1539850Y1087847D01*
X1539648Y1086832D01*
X1539451Y1086871D01*
G37*
G36*
G01X1541658Y1095874D02*
X1542022Y1095655D01*
X1541875Y1094920D01*
X1541455Y1094859D01*
X1541259Y1094898D01*
X1541462Y1095913D01*
X1541658Y1095874D01*
G37*
G36*
G01X1541197Y1093569D02*
X1541562Y1093351D01*
X1541415Y1092615D01*
X1540995Y1092554D01*
X1540798Y1092593D01*
X1541001Y1093608D01*
X1541197Y1093569D01*
G37*
G36*
G01X1540832Y1093785D02*
X1540468Y1094003D01*
X1540615Y1094738D01*
X1541035Y1094800D01*
X1541231Y1094760D01*
X1541029Y1093746D01*
X1540832Y1093785D01*
G37*
G36*
G01X1529991Y1088674D02*
X1530173Y1088290D01*
X1529642Y1087760D01*
X1529259Y1087942D01*
X1529117Y1088083D01*
X1529849Y1088815D01*
X1529991Y1088674D01*
G37*
G36*
G01X1528329Y1087012D02*
X1528511Y1086629D01*
X1527981Y1086098D01*
X1527597Y1086280D01*
X1527456Y1086422D01*
X1528188Y1087154D01*
X1528329Y1087012D01*
G37*
G36*
G01X1528145Y1087394D02*
X1527963Y1087778D01*
X1528493Y1088308D01*
X1528877Y1088126D01*
X1529018Y1087984D01*
X1528287Y1087253D01*
X1528145Y1087394D01*
G37*
G36*
G01X1531276Y1092278D02*
X1531640Y1092059D01*
X1531493Y1091324D01*
X1531073Y1091263D01*
X1530877Y1091302D01*
X1531080Y1092317D01*
X1531276Y1092278D01*
G37*
G36*
G01X1530450Y1090189D02*
X1530086Y1090407D01*
X1530233Y1091143D01*
X1530653Y1091204D01*
X1530849Y1091165D01*
X1530646Y1090150D01*
X1530450Y1090189D01*
G37*
G36*
G01X1530911Y1092493D02*
X1530547Y1092712D01*
X1530694Y1093447D01*
X1531115Y1093508D01*
X1531311Y1093469D01*
X1531107Y1092454D01*
X1530911Y1092493D01*
G37*
G36*
G01X1531737Y1094582D02*
X1532102Y1094364D01*
X1531954Y1093628D01*
X1531534Y1093567D01*
X1531338Y1093606D01*
X1531541Y1094621D01*
X1531737Y1094582D01*
G37*
G36*
G01X1531373Y1094798D02*
X1531008Y1095016D01*
X1531156Y1095751D01*
X1531576Y1095813D01*
X1531772Y1095773D01*
X1531569Y1094758D01*
X1531373Y1094798D01*
G37*
G36*
G01X1530037Y1085304D02*
X1530219Y1084921D01*
X1529689Y1084390D01*
X1529305Y1084572D01*
X1529164Y1084714D01*
X1529896Y1085446D01*
X1530037Y1085304D01*
G37*
G36*
G01X1528191Y1084024D02*
X1528009Y1084408D01*
X1528540Y1084938D01*
X1528923Y1084756D01*
X1529065Y1084615D01*
X1528333Y1083883D01*
X1528191Y1084024D01*
G37*
G36*
G01X1533633Y1091806D02*
X1533997Y1091588D01*
X1533850Y1090852D01*
X1533430Y1090791D01*
X1533234Y1090830D01*
X1533437Y1091845D01*
X1533633Y1091806D01*
G37*
G36*
G01X1533268Y1092022D02*
X1532904Y1092240D01*
X1533051Y1092975D01*
X1533472Y1093036D01*
X1533668Y1092997D01*
X1533465Y1091982D01*
X1533268Y1092022D01*
G37*
G36*
G01X1534556Y1096414D02*
X1534920Y1096196D01*
X1534773Y1095461D01*
X1534353Y1095399D01*
X1534157Y1095439D01*
X1534360Y1096454D01*
X1534556Y1096414D01*
G37*
G36*
G01X1533730Y1094326D02*
X1533365Y1094544D01*
X1533513Y1095279D01*
X1533933Y1095341D01*
X1534129Y1095301D01*
X1533926Y1094287D01*
X1533730Y1094326D01*
G37*
G36*
G01X1534094Y1094110D02*
X1534459Y1093892D01*
X1534311Y1093156D01*
X1533891Y1093095D01*
X1533695Y1093134D01*
X1533898Y1094149D01*
X1534094Y1094110D01*
G37*
G36*
G01X1533172Y1089501D02*
X1533536Y1089283D01*
X1533389Y1088548D01*
X1532969Y1088487D01*
X1532773Y1088526D01*
X1532976Y1089541D01*
X1533172Y1089501D01*
G37*
G36*
G01X1532807Y1089717D02*
X1532443Y1089936D01*
X1532590Y1090671D01*
X1533010Y1090732D01*
X1533206Y1090693D01*
X1533003Y1089678D01*
X1532807Y1089717D01*
G37*
G36*
G01X1529853Y1085686D02*
X1529671Y1086070D01*
X1530201Y1086600D01*
X1530585Y1086418D01*
X1530726Y1086276D01*
X1529995Y1085545D01*
X1529853Y1085686D01*
G37*
G36*
G01X1531699Y1086966D02*
X1531881Y1086582D01*
X1531350Y1086052D01*
X1530967Y1086234D01*
X1530825Y1086375D01*
X1531557Y1087107D01*
X1531699Y1086966D01*
G37*
G36*
G01X1532551Y1094562D02*
X1532187Y1094780D01*
X1532334Y1095515D01*
X1532754Y1095577D01*
X1532951Y1095537D01*
X1532747Y1094522D01*
X1532551Y1094562D01*
G37*
G36*
G01X1532916Y1094346D02*
X1533280Y1094128D01*
X1533133Y1093392D01*
X1532713Y1093331D01*
X1532517Y1093370D01*
X1532720Y1094385D01*
X1532916Y1094346D01*
G37*
G36*
G01X1532090Y1092257D02*
X1531726Y1092476D01*
X1531873Y1093211D01*
X1532293Y1093272D01*
X1532489Y1093233D01*
X1532286Y1092218D01*
X1532090Y1092257D01*
G37*
G36*
G01X1531629Y1089953D02*
X1531265Y1090171D01*
X1531412Y1090907D01*
X1531832Y1090968D01*
X1532028Y1090929D01*
X1531825Y1089914D01*
X1531629Y1089953D01*
G37*
G36*
G01X1532455Y1092042D02*
X1532819Y1091823D01*
X1532672Y1091088D01*
X1532252Y1091027D01*
X1532056Y1091066D01*
X1532259Y1092081D01*
X1532455Y1092042D01*
G37*
G36*
G01X1533377Y1096650D02*
X1533742Y1096432D01*
X1533594Y1095697D01*
X1533174Y1095635D01*
X1532978Y1095675D01*
X1533181Y1096689D01*
X1533377Y1096650D01*
G37*
G36*
G01X1528998Y1086541D02*
X1528816Y1086925D01*
X1529346Y1087455D01*
X1529730Y1087273D01*
X1529871Y1087131D01*
X1529140Y1086400D01*
X1528998Y1086541D01*
G37*
G36*
G01X1529182Y1086159D02*
X1529364Y1085776D01*
X1528834Y1085245D01*
X1528450Y1085427D01*
X1528309Y1085569D01*
X1529041Y1086301D01*
X1529182Y1086159D01*
G37*
G36*
G01X1530844Y1087821D02*
X1531026Y1087437D01*
X1530495Y1086907D01*
X1530112Y1087089D01*
X1529970Y1087230D01*
X1530702Y1087962D01*
X1530844Y1087821D01*
G37*
G36*
G01X1529042Y1083173D02*
X1528860Y1083557D01*
X1529391Y1084087D01*
X1529774Y1083905D01*
X1529916Y1083764D01*
X1529184Y1083032D01*
X1529042Y1083173D01*
G37*
G36*
G01X1530888Y1084453D02*
X1531070Y1084070D01*
X1530540Y1083539D01*
X1530156Y1083721D01*
X1530015Y1083863D01*
X1530747Y1084595D01*
X1530888Y1084453D01*
G37*
G36*
G01X1530704Y1084835D02*
X1530522Y1085219D01*
X1531052Y1085749D01*
X1531436Y1085567D01*
X1531577Y1085425D01*
X1530846Y1084694D01*
X1530704Y1084835D01*
G37*
G36*
G01X1532550Y1086115D02*
X1532732Y1085731D01*
X1532201Y1085201D01*
X1531818Y1085383D01*
X1531676Y1085524D01*
X1532408Y1086256D01*
X1532550Y1086115D01*
G37*
G36*
G01X1532366Y1086497D02*
X1532184Y1086880D01*
X1532714Y1087411D01*
X1533098Y1087229D01*
X1533239Y1087087D01*
X1532507Y1086355D01*
X1532366Y1086497D01*
G37*
G36*
G01X1533986Y1089481D02*
X1533622Y1089700D01*
X1533769Y1090435D01*
X1534189Y1090496D01*
X1534385Y1090457D01*
X1534182Y1089442D01*
X1533986Y1089481D01*
G37*
G36*
G01X1534351Y1089266D02*
X1534715Y1089047D01*
X1534568Y1088312D01*
X1534147Y1088251D01*
X1533951Y1088290D01*
X1534155Y1089305D01*
X1534351Y1089266D01*
G37*
G36*
G01X1534908Y1094090D02*
X1534544Y1094308D01*
X1534691Y1095044D01*
X1535112Y1095105D01*
X1535308Y1095065D01*
X1535105Y1094051D01*
X1534908Y1094090D01*
G37*
G36*
G01X1535273Y1093874D02*
X1535637Y1093656D01*
X1535490Y1092920D01*
X1535070Y1092859D01*
X1534874Y1092898D01*
X1535077Y1093913D01*
X1535273Y1093874D01*
G37*
G36*
G01X1534447Y1091786D02*
X1534083Y1092004D01*
X1534230Y1092739D01*
X1534650Y1092800D01*
X1534846Y1092761D01*
X1534643Y1091746D01*
X1534447Y1091786D01*
G37*
G36*
G01X1534812Y1091570D02*
X1535176Y1091352D01*
X1535029Y1090616D01*
X1534609Y1090555D01*
X1534413Y1090594D01*
X1534616Y1091609D01*
X1534812Y1091570D01*
G37*
G36*
G01X1535734Y1096178D02*
X1536099Y1095960D01*
X1535952Y1095225D01*
X1535531Y1095163D01*
X1535335Y1095203D01*
X1535538Y1096218D01*
X1535734Y1096178D01*
G37*
G36*
G01X1537755Y1096796D02*
X1537391Y1097014D01*
X1537538Y1097749D01*
X1537958Y1097811D01*
X1538154Y1097771D01*
X1537951Y1096756D01*
X1537755Y1096796D01*
G37*
G36*
G01X1538675Y1101405D02*
X1538311Y1101623D01*
X1538458Y1102358D01*
X1538878Y1102420D01*
X1539074Y1102380D01*
X1538871Y1101365D01*
X1538675Y1101405D01*
G37*
G36*
G01X1539040Y1101189D02*
X1539405Y1100971D01*
X1539258Y1100235D01*
X1538837Y1100174D01*
X1538641Y1100213D01*
X1538844Y1101228D01*
X1539040Y1101189D01*
G37*
G36*
G01X1538215Y1099100D02*
X1537851Y1099318D01*
X1537998Y1100054D01*
X1538418Y1100115D01*
X1538614Y1100076D01*
X1538411Y1099061D01*
X1538215Y1099100D01*
G37*
G36*
G01X1538580Y1098884D02*
X1538945Y1098666D01*
X1538797Y1097931D01*
X1538377Y1097869D01*
X1538181Y1097909D01*
X1538384Y1098924D01*
X1538580Y1098884D01*
G37*
G36*
G01X1539501Y1103493D02*
X1539865Y1103275D01*
X1539718Y1102540D01*
X1539298Y1102479D01*
X1539102Y1102518D01*
X1539305Y1103533D01*
X1539501Y1103493D01*
G37*
G36*
G01X1539667Y1112780D02*
X1540067Y1112637D01*
Y1111887D01*
X1539667Y1111745D01*
X1539467D01*
Y1112780D01*
X1539667D01*
G37*
G36*
G01X1539267Y1110569D02*
X1538867Y1110712D01*
Y1111462D01*
X1539267Y1111605D01*
X1539467D01*
Y1110569D01*
X1539267D01*
G37*
G36*
G01X1539667Y1110430D02*
X1540067Y1110287D01*
Y1109537D01*
X1539667Y1109395D01*
X1539467D01*
Y1110430D01*
X1539667D01*
G37*
G36*
G01X1539267Y1105869D02*
X1538867Y1106012D01*
Y1106762D01*
X1539267Y1106905D01*
X1539467D01*
Y1105869D01*
X1539267D01*
G37*
G36*
G01X1539667Y1108080D02*
X1540067Y1107937D01*
Y1107187D01*
X1539667Y1107045D01*
X1539467D01*
Y1108080D01*
X1539667D01*
G37*
G36*
G01X1539267Y1108219D02*
X1538867Y1108362D01*
Y1109112D01*
X1539267Y1109255D01*
X1539467D01*
Y1108219D01*
X1539267D01*
G37*
G36*
G01X1541036Y1100933D02*
X1540671Y1101152D01*
X1540818Y1101887D01*
X1541239Y1101948D01*
X1541435Y1101909D01*
X1541232Y1100894D01*
X1541036Y1100933D01*
G37*
G36*
G01X1540575Y1098629D02*
X1540211Y1098847D01*
X1540358Y1099583D01*
X1540778Y1099644D01*
X1540974Y1099605D01*
X1540771Y1098590D01*
X1540575Y1098629D01*
G37*
G36*
G01X1541400Y1100718D02*
X1541765Y1100500D01*
X1541618Y1099764D01*
X1541198Y1099703D01*
X1541001Y1099742D01*
X1541204Y1100757D01*
X1541400Y1100718D01*
G37*
G36*
G01X1540114Y1096325D02*
X1539750Y1096543D01*
X1539897Y1097278D01*
X1540317Y1097339D01*
X1540513Y1097300D01*
X1540310Y1096285D01*
X1540114Y1096325D01*
G37*
G36*
G01X1540940Y1098413D02*
X1541304Y1098195D01*
X1541157Y1097460D01*
X1540737Y1097398D01*
X1540541Y1097438D01*
X1540744Y1098452D01*
X1540940Y1098413D01*
G37*
G36*
G01X1541861Y1103022D02*
X1542225Y1102804D01*
X1542078Y1102069D01*
X1541658Y1102007D01*
X1541462Y1102046D01*
X1541665Y1103061D01*
X1541861Y1103022D01*
G37*
G36*
G01X1541667Y1110569D02*
X1541267Y1110712D01*
Y1111462D01*
X1541667Y1111605D01*
X1541867D01*
Y1110569D01*
X1541667D01*
G37*
G36*
G01Y1105869D02*
X1541267Y1106012D01*
Y1106762D01*
X1541667Y1106905D01*
X1541867D01*
Y1105869D01*
X1541667D01*
G37*
G36*
G01Y1108219D02*
X1541267Y1108362D01*
Y1109112D01*
X1541667Y1109255D01*
X1541867D01*
Y1108219D01*
X1541667D01*
G37*
G36*
G01X1539858Y1101169D02*
X1539494Y1101387D01*
X1539641Y1102122D01*
X1540061Y1102183D01*
X1540257Y1102144D01*
X1540054Y1101129D01*
X1539858Y1101169D01*
G37*
G36*
G01X1540223Y1100953D02*
X1540587Y1100735D01*
X1540440Y1099999D01*
X1540020Y1099938D01*
X1539824Y1099977D01*
X1540027Y1100992D01*
X1540223Y1100953D01*
G37*
G36*
G01X1539397Y1098864D02*
X1539033Y1099082D01*
X1539180Y1099818D01*
X1539600Y1099879D01*
X1539796Y1099840D01*
X1539593Y1098825D01*
X1539397Y1098864D01*
G37*
G36*
G01X1538936Y1096560D02*
X1538572Y1096778D01*
X1538719Y1097513D01*
X1539139Y1097575D01*
X1539335Y1097536D01*
X1539132Y1096521D01*
X1538936Y1096560D01*
G37*
G36*
G01X1539762Y1098648D02*
X1540126Y1098430D01*
X1539979Y1097695D01*
X1539559Y1097634D01*
X1539363Y1097673D01*
X1539566Y1098688D01*
X1539762Y1098648D01*
G37*
G36*
G01X1540867Y1112780D02*
X1541267Y1112637D01*
Y1111887D01*
X1540867Y1111745D01*
X1540667D01*
Y1112780D01*
X1540867D01*
G37*
G36*
G01X1540467Y1110569D02*
X1540067Y1110712D01*
Y1111462D01*
X1540467Y1111605D01*
X1540667D01*
Y1110569D01*
X1540467D01*
G37*
G36*
G01X1540867Y1110430D02*
X1541267Y1110287D01*
Y1109537D01*
X1540867Y1109395D01*
X1540667D01*
Y1110430D01*
X1540867D01*
G37*
G36*
G01X1540467Y1105869D02*
X1540067Y1106012D01*
Y1106762D01*
X1540467Y1106905D01*
X1540667D01*
Y1105869D01*
X1540467D01*
G37*
G36*
G01X1540867Y1108080D02*
X1541267Y1107937D01*
Y1107187D01*
X1540867Y1107045D01*
X1540667D01*
Y1108080D01*
X1540867D01*
G37*
G36*
G01X1540467Y1108219D02*
X1540067Y1108362D01*
Y1109112D01*
X1540467Y1109255D01*
X1540667D01*
Y1108219D01*
X1540467D01*
G37*
G36*
G01X1540684Y1103257D02*
X1541048Y1103039D01*
X1540901Y1102304D01*
X1540481Y1102242D01*
X1540285Y1102281D01*
X1540488Y1103296D01*
X1540684Y1103257D01*
G37*
G36*
G01X1542118Y1098178D02*
X1542482Y1097960D01*
X1542335Y1097224D01*
X1541915Y1097163D01*
X1541719Y1097202D01*
X1541922Y1098217D01*
X1542118Y1098178D01*
G37*
G36*
G01X1541293Y1096089D02*
X1540929Y1096307D01*
X1541075Y1097043D01*
X1541496Y1097104D01*
X1541692Y1097065D01*
X1541489Y1096050D01*
X1541293Y1096089D01*
G37*
G36*
G01X1541753Y1098394D02*
X1541389Y1098612D01*
X1541536Y1099347D01*
X1541956Y1099409D01*
X1542152Y1099369D01*
X1541949Y1098354D01*
X1541753Y1098394D01*
G37*
G36*
G01X1526086Y1111344D02*
X1525686Y1111487D01*
Y1112237D01*
X1526086Y1112379D01*
X1526286D01*
Y1111344D01*
X1526086D01*
G37*
G36*
G01Y1108994D02*
X1525686Y1109137D01*
Y1109887D01*
X1526086Y1110029D01*
X1526286D01*
Y1108994D01*
X1526086D01*
G37*
G36*
G01X1526486Y1111204D02*
X1526886Y1111061D01*
Y1110311D01*
X1526486Y1110169D01*
X1526286D01*
Y1111204D01*
X1526486D01*
G37*
G36*
G01Y1108854D02*
X1526886Y1108711D01*
Y1107961D01*
X1526486Y1107819D01*
X1526286D01*
Y1108854D01*
X1526486D01*
G37*
G36*
G01X1527286Y1111344D02*
X1526886Y1111487D01*
Y1112237D01*
X1527286Y1112379D01*
X1527486D01*
Y1111344D01*
X1527286D01*
G37*
G36*
G01Y1108994D02*
X1526886Y1109137D01*
Y1109887D01*
X1527286Y1110029D01*
X1527486D01*
Y1108994D01*
X1527286D01*
G37*
G36*
G01X1527686Y1111204D02*
X1528086Y1111061D01*
Y1110311D01*
X1527686Y1110169D01*
X1527486D01*
Y1111204D01*
X1527686D01*
G37*
G36*
G01Y1108854D02*
X1528086Y1108711D01*
Y1107961D01*
X1527686Y1107819D01*
X1527486D01*
Y1108854D01*
X1527686D01*
G37*
G36*
G01X1533121Y1101495D02*
X1533486Y1101277D01*
X1533338Y1100541D01*
X1532918Y1100480D01*
X1532722Y1100519D01*
X1532925Y1101534D01*
X1533121Y1101495D01*
G37*
G36*
G01X1532660Y1099190D02*
X1533024Y1098972D01*
X1532877Y1098237D01*
X1532457Y1098176D01*
X1532261Y1098215D01*
X1532464Y1099230D01*
X1532660Y1099190D01*
G37*
G36*
G01X1532295Y1099406D02*
X1531931Y1099624D01*
X1532078Y1100360D01*
X1532498Y1100421D01*
X1532695Y1100382D01*
X1532491Y1099367D01*
X1532295Y1099406D01*
G37*
G36*
G01X1532199Y1096886D02*
X1532563Y1096668D01*
X1532416Y1095933D01*
X1531996Y1095871D01*
X1531799Y1095911D01*
X1532003Y1096925D01*
X1532199Y1096886D01*
G37*
G36*
G01X1531834Y1097102D02*
X1531470Y1097320D01*
X1531617Y1098056D01*
X1532037Y1098117D01*
X1532233Y1098078D01*
X1532030Y1097063D01*
X1531834Y1097102D01*
G37*
G36*
G01X1532757Y1101711D02*
X1532392Y1101929D01*
X1532540Y1102664D01*
X1532960Y1102725D01*
X1533156Y1102686D01*
X1532953Y1101671D01*
X1532757Y1101711D01*
G37*
G36*
G01X1533706Y1111509D02*
X1534106Y1111367D01*
Y1110617D01*
X1533706Y1110474D01*
X1533506D01*
Y1111509D01*
X1533706D01*
G37*
G36*
G01X1533306Y1111649D02*
X1532906Y1111792D01*
Y1112542D01*
X1533306Y1112684D01*
X1533506D01*
Y1111649D01*
X1533306D01*
G37*
G36*
G01Y1109299D02*
X1532906Y1109442D01*
Y1110192D01*
X1533306Y1110334D01*
X1533506D01*
Y1109299D01*
X1533306D01*
G37*
G36*
G01X1533706Y1106809D02*
X1534106Y1106667D01*
Y1105917D01*
X1533706Y1105774D01*
X1533506D01*
Y1106809D01*
X1533706D01*
G37*
G36*
G01X1533306Y1106949D02*
X1532906Y1107092D01*
Y1107842D01*
X1533306Y1107984D01*
X1533506D01*
Y1106949D01*
X1533306D01*
G37*
G36*
G01X1533706Y1109159D02*
X1534106Y1109017D01*
Y1108267D01*
X1533706Y1108124D01*
X1533506D01*
Y1109159D01*
X1533706D01*
G37*
G36*
G01X1535114Y1101239D02*
X1534749Y1101457D01*
X1534897Y1102192D01*
X1535317Y1102254D01*
X1535513Y1102214D01*
X1535310Y1101199D01*
X1535114Y1101239D01*
G37*
G36*
G01X1534652Y1098934D02*
X1534288Y1099153D01*
X1534435Y1099888D01*
X1534856Y1099949D01*
X1535052Y1099910D01*
X1534848Y1098895D01*
X1534652Y1098934D01*
G37*
G36*
G01X1535017Y1098719D02*
X1535381Y1098500D01*
X1535234Y1097765D01*
X1534814Y1097704D01*
X1534618Y1097743D01*
X1534821Y1098758D01*
X1535017Y1098719D01*
G37*
G36*
G01X1534191Y1096630D02*
X1533827Y1096848D01*
X1533974Y1097584D01*
X1534394Y1097645D01*
X1534590Y1097606D01*
X1534387Y1096591D01*
X1534191Y1096630D01*
G37*
G36*
G01X1535478Y1101023D02*
X1535843Y1100805D01*
X1535695Y1100069D01*
X1535275Y1100008D01*
X1535079Y1100047D01*
X1535282Y1101062D01*
X1535478Y1101023D01*
G37*
G36*
G01X1536106Y1111509D02*
X1536506Y1111367D01*
Y1110617D01*
X1536106Y1110474D01*
X1535906D01*
Y1111509D01*
X1536106D01*
G37*
G36*
G01X1535706Y1111649D02*
X1535306Y1111792D01*
Y1112542D01*
X1535706Y1112684D01*
X1535906D01*
Y1111649D01*
X1535706D01*
G37*
G36*
G01Y1109299D02*
X1535306Y1109442D01*
Y1110192D01*
X1535706Y1110334D01*
X1535906D01*
Y1109299D01*
X1535706D01*
G37*
G36*
G01X1536106Y1106809D02*
X1536506Y1106667D01*
Y1105917D01*
X1536106Y1105774D01*
X1535906D01*
Y1106809D01*
X1536106D01*
G37*
G36*
G01X1535706Y1106949D02*
X1535306Y1107092D01*
Y1107842D01*
X1535706Y1107984D01*
X1535906D01*
Y1106949D01*
X1535706D01*
G37*
G36*
G01X1536106Y1109159D02*
X1536506Y1109017D01*
Y1108267D01*
X1536106Y1108124D01*
X1535906D01*
Y1109159D01*
X1536106D01*
G37*
G36*
G01X1534300Y1101259D02*
X1534664Y1101041D01*
X1534517Y1100305D01*
X1534097Y1100244D01*
X1533900Y1100283D01*
X1534104Y1101298D01*
X1534300Y1101259D01*
G37*
G36*
G01X1533839Y1098955D02*
X1534203Y1098736D01*
X1534056Y1098001D01*
X1533635Y1097940D01*
X1533439Y1097979D01*
X1533642Y1098994D01*
X1533839Y1098955D01*
G37*
G36*
G01X1533474Y1099170D02*
X1533110Y1099389D01*
X1533257Y1100124D01*
X1533677Y1100185D01*
X1533873Y1100146D01*
X1533670Y1099131D01*
X1533474Y1099170D01*
G37*
G36*
G01X1533013Y1096866D02*
X1532648Y1097084D01*
X1532796Y1097820D01*
X1533216Y1097881D01*
X1533412Y1097842D01*
X1533209Y1096827D01*
X1533013Y1096866D01*
G37*
G36*
G01X1534506Y1109299D02*
X1534106Y1109442D01*
Y1110192D01*
X1534506Y1110334D01*
X1534706D01*
Y1109299D01*
X1534506D01*
G37*
G36*
G01X1534906Y1106809D02*
X1535306Y1106667D01*
Y1105917D01*
X1534906Y1105774D01*
X1534706D01*
Y1106809D01*
X1534906D01*
G37*
G36*
G01X1534506Y1106949D02*
X1534106Y1107092D01*
Y1107842D01*
X1534506Y1107984D01*
X1534706D01*
Y1106949D01*
X1534506D01*
G37*
G36*
G01X1534906Y1109159D02*
X1535306Y1109017D01*
Y1108267D01*
X1534906Y1108124D01*
X1534706D01*
Y1109159D01*
X1534906D01*
G37*
G36*
G01Y1111509D02*
X1535306Y1111367D01*
Y1110617D01*
X1534906Y1110474D01*
X1534706D01*
Y1111509D01*
X1534906D01*
G37*
G36*
G01X1534506Y1111649D02*
X1534106Y1111792D01*
Y1112542D01*
X1534506Y1112684D01*
X1534706D01*
Y1111649D01*
X1534506D01*
G37*
G36*
G01X1533935Y1101475D02*
X1533571Y1101693D01*
X1533718Y1102428D01*
X1534138Y1102489D01*
X1534334Y1102450D01*
X1534131Y1101435D01*
X1533935Y1101475D01*
G37*
G36*
G01X1535370Y1096394D02*
X1535006Y1096612D01*
X1535153Y1097348D01*
X1535573Y1097409D01*
X1535769Y1097370D01*
X1535566Y1096355D01*
X1535370Y1096394D01*
G37*
G36*
G01X1536292Y1101003D02*
X1535928Y1101221D01*
X1536075Y1101956D01*
X1536495Y1102018D01*
X1536692Y1101978D01*
X1536488Y1100963D01*
X1536292Y1101003D01*
G37*
G36*
G01X1535831Y1098698D02*
X1535467Y1098917D01*
X1535614Y1099652D01*
X1536034Y1099713D01*
X1536230Y1099674D01*
X1536027Y1098659D01*
X1535831Y1098698D01*
G37*
G36*
G01X1536657Y1100787D02*
X1537021Y1100569D01*
X1536874Y1099833D01*
X1536454Y1099772D01*
X1536258Y1099811D01*
X1536461Y1100826D01*
X1536657Y1100787D01*
G37*
G36*
G01X1536196Y1098483D02*
X1536560Y1098264D01*
X1536413Y1097529D01*
X1535993Y1097468D01*
X1535797Y1097507D01*
X1536000Y1098522D01*
X1536196Y1098483D01*
G37*
G36*
G01X1537306Y1109159D02*
X1537706Y1109017D01*
Y1108267D01*
X1537306Y1108124D01*
X1537106D01*
Y1109159D01*
X1537306D01*
G37*
G36*
G01Y1106809D02*
X1537706Y1106667D01*
Y1105917D01*
X1537306Y1105774D01*
X1537106D01*
Y1106809D01*
X1537306D01*
G37*
G36*
G01X1536906Y1106949D02*
X1536506Y1107092D01*
Y1107842D01*
X1536906Y1107984D01*
X1537106D01*
Y1106949D01*
X1536906D01*
G37*
G36*
G01Y1111649D02*
X1536506Y1111792D01*
Y1112542D01*
X1536906Y1112684D01*
X1537106D01*
Y1111649D01*
X1536906D01*
G37*
G36*
G01X1537306Y1111509D02*
X1537706Y1111367D01*
Y1110617D01*
X1537306Y1110474D01*
X1537106D01*
Y1111509D01*
X1537306D01*
G37*
G36*
G01X1536906Y1109299D02*
X1536506Y1109442D01*
Y1110192D01*
X1536906Y1110334D01*
X1537106D01*
Y1109299D01*
X1536906D01*
G37*
G36*
G01X1539267Y1117619D02*
X1538867Y1117762D01*
Y1118512D01*
X1539267Y1118655D01*
X1539467D01*
Y1117619D01*
X1539267D01*
G37*
G36*
G01X1539667Y1117480D02*
X1540067Y1117337D01*
Y1116587D01*
X1539667Y1116445D01*
X1539467D01*
Y1117480D01*
X1539667D01*
G37*
G36*
G01X1539267Y1115269D02*
X1538867Y1115412D01*
Y1116162D01*
X1539267Y1116305D01*
X1539467D01*
Y1115269D01*
X1539267D01*
G37*
G36*
G01X1539667Y1115130D02*
X1540067Y1114987D01*
Y1114237D01*
X1539667Y1114095D01*
X1539467D01*
Y1115130D01*
X1539667D01*
G37*
G36*
G01X1539267Y1112919D02*
X1538867Y1113062D01*
Y1113812D01*
X1539267Y1113955D01*
X1539467D01*
Y1112919D01*
X1539267D01*
G37*
G36*
G01X1539667Y1129230D02*
X1540067Y1129087D01*
Y1128337D01*
X1539667Y1128195D01*
X1539467D01*
Y1129230D01*
X1539667D01*
G37*
G36*
G01X1539267Y1127019D02*
X1538867Y1127162D01*
Y1127912D01*
X1539267Y1128055D01*
X1539467D01*
Y1127019D01*
X1539267D01*
G37*
G36*
G01X1539667Y1119830D02*
X1540067Y1119687D01*
Y1118937D01*
X1539667Y1118795D01*
X1539467D01*
Y1119830D01*
X1539667D01*
G37*
G36*
G01Y1122180D02*
X1540067Y1122037D01*
Y1121287D01*
X1539667Y1121145D01*
X1539467D01*
Y1122180D01*
X1539667D01*
G37*
G36*
G01Y1124530D02*
X1540067Y1124387D01*
Y1123637D01*
X1539667Y1123495D01*
X1539467D01*
Y1124530D01*
X1539667D01*
G37*
G36*
G01X1539267Y1119969D02*
X1538867Y1120112D01*
Y1120862D01*
X1539267Y1121005D01*
X1539467D01*
Y1119969D01*
X1539267D01*
G37*
G36*
G01Y1122319D02*
X1538867Y1122462D01*
Y1123212D01*
X1539267Y1123355D01*
X1539467D01*
Y1122319D01*
X1539267D01*
G37*
G36*
G01X1539667Y1126880D02*
X1540067Y1126737D01*
Y1125987D01*
X1539667Y1125845D01*
X1539467D01*
Y1126880D01*
X1539667D01*
G37*
G36*
G01X1539267Y1124669D02*
X1538867Y1124812D01*
Y1125562D01*
X1539267Y1125705D01*
X1539467D01*
Y1124669D01*
X1539267D01*
G37*
G36*
G01X1541667Y1117619D02*
X1541267Y1117762D01*
Y1118512D01*
X1541667Y1118655D01*
X1541867D01*
Y1117619D01*
X1541667D01*
G37*
G36*
G01Y1115269D02*
X1541267Y1115412D01*
Y1116162D01*
X1541667Y1116305D01*
X1541867D01*
Y1115269D01*
X1541667D01*
G37*
G36*
G01Y1112919D02*
X1541267Y1113062D01*
Y1113812D01*
X1541667Y1113955D01*
X1541867D01*
Y1112919D01*
X1541667D01*
G37*
G36*
G01Y1127019D02*
X1541267Y1127162D01*
Y1127912D01*
X1541667Y1128055D01*
X1541867D01*
Y1127019D01*
X1541667D01*
G37*
G36*
G01Y1124669D02*
X1541267Y1124812D01*
Y1125562D01*
X1541667Y1125705D01*
X1541867D01*
Y1124669D01*
X1541667D01*
G37*
G36*
G01Y1119969D02*
X1541267Y1120112D01*
Y1120862D01*
X1541667Y1121005D01*
X1541867D01*
Y1119969D01*
X1541667D01*
G37*
G36*
G01Y1122319D02*
X1541267Y1122462D01*
Y1123212D01*
X1541667Y1123355D01*
X1541867D01*
Y1122319D01*
X1541667D01*
G37*
G36*
G01X1540467Y1117619D02*
X1540067Y1117762D01*
Y1118512D01*
X1540467Y1118655D01*
X1540667D01*
Y1117619D01*
X1540467D01*
G37*
G36*
G01X1540867Y1117480D02*
X1541267Y1117337D01*
Y1116587D01*
X1540867Y1116445D01*
X1540667D01*
Y1117480D01*
X1540867D01*
G37*
G36*
G01X1540467Y1115269D02*
X1540067Y1115412D01*
Y1116162D01*
X1540467Y1116305D01*
X1540667D01*
Y1115269D01*
X1540467D01*
G37*
G36*
G01X1540867Y1115130D02*
X1541267Y1114987D01*
Y1114237D01*
X1540867Y1114095D01*
X1540667D01*
Y1115130D01*
X1540867D01*
G37*
G36*
G01X1540467Y1112919D02*
X1540067Y1113062D01*
Y1113812D01*
X1540467Y1113955D01*
X1540667D01*
Y1112919D01*
X1540467D01*
G37*
G36*
G01X1540867Y1129230D02*
X1541267Y1129087D01*
Y1128337D01*
X1540867Y1128195D01*
X1540667D01*
Y1129230D01*
X1540867D01*
G37*
G36*
G01X1540467Y1127019D02*
X1540067Y1127162D01*
Y1127912D01*
X1540467Y1128055D01*
X1540667D01*
Y1127019D01*
X1540467D01*
G37*
G36*
G01X1540867Y1126880D02*
X1541267Y1126737D01*
Y1125987D01*
X1540867Y1125845D01*
X1540667D01*
Y1126880D01*
X1540867D01*
G37*
G36*
G01X1540467Y1124669D02*
X1540067Y1124812D01*
Y1125562D01*
X1540467Y1125705D01*
X1540667D01*
Y1124669D01*
X1540467D01*
G37*
G36*
G01X1540867Y1119830D02*
X1541267Y1119687D01*
Y1118937D01*
X1540867Y1118795D01*
X1540667D01*
Y1119830D01*
X1540867D01*
G37*
G36*
G01Y1122180D02*
X1541267Y1122037D01*
Y1121287D01*
X1540867Y1121145D01*
X1540667D01*
Y1122180D01*
X1540867D01*
G37*
G36*
G01Y1124530D02*
X1541267Y1124387D01*
Y1123637D01*
X1540867Y1123495D01*
X1540667D01*
Y1124530D01*
X1540867D01*
G37*
G36*
G01X1540467Y1119969D02*
X1540067Y1120112D01*
Y1120862D01*
X1540467Y1121005D01*
X1540667D01*
Y1119969D01*
X1540467D01*
G37*
G36*
G01Y1122319D02*
X1540067Y1122462D01*
Y1123212D01*
X1540467Y1123355D01*
X1540667D01*
Y1122319D01*
X1540467D01*
G37*
G36*
G01X1526086Y1113694D02*
X1525686Y1113837D01*
Y1114587D01*
X1526086Y1114729D01*
X1526286D01*
Y1113694D01*
X1526086D01*
G37*
G36*
G01Y1116044D02*
X1525686Y1116187D01*
Y1116937D01*
X1526086Y1117079D01*
X1526286D01*
Y1116044D01*
X1526086D01*
G37*
G36*
G01X1526486Y1113554D02*
X1526886Y1113411D01*
Y1112661D01*
X1526486Y1112519D01*
X1526286D01*
Y1113554D01*
X1526486D01*
G37*
G36*
G01Y1115904D02*
X1526886Y1115761D01*
Y1115011D01*
X1526486Y1114869D01*
X1526286D01*
Y1115904D01*
X1526486D01*
G37*
G36*
G01Y1118254D02*
X1526886Y1118111D01*
Y1117361D01*
X1526486Y1117219D01*
X1526286D01*
Y1118254D01*
X1526486D01*
G37*
G36*
G01X1526086Y1127794D02*
X1525686Y1127937D01*
Y1128687D01*
X1526086Y1128829D01*
X1526286D01*
Y1127794D01*
X1526086D01*
G37*
G36*
G01Y1118394D02*
X1525686Y1118537D01*
Y1119287D01*
X1526086Y1119429D01*
X1526286D01*
Y1118394D01*
X1526086D01*
G37*
G36*
G01X1526486Y1127654D02*
X1526886Y1127511D01*
Y1126761D01*
X1526486Y1126619D01*
X1526286D01*
Y1127654D01*
X1526486D01*
G37*
G36*
G01Y1120604D02*
X1526886Y1120461D01*
Y1119711D01*
X1526486Y1119569D01*
X1526286D01*
Y1120604D01*
X1526486D01*
G37*
G36*
G01Y1122954D02*
X1526886Y1122811D01*
Y1122061D01*
X1526486Y1121919D01*
X1526286D01*
Y1122954D01*
X1526486D01*
G37*
G36*
G01Y1125304D02*
X1526886Y1125161D01*
Y1124411D01*
X1526486Y1124269D01*
X1526286D01*
Y1125304D01*
X1526486D01*
G37*
G36*
G01X1526086Y1125444D02*
X1525686Y1125587D01*
Y1126337D01*
X1526086Y1126479D01*
X1526286D01*
Y1125444D01*
X1526086D01*
G37*
G36*
G01Y1120744D02*
X1525686Y1120887D01*
Y1121637D01*
X1526086Y1121779D01*
X1526286D01*
Y1120744D01*
X1526086D01*
G37*
G36*
G01Y1123094D02*
X1525686Y1123237D01*
Y1123987D01*
X1526086Y1124129D01*
X1526286D01*
Y1123094D01*
X1526086D01*
G37*
G36*
G01X1527286Y1113694D02*
X1526886Y1113837D01*
Y1114587D01*
X1527286Y1114729D01*
X1527486D01*
Y1113694D01*
X1527286D01*
G37*
G36*
G01Y1116044D02*
X1526886Y1116187D01*
Y1116937D01*
X1527286Y1117079D01*
X1527486D01*
Y1116044D01*
X1527286D01*
G37*
G36*
G01Y1127794D02*
X1526886Y1127937D01*
Y1128687D01*
X1527286Y1128829D01*
X1527486D01*
Y1127794D01*
X1527286D01*
G37*
G36*
G01Y1118394D02*
X1526886Y1118537D01*
Y1119287D01*
X1527286Y1119429D01*
X1527486D01*
Y1118394D01*
X1527286D01*
G37*
G36*
G01Y1125444D02*
X1526886Y1125587D01*
Y1126337D01*
X1527286Y1126479D01*
X1527486D01*
Y1125444D01*
X1527286D01*
G37*
G36*
G01Y1120744D02*
X1526886Y1120887D01*
Y1121637D01*
X1527286Y1121779D01*
X1527486D01*
Y1120744D01*
X1527286D01*
G37*
G36*
G01Y1123094D02*
X1526886Y1123237D01*
Y1123987D01*
X1527286Y1124129D01*
X1527486D01*
Y1123094D01*
X1527286D01*
G37*
G36*
G01X1527686Y1113554D02*
X1528086Y1113411D01*
Y1112661D01*
X1527686Y1112519D01*
X1527486D01*
Y1113554D01*
X1527686D01*
G37*
G36*
G01Y1115904D02*
X1528086Y1115761D01*
Y1115011D01*
X1527686Y1114869D01*
X1527486D01*
Y1115904D01*
X1527686D01*
G37*
G36*
G01Y1118254D02*
X1528086Y1118111D01*
Y1117361D01*
X1527686Y1117219D01*
X1527486D01*
Y1118254D01*
X1527686D01*
G37*
G36*
G01Y1127654D02*
X1528086Y1127511D01*
Y1126761D01*
X1527686Y1126619D01*
X1527486D01*
Y1127654D01*
X1527686D01*
G37*
G36*
G01Y1120604D02*
X1528086Y1120461D01*
Y1119711D01*
X1527686Y1119569D01*
X1527486D01*
Y1120604D01*
X1527686D01*
G37*
G36*
G01Y1122954D02*
X1528086Y1122811D01*
Y1122061D01*
X1527686Y1121919D01*
X1527486D01*
Y1122954D01*
X1527686D01*
G37*
G36*
G01Y1125304D02*
X1528086Y1125161D01*
Y1124411D01*
X1527686Y1124269D01*
X1527486D01*
Y1125304D01*
X1527686D01*
G37*
G36*
G01X1533706Y1118559D02*
X1534106Y1118417D01*
Y1117667D01*
X1533706Y1117524D01*
X1533506D01*
Y1118559D01*
X1533706D01*
G37*
G36*
G01Y1113859D02*
X1534106Y1113717D01*
Y1112967D01*
X1533706Y1112824D01*
X1533506D01*
Y1113859D01*
X1533706D01*
G37*
G36*
G01Y1116209D02*
X1534106Y1116067D01*
Y1115317D01*
X1533706Y1115174D01*
X1533506D01*
Y1116209D01*
X1533706D01*
G37*
G36*
G01X1533306Y1113999D02*
X1532906Y1114142D01*
Y1114892D01*
X1533306Y1115034D01*
X1533506D01*
Y1113999D01*
X1533306D01*
G37*
G36*
G01Y1116349D02*
X1532906Y1116492D01*
Y1117242D01*
X1533306Y1117384D01*
X1533506D01*
Y1116349D01*
X1533306D01*
G37*
G36*
G01X1533706Y1127959D02*
X1534106Y1127817D01*
Y1127067D01*
X1533706Y1126924D01*
X1533506D01*
Y1127959D01*
X1533706D01*
G37*
G36*
G01X1533306Y1128099D02*
X1532906Y1128242D01*
Y1128992D01*
X1533306Y1129134D01*
X1533506D01*
Y1128099D01*
X1533306D01*
G37*
G36*
G01X1533706Y1125609D02*
X1534106Y1125467D01*
Y1124717D01*
X1533706Y1124574D01*
X1533506D01*
Y1125609D01*
X1533706D01*
G37*
G36*
G01X1533306Y1125749D02*
X1532906Y1125892D01*
Y1126642D01*
X1533306Y1126784D01*
X1533506D01*
Y1125749D01*
X1533306D01*
G37*
G36*
G01X1533706Y1120909D02*
X1534106Y1120767D01*
Y1120017D01*
X1533706Y1119874D01*
X1533506D01*
Y1120909D01*
X1533706D01*
G37*
G36*
G01Y1123259D02*
X1534106Y1123117D01*
Y1122367D01*
X1533706Y1122224D01*
X1533506D01*
Y1123259D01*
X1533706D01*
G37*
G36*
G01X1533306Y1118699D02*
X1532906Y1118842D01*
Y1119592D01*
X1533306Y1119734D01*
X1533506D01*
Y1118699D01*
X1533306D01*
G37*
G36*
G01Y1121049D02*
X1532906Y1121192D01*
Y1121942D01*
X1533306Y1122084D01*
X1533506D01*
Y1121049D01*
X1533306D01*
G37*
G36*
G01Y1123399D02*
X1532906Y1123542D01*
Y1124292D01*
X1533306Y1124434D01*
X1533506D01*
Y1123399D01*
X1533306D01*
G37*
G36*
G01X1536106Y1118559D02*
X1536506Y1118417D01*
Y1117667D01*
X1536106Y1117524D01*
X1535906D01*
Y1118559D01*
X1536106D01*
G37*
G36*
G01Y1113859D02*
X1536506Y1113717D01*
Y1112967D01*
X1536106Y1112824D01*
X1535906D01*
Y1113859D01*
X1536106D01*
G37*
G36*
G01Y1116209D02*
X1536506Y1116067D01*
Y1115317D01*
X1536106Y1115174D01*
X1535906D01*
Y1116209D01*
X1536106D01*
G37*
G36*
G01X1535706Y1113999D02*
X1535306Y1114142D01*
Y1114892D01*
X1535706Y1115034D01*
X1535906D01*
Y1113999D01*
X1535706D01*
G37*
G36*
G01Y1116349D02*
X1535306Y1116492D01*
Y1117242D01*
X1535706Y1117384D01*
X1535906D01*
Y1116349D01*
X1535706D01*
G37*
G36*
G01X1536106Y1127959D02*
X1536506Y1127817D01*
Y1127067D01*
X1536106Y1126924D01*
X1535906D01*
Y1127959D01*
X1536106D01*
G37*
G36*
G01X1535706Y1128099D02*
X1535306Y1128242D01*
Y1128992D01*
X1535706Y1129134D01*
X1535906D01*
Y1128099D01*
X1535706D01*
G37*
G36*
G01X1536106Y1125609D02*
X1536506Y1125467D01*
Y1124717D01*
X1536106Y1124574D01*
X1535906D01*
Y1125609D01*
X1536106D01*
G37*
G36*
G01X1535706Y1125749D02*
X1535306Y1125892D01*
Y1126642D01*
X1535706Y1126784D01*
X1535906D01*
Y1125749D01*
X1535706D01*
G37*
G36*
G01X1536106Y1120909D02*
X1536506Y1120767D01*
Y1120017D01*
X1536106Y1119874D01*
X1535906D01*
Y1120909D01*
X1536106D01*
G37*
G36*
G01Y1123259D02*
X1536506Y1123117D01*
Y1122367D01*
X1536106Y1122224D01*
X1535906D01*
Y1123259D01*
X1536106D01*
G37*
G36*
G01X1535706Y1118699D02*
X1535306Y1118842D01*
Y1119592D01*
X1535706Y1119734D01*
X1535906D01*
Y1118699D01*
X1535706D01*
G37*
G36*
G01Y1121049D02*
X1535306Y1121192D01*
Y1121942D01*
X1535706Y1122084D01*
X1535906D01*
Y1121049D01*
X1535706D01*
G37*
G36*
G01Y1123399D02*
X1535306Y1123542D01*
Y1124292D01*
X1535706Y1124434D01*
X1535906D01*
Y1123399D01*
X1535706D01*
G37*
G36*
G01X1534906Y1113859D02*
X1535306Y1113717D01*
Y1112967D01*
X1534906Y1112824D01*
X1534706D01*
Y1113859D01*
X1534906D01*
G37*
G36*
G01Y1116209D02*
X1535306Y1116067D01*
Y1115317D01*
X1534906Y1115174D01*
X1534706D01*
Y1116209D01*
X1534906D01*
G37*
G36*
G01X1534506Y1113999D02*
X1534106Y1114142D01*
Y1114892D01*
X1534506Y1115034D01*
X1534706D01*
Y1113999D01*
X1534506D01*
G37*
G36*
G01Y1116349D02*
X1534106Y1116492D01*
Y1117242D01*
X1534506Y1117384D01*
X1534706D01*
Y1116349D01*
X1534506D01*
G37*
G36*
G01X1534906Y1118559D02*
X1535306Y1118417D01*
Y1117667D01*
X1534906Y1117524D01*
X1534706D01*
Y1118559D01*
X1534906D01*
G37*
G36*
G01Y1127959D02*
X1535306Y1127817D01*
Y1127067D01*
X1534906Y1126924D01*
X1534706D01*
Y1127959D01*
X1534906D01*
G37*
G36*
G01X1534506Y1128099D02*
X1534106Y1128242D01*
Y1128992D01*
X1534506Y1129134D01*
X1534706D01*
Y1128099D01*
X1534506D01*
G37*
G36*
G01X1534906Y1125609D02*
X1535306Y1125467D01*
Y1124717D01*
X1534906Y1124574D01*
X1534706D01*
Y1125609D01*
X1534906D01*
G37*
G36*
G01X1534506Y1125749D02*
X1534106Y1125892D01*
Y1126642D01*
X1534506Y1126784D01*
X1534706D01*
Y1125749D01*
X1534506D01*
G37*
G36*
G01X1534906Y1120909D02*
X1535306Y1120767D01*
Y1120017D01*
X1534906Y1119874D01*
X1534706D01*
Y1120909D01*
X1534906D01*
G37*
G36*
G01Y1123259D02*
X1535306Y1123117D01*
Y1122367D01*
X1534906Y1122224D01*
X1534706D01*
Y1123259D01*
X1534906D01*
G37*
G36*
G01X1534506Y1118699D02*
X1534106Y1118842D01*
Y1119592D01*
X1534506Y1119734D01*
X1534706D01*
Y1118699D01*
X1534506D01*
G37*
G36*
G01Y1121049D02*
X1534106Y1121192D01*
Y1121942D01*
X1534506Y1122084D01*
X1534706D01*
Y1121049D01*
X1534506D01*
G37*
G36*
G01Y1123399D02*
X1534106Y1123542D01*
Y1124292D01*
X1534506Y1124434D01*
X1534706D01*
Y1123399D01*
X1534506D01*
G37*
G36*
G01X1537306Y1113859D02*
X1537706Y1113717D01*
Y1112967D01*
X1537306Y1112824D01*
X1537106D01*
Y1113859D01*
X1537306D01*
G37*
G36*
G01Y1116209D02*
X1537706Y1116067D01*
Y1115317D01*
X1537306Y1115174D01*
X1537106D01*
Y1116209D01*
X1537306D01*
G37*
G36*
G01Y1118559D02*
X1537706Y1118417D01*
Y1117667D01*
X1537306Y1117524D01*
X1537106D01*
Y1118559D01*
X1537306D01*
G37*
G36*
G01X1536906Y1113999D02*
X1536506Y1114142D01*
Y1114892D01*
X1536906Y1115034D01*
X1537106D01*
Y1113999D01*
X1536906D01*
G37*
G36*
G01Y1116349D02*
X1536506Y1116492D01*
Y1117242D01*
X1536906Y1117384D01*
X1537106D01*
Y1116349D01*
X1536906D01*
G37*
G36*
G01Y1128099D02*
X1536506Y1128242D01*
Y1128992D01*
X1536906Y1129134D01*
X1537106D01*
Y1128099D01*
X1536906D01*
G37*
G36*
G01X1537306Y1127959D02*
X1537706Y1127817D01*
Y1127067D01*
X1537306Y1126924D01*
X1537106D01*
Y1127959D01*
X1537306D01*
G37*
G36*
G01X1536906Y1125749D02*
X1536506Y1125892D01*
Y1126642D01*
X1536906Y1126784D01*
X1537106D01*
Y1125749D01*
X1536906D01*
G37*
G36*
G01X1537306Y1125609D02*
X1537706Y1125467D01*
Y1124717D01*
X1537306Y1124574D01*
X1537106D01*
Y1125609D01*
X1537306D01*
G37*
G36*
G01X1536906Y1123399D02*
X1536506Y1123542D01*
Y1124292D01*
X1536906Y1124434D01*
X1537106D01*
Y1123399D01*
X1536906D01*
G37*
G36*
G01Y1118699D02*
X1536506Y1118842D01*
Y1119592D01*
X1536906Y1119734D01*
X1537106D01*
Y1118699D01*
X1536906D01*
G37*
G36*
G01Y1121049D02*
X1536506Y1121192D01*
Y1121942D01*
X1536906Y1122084D01*
X1537106D01*
Y1121049D01*
X1536906D01*
G37*
G36*
G01X1537306Y1120909D02*
X1537706Y1120767D01*
Y1120017D01*
X1537306Y1119874D01*
X1537106D01*
Y1120909D01*
X1537306D01*
G37*
G36*
G01Y1123259D02*
X1537706Y1123117D01*
Y1122367D01*
X1537306Y1122224D01*
X1537106D01*
Y1123259D01*
X1537306D01*
G37*
G36*
G01X1539267Y1134069D02*
X1538867Y1134212D01*
Y1134962D01*
X1539267Y1135105D01*
X1539467D01*
Y1134069D01*
X1539267D01*
G37*
G36*
G01X1539667Y1133930D02*
X1540067Y1133787D01*
Y1133037D01*
X1539667Y1132895D01*
X1539467D01*
Y1133930D01*
X1539667D01*
G37*
G36*
G01X1539267Y1131719D02*
X1538867Y1131862D01*
Y1132612D01*
X1539267Y1132755D01*
X1539467D01*
Y1131719D01*
X1539267D01*
G37*
G36*
G01Y1129369D02*
X1538867Y1129512D01*
Y1130262D01*
X1539267Y1130405D01*
X1539467D01*
Y1129369D01*
X1539267D01*
G37*
G36*
G01X1539667Y1131580D02*
X1540067Y1131437D01*
Y1130687D01*
X1539667Y1130545D01*
X1539467D01*
Y1131580D01*
X1539667D01*
G37*
G36*
G01X1539267Y1141119D02*
X1538867Y1141262D01*
Y1142012D01*
X1539267Y1142155D01*
X1539467D01*
Y1141119D01*
X1539267D01*
G37*
G36*
G01X1539667Y1140980D02*
X1540067Y1140837D01*
Y1140087D01*
X1539667Y1139945D01*
X1539467D01*
Y1140980D01*
X1539667D01*
G37*
G36*
G01Y1138630D02*
X1540067Y1138487D01*
Y1137737D01*
X1539667Y1137595D01*
X1539467D01*
Y1138630D01*
X1539667D01*
G37*
G36*
G01Y1136280D02*
X1540067Y1136137D01*
Y1135387D01*
X1539667Y1135245D01*
X1539467D01*
Y1136280D01*
X1539667D01*
G37*
G36*
G01X1539267Y1136419D02*
X1538867Y1136562D01*
Y1137312D01*
X1539267Y1137455D01*
X1539467D01*
Y1136419D01*
X1539267D01*
G37*
G36*
G01Y1138769D02*
X1538867Y1138912D01*
Y1139662D01*
X1539267Y1139805D01*
X1539467D01*
Y1138769D01*
X1539267D01*
G37*
G36*
G01X1541667Y1131719D02*
X1541267Y1131862D01*
Y1132612D01*
X1541667Y1132755D01*
X1541867D01*
Y1131719D01*
X1541667D01*
G37*
G36*
G01Y1129369D02*
X1541267Y1129512D01*
Y1130262D01*
X1541667Y1130405D01*
X1541867D01*
Y1129369D01*
X1541667D01*
G37*
G36*
G01Y1134069D02*
X1541267Y1134212D01*
Y1134962D01*
X1541667Y1135105D01*
X1541867D01*
Y1134069D01*
X1541667D01*
G37*
G36*
G01Y1136419D02*
X1541267Y1136562D01*
Y1137312D01*
X1541667Y1137455D01*
X1541867D01*
Y1136419D01*
X1541667D01*
G37*
G36*
G01Y1138769D02*
X1541267Y1138912D01*
Y1139662D01*
X1541667Y1139805D01*
X1541867D01*
Y1138769D01*
X1541667D01*
G37*
G36*
G01X1540867Y1133930D02*
X1541267Y1133787D01*
Y1133037D01*
X1540867Y1132895D01*
X1540667D01*
Y1133930D01*
X1540867D01*
G37*
G36*
G01X1540467Y1131719D02*
X1540067Y1131862D01*
Y1132612D01*
X1540467Y1132755D01*
X1540667D01*
Y1131719D01*
X1540467D01*
G37*
G36*
G01Y1129369D02*
X1540067Y1129512D01*
Y1130262D01*
X1540467Y1130405D01*
X1540667D01*
Y1129369D01*
X1540467D01*
G37*
G36*
G01X1540867Y1131580D02*
X1541267Y1131437D01*
Y1130687D01*
X1540867Y1130545D01*
X1540667D01*
Y1131580D01*
X1540867D01*
G37*
G36*
G01X1540467Y1134069D02*
X1540067Y1134212D01*
Y1134962D01*
X1540467Y1135105D01*
X1540667D01*
Y1134069D01*
X1540467D01*
G37*
G36*
G01X1540867Y1138630D02*
X1541267Y1138487D01*
Y1137737D01*
X1540867Y1137595D01*
X1540667D01*
Y1138630D01*
X1540867D01*
G37*
G36*
G01Y1136280D02*
X1541267Y1136137D01*
Y1135387D01*
X1540867Y1135245D01*
X1540667D01*
Y1136280D01*
X1540867D01*
G37*
G36*
G01X1540467Y1136419D02*
X1540067Y1136562D01*
Y1137312D01*
X1540467Y1137455D01*
X1540667D01*
Y1136419D01*
X1540467D01*
G37*
G36*
G01Y1138769D02*
X1540067Y1138912D01*
Y1139662D01*
X1540467Y1139805D01*
X1540667D01*
Y1138769D01*
X1540467D01*
G37*
G36*
G01X1526486Y1130004D02*
X1526886Y1129861D01*
Y1129111D01*
X1526486Y1128969D01*
X1526286D01*
Y1130004D01*
X1526486D01*
G37*
G36*
G01Y1132354D02*
X1526886Y1132211D01*
Y1131461D01*
X1526486Y1131319D01*
X1526286D01*
Y1132354D01*
X1526486D01*
G37*
G36*
G01Y1134704D02*
X1526886Y1134561D01*
Y1133811D01*
X1526486Y1133669D01*
X1526286D01*
Y1134704D01*
X1526486D01*
G37*
G36*
G01X1526086Y1132494D02*
X1525686Y1132637D01*
Y1133387D01*
X1526086Y1133529D01*
X1526286D01*
Y1132494D01*
X1526086D01*
G37*
G36*
G01Y1130144D02*
X1525686Y1130287D01*
Y1131037D01*
X1526086Y1131179D01*
X1526286D01*
Y1130144D01*
X1526086D01*
G37*
G36*
G01Y1144244D02*
X1525686Y1144387D01*
Y1145137D01*
X1526086Y1145279D01*
X1526286D01*
Y1144244D01*
X1526086D01*
G37*
G36*
G01X1526486Y1144104D02*
X1526886Y1143961D01*
Y1143211D01*
X1526486Y1143069D01*
X1526286D01*
Y1144104D01*
X1526486D01*
G37*
G36*
G01Y1141754D02*
X1526886Y1141611D01*
Y1140861D01*
X1526486Y1140719D01*
X1526286D01*
Y1141754D01*
X1526486D01*
G37*
G36*
G01X1526086Y1141894D02*
X1525686Y1142037D01*
Y1142787D01*
X1526086Y1142929D01*
X1526286D01*
Y1141894D01*
X1526086D01*
G37*
G36*
G01Y1134844D02*
X1525686Y1134987D01*
Y1135737D01*
X1526086Y1135879D01*
X1526286D01*
Y1134844D01*
X1526086D01*
G37*
G36*
G01X1526486Y1137054D02*
X1526886Y1136911D01*
Y1136161D01*
X1526486Y1136019D01*
X1526286D01*
Y1137054D01*
X1526486D01*
G37*
G36*
G01Y1139404D02*
X1526886Y1139261D01*
Y1138511D01*
X1526486Y1138369D01*
X1526286D01*
Y1139404D01*
X1526486D01*
G37*
G36*
G01X1526086Y1137194D02*
X1525686Y1137337D01*
Y1138087D01*
X1526086Y1138229D01*
X1526286D01*
Y1137194D01*
X1526086D01*
G37*
G36*
G01Y1139544D02*
X1525686Y1139687D01*
Y1140437D01*
X1526086Y1140579D01*
X1526286D01*
Y1139544D01*
X1526086D01*
G37*
G36*
G01X1527286Y1132494D02*
X1526886Y1132637D01*
Y1133387D01*
X1527286Y1133529D01*
X1527486D01*
Y1132494D01*
X1527286D01*
G37*
G36*
G01Y1130144D02*
X1526886Y1130287D01*
Y1131037D01*
X1527286Y1131179D01*
X1527486D01*
Y1130144D01*
X1527286D01*
G37*
G36*
G01Y1141894D02*
X1526886Y1142037D01*
Y1142787D01*
X1527286Y1142929D01*
X1527486D01*
Y1141894D01*
X1527286D01*
G37*
G36*
G01Y1144244D02*
X1526886Y1144387D01*
Y1145137D01*
X1527286Y1145279D01*
X1527486D01*
Y1144244D01*
X1527286D01*
G37*
G36*
G01Y1134844D02*
X1526886Y1134987D01*
Y1135737D01*
X1527286Y1135879D01*
X1527486D01*
Y1134844D01*
X1527286D01*
G37*
G36*
G01Y1137194D02*
X1526886Y1137337D01*
Y1138087D01*
X1527286Y1138229D01*
X1527486D01*
Y1137194D01*
X1527286D01*
G37*
G36*
G01Y1139544D02*
X1526886Y1139687D01*
Y1140437D01*
X1527286Y1140579D01*
X1527486D01*
Y1139544D01*
X1527286D01*
G37*
G36*
G01X1527686Y1130004D02*
X1528086Y1129861D01*
Y1129111D01*
X1527686Y1128969D01*
X1527486D01*
Y1130004D01*
X1527686D01*
G37*
G36*
G01Y1132354D02*
X1528086Y1132211D01*
Y1131461D01*
X1527686Y1131319D01*
X1527486D01*
Y1132354D01*
X1527686D01*
G37*
G36*
G01Y1134704D02*
X1528086Y1134561D01*
Y1133811D01*
X1527686Y1133669D01*
X1527486D01*
Y1134704D01*
X1527686D01*
G37*
G36*
G01Y1144104D02*
X1528086Y1143961D01*
Y1143211D01*
X1527686Y1143069D01*
X1527486D01*
Y1144104D01*
X1527686D01*
G37*
G36*
G01Y1141754D02*
X1528086Y1141611D01*
Y1140861D01*
X1527686Y1140719D01*
X1527486D01*
Y1141754D01*
X1527686D01*
G37*
G36*
G01Y1137054D02*
X1528086Y1136911D01*
Y1136161D01*
X1527686Y1136019D01*
X1527486D01*
Y1137054D01*
X1527686D01*
G37*
G36*
G01Y1139404D02*
X1528086Y1139261D01*
Y1138511D01*
X1527686Y1138369D01*
X1527486D01*
Y1139404D01*
X1527686D01*
G37*
G36*
G01X1533706Y1135009D02*
X1534106Y1134867D01*
Y1134117D01*
X1533706Y1133974D01*
X1533506D01*
Y1135009D01*
X1533706D01*
G37*
G36*
G01Y1132659D02*
X1534106Y1132517D01*
Y1131767D01*
X1533706Y1131624D01*
X1533506D01*
Y1132659D01*
X1533706D01*
G37*
G36*
G01Y1130309D02*
X1534106Y1130167D01*
Y1129417D01*
X1533706Y1129274D01*
X1533506D01*
Y1130309D01*
X1533706D01*
G37*
G36*
G01X1533306Y1132799D02*
X1532906Y1132942D01*
Y1133692D01*
X1533306Y1133834D01*
X1533506D01*
Y1132799D01*
X1533306D01*
G37*
G36*
G01Y1130449D02*
X1532906Y1130592D01*
Y1131342D01*
X1533306Y1131484D01*
X1533506D01*
Y1130449D01*
X1533306D01*
G37*
G36*
G01X1533706Y1144409D02*
X1534106Y1144267D01*
Y1143517D01*
X1533706Y1143374D01*
X1533506D01*
Y1144409D01*
X1533706D01*
G37*
G36*
G01Y1142059D02*
X1534106Y1141917D01*
Y1141167D01*
X1533706Y1141024D01*
X1533506D01*
Y1142059D01*
X1533706D01*
G37*
G36*
G01X1533306Y1142199D02*
X1532906Y1142342D01*
Y1143092D01*
X1533306Y1143234D01*
X1533506D01*
Y1142199D01*
X1533306D01*
G37*
G36*
G01X1533706Y1137359D02*
X1534106Y1137217D01*
Y1136467D01*
X1533706Y1136324D01*
X1533506D01*
Y1137359D01*
X1533706D01*
G37*
G36*
G01X1533306Y1137499D02*
X1532906Y1137642D01*
Y1138392D01*
X1533306Y1138534D01*
X1533506D01*
Y1137499D01*
X1533306D01*
G37*
G36*
G01Y1135149D02*
X1532906Y1135292D01*
Y1136042D01*
X1533306Y1136184D01*
X1533506D01*
Y1135149D01*
X1533306D01*
G37*
G36*
G01X1533706Y1139709D02*
X1534106Y1139567D01*
Y1138817D01*
X1533706Y1138674D01*
X1533506D01*
Y1139709D01*
X1533706D01*
G37*
G36*
G01X1533306Y1139849D02*
X1532906Y1139992D01*
Y1140742D01*
X1533306Y1140884D01*
X1533506D01*
Y1139849D01*
X1533306D01*
G37*
G36*
G01X1536106Y1135009D02*
X1536506Y1134867D01*
Y1134117D01*
X1536106Y1133974D01*
X1535906D01*
Y1135009D01*
X1536106D01*
G37*
G36*
G01Y1132659D02*
X1536506Y1132517D01*
Y1131767D01*
X1536106Y1131624D01*
X1535906D01*
Y1132659D01*
X1536106D01*
G37*
G36*
G01Y1130309D02*
X1536506Y1130167D01*
Y1129417D01*
X1536106Y1129274D01*
X1535906D01*
Y1130309D01*
X1536106D01*
G37*
G36*
G01X1535706Y1132799D02*
X1535306Y1132942D01*
Y1133692D01*
X1535706Y1133834D01*
X1535906D01*
Y1132799D01*
X1535706D01*
G37*
G36*
G01Y1130449D02*
X1535306Y1130592D01*
Y1131342D01*
X1535706Y1131484D01*
X1535906D01*
Y1130449D01*
X1535706D01*
G37*
G36*
G01X1536106Y1142059D02*
X1536506Y1141917D01*
Y1141167D01*
X1536106Y1141024D01*
X1535906D01*
Y1142059D01*
X1536106D01*
G37*
G36*
G01Y1137359D02*
X1536506Y1137217D01*
Y1136467D01*
X1536106Y1136324D01*
X1535906D01*
Y1137359D01*
X1536106D01*
G37*
G36*
G01X1535706Y1137499D02*
X1535306Y1137642D01*
Y1138392D01*
X1535706Y1138534D01*
X1535906D01*
Y1137499D01*
X1535706D01*
G37*
G36*
G01Y1135149D02*
X1535306Y1135292D01*
Y1136042D01*
X1535706Y1136184D01*
X1535906D01*
Y1135149D01*
X1535706D01*
G37*
G36*
G01X1536106Y1139709D02*
X1536506Y1139567D01*
Y1138817D01*
X1536106Y1138674D01*
X1535906D01*
Y1139709D01*
X1536106D01*
G37*
G36*
G01X1535706Y1139849D02*
X1535306Y1139992D01*
Y1140742D01*
X1535706Y1140884D01*
X1535906D01*
Y1139849D01*
X1535706D01*
G37*
G36*
G01X1534906Y1130309D02*
X1535306Y1130167D01*
Y1129417D01*
X1534906Y1129274D01*
X1534706D01*
Y1130309D01*
X1534906D01*
G37*
G36*
G01X1534506Y1132799D02*
X1534106Y1132942D01*
Y1133692D01*
X1534506Y1133834D01*
X1534706D01*
Y1132799D01*
X1534506D01*
G37*
G36*
G01Y1130449D02*
X1534106Y1130592D01*
Y1131342D01*
X1534506Y1131484D01*
X1534706D01*
Y1130449D01*
X1534506D01*
G37*
G36*
G01X1534906Y1135009D02*
X1535306Y1134867D01*
Y1134117D01*
X1534906Y1133974D01*
X1534706D01*
Y1135009D01*
X1534906D01*
G37*
G36*
G01Y1132659D02*
X1535306Y1132517D01*
Y1131767D01*
X1534906Y1131624D01*
X1534706D01*
Y1132659D01*
X1534906D01*
G37*
G36*
G01Y1142059D02*
X1535306Y1141917D01*
Y1141167D01*
X1534906Y1141024D01*
X1534706D01*
Y1142059D01*
X1534906D01*
G37*
G36*
G01X1534506Y1142199D02*
X1534106Y1142342D01*
Y1143092D01*
X1534506Y1143234D01*
X1534706D01*
Y1142199D01*
X1534506D01*
G37*
G36*
G01X1534906Y1137359D02*
X1535306Y1137217D01*
Y1136467D01*
X1534906Y1136324D01*
X1534706D01*
Y1137359D01*
X1534906D01*
G37*
G36*
G01X1534506Y1137499D02*
X1534106Y1137642D01*
Y1138392D01*
X1534506Y1138534D01*
X1534706D01*
Y1137499D01*
X1534506D01*
G37*
G36*
G01Y1135149D02*
X1534106Y1135292D01*
Y1136042D01*
X1534506Y1136184D01*
X1534706D01*
Y1135149D01*
X1534506D01*
G37*
G36*
G01X1534906Y1139709D02*
X1535306Y1139567D01*
Y1138817D01*
X1534906Y1138674D01*
X1534706D01*
Y1139709D01*
X1534906D01*
G37*
G36*
G01X1534506Y1139849D02*
X1534106Y1139992D01*
Y1140742D01*
X1534506Y1140884D01*
X1534706D01*
Y1139849D01*
X1534506D01*
G37*
G36*
G01X1536906Y1130449D02*
X1536506Y1130592D01*
Y1131342D01*
X1536906Y1131484D01*
X1537106D01*
Y1130449D01*
X1536906D01*
G37*
G36*
G01Y1132799D02*
X1536506Y1132942D01*
Y1133692D01*
X1536906Y1133834D01*
X1537106D01*
Y1132799D01*
X1536906D01*
G37*
G36*
G01X1537306Y1135009D02*
X1537706Y1134867D01*
Y1134117D01*
X1537306Y1133974D01*
X1537106D01*
Y1135009D01*
X1537306D01*
G37*
G36*
G01Y1132659D02*
X1537706Y1132517D01*
Y1131767D01*
X1537306Y1131624D01*
X1537106D01*
Y1132659D01*
X1537306D01*
G37*
G36*
G01Y1130309D02*
X1537706Y1130167D01*
Y1129417D01*
X1537306Y1129274D01*
X1537106D01*
Y1130309D01*
X1537306D01*
G37*
G36*
G01Y1142059D02*
X1537706Y1141917D01*
Y1141167D01*
X1537306Y1141024D01*
X1537106D01*
Y1142059D01*
X1537306D01*
G37*
G36*
G01X1536906Y1137499D02*
X1536506Y1137642D01*
Y1138392D01*
X1536906Y1138534D01*
X1537106D01*
Y1137499D01*
X1536906D01*
G37*
G36*
G01Y1135149D02*
X1536506Y1135292D01*
Y1136042D01*
X1536906Y1136184D01*
X1537106D01*
Y1135149D01*
X1536906D01*
G37*
G36*
G01X1537306Y1137359D02*
X1537706Y1137217D01*
Y1136467D01*
X1537306Y1136324D01*
X1537106D01*
Y1137359D01*
X1537306D01*
G37*
G36*
G01X1536906Y1139849D02*
X1536506Y1139992D01*
Y1140742D01*
X1536906Y1140884D01*
X1537106D01*
Y1139849D01*
X1536906D01*
G37*
G36*
G01X1537306Y1139709D02*
X1537706Y1139567D01*
Y1138817D01*
X1537306Y1138674D01*
X1537106D01*
Y1139709D01*
X1537306D01*
G37*
G36*
G01X1526486Y1151154D02*
X1526886Y1151011D01*
Y1150261D01*
X1526486Y1150119D01*
X1526286D01*
Y1151154D01*
X1526486D01*
G37*
G36*
G01X1526086Y1151294D02*
X1525686Y1151437D01*
Y1152187D01*
X1526086Y1152329D01*
X1526286D01*
Y1151294D01*
X1526086D01*
G37*
G36*
G01Y1148944D02*
X1525686Y1149087D01*
Y1149837D01*
X1526086Y1149979D01*
X1526286D01*
Y1148944D01*
X1526086D01*
G37*
G36*
G01X1526486Y1148804D02*
X1526886Y1148661D01*
Y1147911D01*
X1526486Y1147769D01*
X1526286D01*
Y1148804D01*
X1526486D01*
G37*
G36*
G01Y1146454D02*
X1526886Y1146311D01*
Y1145561D01*
X1526486Y1145419D01*
X1526286D01*
Y1146454D01*
X1526486D01*
G37*
G36*
G01X1526086Y1146594D02*
X1525686Y1146737D01*
Y1147487D01*
X1526086Y1147629D01*
X1526286D01*
Y1146594D01*
X1526086D01*
G37*
G36*
G01X1526486Y1160554D02*
X1526886Y1160411D01*
Y1159661D01*
X1526486Y1159519D01*
X1526286D01*
Y1160554D01*
X1526486D01*
G37*
G36*
G01Y1158204D02*
X1526886Y1158061D01*
Y1157311D01*
X1526486Y1157169D01*
X1526286D01*
Y1158204D01*
X1526486D01*
G37*
G36*
G01Y1155854D02*
X1526886Y1155711D01*
Y1154961D01*
X1526486Y1154819D01*
X1526286D01*
Y1155854D01*
X1526486D01*
G37*
G36*
G01Y1153504D02*
X1526886Y1153361D01*
Y1152611D01*
X1526486Y1152469D01*
X1526286D01*
Y1153504D01*
X1526486D01*
G37*
G36*
G01X1526086Y1160694D02*
X1525686Y1160837D01*
Y1161587D01*
X1526086Y1161729D01*
X1526286D01*
Y1160694D01*
X1526086D01*
G37*
G36*
G01Y1158344D02*
X1525686Y1158487D01*
Y1159237D01*
X1526086Y1159379D01*
X1526286D01*
Y1158344D01*
X1526086D01*
G37*
G36*
G01Y1155994D02*
X1525686Y1156137D01*
Y1156887D01*
X1526086Y1157029D01*
X1526286D01*
Y1155994D01*
X1526086D01*
G37*
G36*
G01Y1153644D02*
X1525686Y1153787D01*
Y1154537D01*
X1526086Y1154679D01*
X1526286D01*
Y1153644D01*
X1526086D01*
G37*
G36*
G01X1527286Y1146594D02*
X1526886Y1146737D01*
Y1147487D01*
X1527286Y1147629D01*
X1527486D01*
Y1146594D01*
X1527286D01*
G37*
G36*
G01Y1151294D02*
X1526886Y1151437D01*
Y1152187D01*
X1527286Y1152329D01*
X1527486D01*
Y1151294D01*
X1527286D01*
G37*
G36*
G01Y1148944D02*
X1526886Y1149087D01*
Y1149837D01*
X1527286Y1149979D01*
X1527486D01*
Y1148944D01*
X1527286D01*
G37*
G36*
G01X1527686Y1148804D02*
X1528086Y1148661D01*
Y1147911D01*
X1527686Y1147769D01*
X1527486D01*
Y1148804D01*
X1527686D01*
G37*
G36*
G01Y1146454D02*
X1528086Y1146311D01*
Y1145561D01*
X1527686Y1145419D01*
X1527486D01*
Y1146454D01*
X1527686D01*
G37*
G36*
G01Y1151154D02*
X1528086Y1151011D01*
Y1150261D01*
X1527686Y1150119D01*
X1527486D01*
Y1151154D01*
X1527686D01*
G37*
G36*
G01Y1160554D02*
X1528086Y1160411D01*
Y1159661D01*
X1527686Y1159519D01*
X1527486D01*
Y1160554D01*
X1527686D01*
G37*
G36*
G01X1527286Y1158344D02*
X1526886Y1158487D01*
Y1159237D01*
X1527286Y1159379D01*
X1527486D01*
Y1158344D01*
X1527286D01*
G37*
G36*
G01X1527686Y1158204D02*
X1528086Y1158061D01*
Y1157311D01*
X1527686Y1157169D01*
X1527486D01*
Y1158204D01*
X1527686D01*
G37*
G36*
G01X1527286Y1155994D02*
X1526886Y1156137D01*
Y1156887D01*
X1527286Y1157029D01*
X1527486D01*
Y1155994D01*
X1527286D01*
G37*
G36*
G01X1527686Y1155854D02*
X1528086Y1155711D01*
Y1154961D01*
X1527686Y1154819D01*
X1527486D01*
Y1155854D01*
X1527686D01*
G37*
G36*
G01X1527286Y1153644D02*
X1526886Y1153787D01*
Y1154537D01*
X1527286Y1154679D01*
X1527486D01*
Y1153644D01*
X1527286D01*
G37*
G36*
G01X1527686Y1153504D02*
X1528086Y1153361D01*
Y1152611D01*
X1527686Y1152469D01*
X1527486D01*
Y1153504D01*
X1527686D01*
G37*
G36*
G01X1527286Y1160694D02*
X1526886Y1160837D01*
Y1161587D01*
X1527286Y1161729D01*
X1527486D01*
Y1160694D01*
X1527286D01*
G37*
G36*
G01X1526086Y1163044D02*
X1525686Y1163187D01*
Y1163937D01*
X1526086Y1164079D01*
X1526286D01*
Y1163044D01*
X1526086D01*
G37*
G36*
G01X1526486Y1162904D02*
X1526886Y1162761D01*
Y1162011D01*
X1526486Y1161869D01*
X1526286D01*
Y1162904D01*
X1526486D01*
G37*
G36*
G01X1527686D02*
X1528086Y1162761D01*
Y1162011D01*
X1527686Y1161869D01*
X1527486D01*
Y1162904D01*
X1527686D01*
G37*
G36*
G01X1527286Y1163044D02*
X1526886Y1163187D01*
Y1163937D01*
X1527286Y1164079D01*
X1527486D01*
Y1163044D01*
X1527286D01*
G37*
G36*
G01X1534597Y1575592D02*
G03I-720J0D01*
G37*
G36*
G01X1539553D02*
G03I-720J0D01*
G37*
G36*
G01X1534597Y1580678D02*
G03I-720J0D01*
G37*
G36*
G01X1539553D02*
G03I-720J0D01*
G37*
G36*
G01X1527493D02*
G03I-720J0D01*
G37*
G36*
G01Y1575686D02*
G03I-720J0D01*
G37*
G36*
G01X1539897Y1599790D02*
G03I-720J0D01*
G37*
G36*
G01X1527837Y1599884D02*
G03I-720J0D01*
G37*
G36*
G01X1532793D02*
G03I-720J0D01*
G37*
G36*
G01X1534597Y1587598D02*
G03I-720J0D01*
G37*
G36*
G01X1539553D02*
G03I-720J0D01*
G37*
G36*
G01X1534597Y1592590D02*
G03I-720J0D01*
G37*
G36*
G01X1539553D02*
G03I-720J0D01*
G37*
G36*
G01X1527493D02*
G03I-720J0D01*
G37*
G36*
G01Y1587598D02*
G03I-720J0D01*
G37*
G36*
G01X1539897Y1611796D02*
G03I-720J0D01*
G37*
G36*
G01Y1604876D02*
G03I-720J0D01*
G37*
G36*
G01Y1616788D02*
G03I-720J0D01*
G37*
G36*
G01X1527837D02*
G03I-720J0D01*
G37*
G36*
G01Y1604876D02*
G03I-720J0D01*
G37*
G36*
G01Y1611796D02*
G03I-720J0D01*
G37*
G36*
G01X1532793Y1616788D02*
G03I-720J0D01*
G37*
G36*
G01Y1604876D02*
G03I-720J0D01*
G37*
G36*
G01Y1611796D02*
G03I-720J0D01*
G37*
G36*
G01X1556355Y16999D02*
G03I-720J0D01*
G37*
G36*
G01Y21991D02*
G03I-720J0D01*
G37*
G36*
G01X1554355Y19495D02*
G03I-720J0D01*
G37*
G36*
G01X1554206Y23935D02*
G03I-720J0D01*
G37*
G36*
G01X1549250D02*
G03I-720J0D01*
G37*
G36*
G01X1547250Y25931D02*
G03I-720J0D01*
G37*
G36*
G01X1556206D02*
G03I-720J0D01*
G37*
G36*
G01X1555538Y69297D02*
G03I-720J0D01*
G37*
G36*
G01X1557538Y66801D02*
G03I-720J0D01*
G37*
G36*
G01Y71793D02*
G03I-720J0D01*
G37*
G36*
G01X1544538Y75297D02*
G03I-720J0D01*
G37*
G36*
G01X1553494D02*
G03I-720J0D01*
G37*
G36*
G01X1551494Y77793D02*
G03I-720J0D01*
G37*
G36*
G01Y72801D02*
G03I-720J0D01*
G37*
G36*
G01X1546538Y77793D02*
G03I-720J0D01*
G37*
G36*
G01Y72801D02*
G03I-720J0D01*
G37*
G36*
G01X1556684Y204474D02*
X1565767D01*
X1565784Y204471D01*
G03X1566004Y204452I218J1237D01*
G01X1570096D01*
X1570398Y204150D01*
Y203556D01*
X1570047Y203205D01*
X1563352D01*
X1563298Y203259D01*
X1561651D01*
X1560625Y202233D01*
X1556981D01*
X1556198Y203016D01*
Y203988D01*
X1556684Y204474D01*
G37*
G36*
G01X1542570Y848264D02*
X1542170Y848407D01*
Y849157D01*
X1542570Y849299D01*
X1542770D01*
Y848264D01*
X1542570D01*
G37*
G36*
G01Y850614D02*
X1542170Y850757D01*
Y851507D01*
X1542570Y851649D01*
X1542770D01*
Y850614D01*
X1542570D01*
G37*
G36*
G01X1542970Y850474D02*
X1543370Y850331D01*
Y849581D01*
X1542970Y849439D01*
X1542770D01*
Y850474D01*
X1542970D01*
G37*
G36*
G01X1543770Y850614D02*
X1543370Y850757D01*
Y851507D01*
X1543770Y851649D01*
X1543970D01*
Y850614D01*
X1543770D01*
G37*
G36*
G01X1552170Y866781D02*
X1551770Y866923D01*
Y867673D01*
X1552170Y867816D01*
X1552370D01*
Y866781D01*
X1552170D01*
G37*
G36*
G01X1552570Y868991D02*
X1552970Y868848D01*
Y868098D01*
X1552570Y867956D01*
X1552370D01*
Y868991D01*
X1552570D01*
G37*
G36*
G01X1553370Y866781D02*
X1552970Y866923D01*
Y867673D01*
X1553370Y867816D01*
X1553570D01*
Y866781D01*
X1553370D01*
G37*
G36*
G01X1553770Y868991D02*
X1554170Y868848D01*
Y868098D01*
X1553770Y867956D01*
X1553570D01*
Y868991D01*
X1553770D01*
G37*
G36*
G01X1551370D02*
X1551770Y868848D01*
Y868098D01*
X1551370Y867956D01*
X1551170D01*
Y868991D01*
X1551370D01*
G37*
G36*
G01Y866641D02*
X1551770Y866498D01*
Y865748D01*
X1551370Y865606D01*
X1551170D01*
Y866641D01*
X1551370D01*
G37*
G36*
G01X1550970Y864431D02*
X1550570Y864573D01*
Y865323D01*
X1550970Y865466D01*
X1551170D01*
Y864431D01*
X1550970D01*
G37*
G36*
G01Y866781D02*
X1550570Y866923D01*
Y867673D01*
X1550970Y867816D01*
X1551170D01*
Y866781D01*
X1550970D01*
G37*
G36*
G01X1544970Y855314D02*
X1544570Y855457D01*
Y856207D01*
X1544970Y856349D01*
X1545170D01*
Y855314D01*
X1544970D01*
G37*
G36*
G01Y857664D02*
X1544570Y857807D01*
Y858557D01*
X1544970Y858699D01*
X1545170D01*
Y857664D01*
X1544970D01*
G37*
G36*
G01Y860014D02*
X1544570Y860157D01*
Y860907D01*
X1544970Y861049D01*
X1545170D01*
Y860014D01*
X1544970D01*
G37*
G36*
G01Y852964D02*
X1544570Y853107D01*
Y853857D01*
X1544970Y853999D01*
X1545170D01*
Y852964D01*
X1544970D01*
G37*
G36*
G01Y867064D02*
X1544570Y867207D01*
Y867957D01*
X1544970Y868099D01*
X1545170D01*
Y867064D01*
X1544970D01*
G37*
G36*
G01Y862364D02*
X1544570Y862507D01*
Y863257D01*
X1544970Y863399D01*
X1545170D01*
Y862364D01*
X1544970D01*
G37*
G36*
G01Y864714D02*
X1544570Y864857D01*
Y865607D01*
X1544970Y865749D01*
X1545170D01*
Y864714D01*
X1544970D01*
G37*
G36*
G01X1545370Y855174D02*
X1545770Y855031D01*
Y854281D01*
X1545370Y854139D01*
X1545170D01*
Y855174D01*
X1545370D01*
G37*
G36*
G01Y857524D02*
X1545770Y857381D01*
Y856631D01*
X1545370Y856489D01*
X1545170D01*
Y857524D01*
X1545370D01*
G37*
G36*
G01Y859874D02*
X1545770Y859731D01*
Y858981D01*
X1545370Y858839D01*
X1545170D01*
Y859874D01*
X1545370D01*
G37*
G36*
G01Y862224D02*
X1545770Y862081D01*
Y861331D01*
X1545370Y861189D01*
X1545170D01*
Y862224D01*
X1545370D01*
G37*
G36*
G01Y852824D02*
X1545770Y852681D01*
Y851931D01*
X1545370Y851789D01*
X1545170D01*
Y852824D01*
X1545370D01*
G37*
G36*
G01Y864574D02*
X1545770Y864431D01*
Y863681D01*
X1545370Y863539D01*
X1545170D01*
Y864574D01*
X1545370D01*
G37*
G36*
G01Y866924D02*
X1545770Y866781D01*
Y866031D01*
X1545370Y865889D01*
X1545170D01*
Y866924D01*
X1545370D01*
G37*
G36*
G01X1542570Y864714D02*
X1542170Y864857D01*
Y865607D01*
X1542570Y865749D01*
X1542770D01*
Y864714D01*
X1542570D01*
G37*
G36*
G01Y862364D02*
X1542170Y862507D01*
Y863257D01*
X1542570Y863399D01*
X1542770D01*
Y862364D01*
X1542570D01*
G37*
G36*
G01Y867064D02*
X1542170Y867207D01*
Y867957D01*
X1542570Y868099D01*
X1542770D01*
Y867064D01*
X1542570D01*
G37*
G36*
G01X1542970Y866924D02*
X1543370Y866781D01*
Y866031D01*
X1542970Y865889D01*
X1542770D01*
Y866924D01*
X1542970D01*
G37*
G36*
G01Y864574D02*
X1543370Y864431D01*
Y863681D01*
X1542970Y863539D01*
X1542770D01*
Y864574D01*
X1542970D01*
G37*
G36*
G01X1542570Y852964D02*
X1542170Y853107D01*
Y853857D01*
X1542570Y853999D01*
X1542770D01*
Y852964D01*
X1542570D01*
G37*
G36*
G01Y860014D02*
X1542170Y860157D01*
Y860907D01*
X1542570Y861049D01*
X1542770D01*
Y860014D01*
X1542570D01*
G37*
G36*
G01Y857664D02*
X1542170Y857807D01*
Y858557D01*
X1542570Y858699D01*
X1542770D01*
Y857664D01*
X1542570D01*
G37*
G36*
G01Y855314D02*
X1542170Y855457D01*
Y856207D01*
X1542570Y856349D01*
X1542770D01*
Y855314D01*
X1542570D01*
G37*
G36*
G01X1542970Y852824D02*
X1543370Y852681D01*
Y851931D01*
X1542970Y851789D01*
X1542770D01*
Y852824D01*
X1542970D01*
G37*
G36*
G01Y862224D02*
X1543370Y862081D01*
Y861331D01*
X1542970Y861189D01*
X1542770D01*
Y862224D01*
X1542970D01*
G37*
G36*
G01Y859874D02*
X1543370Y859731D01*
Y858981D01*
X1542970Y858839D01*
X1542770D01*
Y859874D01*
X1542970D01*
G37*
G36*
G01Y857524D02*
X1543370Y857381D01*
Y856631D01*
X1542970Y856489D01*
X1542770D01*
Y857524D01*
X1542970D01*
G37*
G36*
G01Y855174D02*
X1543370Y855031D01*
Y854281D01*
X1542970Y854139D01*
X1542770D01*
Y855174D01*
X1542970D01*
G37*
G36*
G01X1543770Y855314D02*
X1543370Y855457D01*
Y856207D01*
X1543770Y856349D01*
X1543970D01*
Y855314D01*
X1543770D01*
G37*
G36*
G01Y857664D02*
X1543370Y857807D01*
Y858557D01*
X1543770Y858699D01*
X1543970D01*
Y857664D01*
X1543770D01*
G37*
G36*
G01Y860014D02*
X1543370Y860157D01*
Y860907D01*
X1543770Y861049D01*
X1543970D01*
Y860014D01*
X1543770D01*
G37*
G36*
G01X1544170Y855174D02*
X1544570Y855031D01*
Y854281D01*
X1544170Y854139D01*
X1543970D01*
Y855174D01*
X1544170D01*
G37*
G36*
G01Y857524D02*
X1544570Y857381D01*
Y856631D01*
X1544170Y856489D01*
X1543970D01*
Y857524D01*
X1544170D01*
G37*
G36*
G01Y859874D02*
X1544570Y859731D01*
Y858981D01*
X1544170Y858839D01*
X1543970D01*
Y859874D01*
X1544170D01*
G37*
G36*
G01Y862224D02*
X1544570Y862081D01*
Y861331D01*
X1544170Y861189D01*
X1543970D01*
Y862224D01*
X1544170D01*
G37*
G36*
G01X1543770Y852964D02*
X1543370Y853107D01*
Y853857D01*
X1543770Y853999D01*
X1543970D01*
Y852964D01*
X1543770D01*
G37*
G36*
G01X1544170Y852824D02*
X1544570Y852681D01*
Y851931D01*
X1544170Y851789D01*
X1543970D01*
Y852824D01*
X1544170D01*
G37*
G36*
G01X1543770Y867064D02*
X1543370Y867207D01*
Y867957D01*
X1543770Y868099D01*
X1543970D01*
Y867064D01*
X1543770D01*
G37*
G36*
G01Y862364D02*
X1543370Y862507D01*
Y863257D01*
X1543770Y863399D01*
X1543970D01*
Y862364D01*
X1543770D01*
G37*
G36*
G01Y864714D02*
X1543370Y864857D01*
Y865607D01*
X1543770Y865749D01*
X1543970D01*
Y864714D01*
X1543770D01*
G37*
G36*
G01X1544170Y864574D02*
X1544570Y864431D01*
Y863681D01*
X1544170Y863539D01*
X1543970D01*
Y864574D01*
X1544170D01*
G37*
G36*
G01Y866924D02*
X1544570Y866781D01*
Y866031D01*
X1544170Y865889D01*
X1543970D01*
Y866924D01*
X1544170D01*
G37*
G36*
G01X1554570Y883231D02*
X1554170Y883373D01*
Y884123D01*
X1554570Y884266D01*
X1554770D01*
Y883231D01*
X1554570D01*
G37*
G36*
G01X1554970Y880741D02*
X1555370Y880598D01*
Y879848D01*
X1554970Y879706D01*
X1554770D01*
Y880741D01*
X1554970D01*
G37*
G36*
G01Y883091D02*
X1555370Y882948D01*
Y882198D01*
X1554970Y882056D01*
X1554770D01*
Y883091D01*
X1554970D01*
G37*
G36*
G01X1554570Y873831D02*
X1554170Y873973D01*
Y874723D01*
X1554570Y874866D01*
X1554770D01*
Y873831D01*
X1554570D01*
G37*
G36*
G01Y876181D02*
X1554170Y876323D01*
Y877073D01*
X1554570Y877216D01*
X1554770D01*
Y876181D01*
X1554570D01*
G37*
G36*
G01X1554970Y873691D02*
X1555370Y873548D01*
Y872798D01*
X1554970Y872656D01*
X1554770D01*
Y873691D01*
X1554970D01*
G37*
G36*
G01Y876041D02*
X1555370Y875898D01*
Y875148D01*
X1554970Y875006D01*
X1554770D01*
Y876041D01*
X1554970D01*
G37*
G36*
G01Y878391D02*
X1555370Y878248D01*
Y877498D01*
X1554970Y877356D01*
X1554770D01*
Y878391D01*
X1554970D01*
G37*
G36*
G01X1554570Y871481D02*
X1554170Y871623D01*
Y872373D01*
X1554570Y872516D01*
X1554770D01*
Y871481D01*
X1554570D01*
G37*
G36*
G01Y878531D02*
X1554170Y878673D01*
Y879423D01*
X1554570Y879566D01*
X1554770D01*
Y878531D01*
X1554570D01*
G37*
G36*
G01Y880881D02*
X1554170Y881023D01*
Y881773D01*
X1554570Y881916D01*
X1554770D01*
Y880881D01*
X1554570D01*
G37*
G36*
G01X1552170D02*
X1551770Y881023D01*
Y881773D01*
X1552170Y881916D01*
X1552370D01*
Y880881D01*
X1552170D01*
G37*
G36*
G01Y883231D02*
X1551770Y883373D01*
Y884123D01*
X1552170Y884266D01*
X1552370D01*
Y883231D01*
X1552170D01*
G37*
G36*
G01Y869131D02*
X1551770Y869273D01*
Y870023D01*
X1552170Y870166D01*
X1552370D01*
Y869131D01*
X1552170D01*
G37*
G36*
G01X1552570Y871341D02*
X1552970Y871198D01*
Y870448D01*
X1552570Y870306D01*
X1552370D01*
Y871341D01*
X1552570D01*
G37*
G36*
G01X1552170Y871481D02*
X1551770Y871623D01*
Y872373D01*
X1552170Y872516D01*
X1552370D01*
Y871481D01*
X1552170D01*
G37*
G36*
G01X1552570Y876041D02*
X1552970Y875898D01*
Y875148D01*
X1552570Y875006D01*
X1552370D01*
Y876041D01*
X1552570D01*
G37*
G36*
G01Y873691D02*
X1552970Y873548D01*
Y872798D01*
X1552570Y872656D01*
X1552370D01*
Y873691D01*
X1552570D01*
G37*
G36*
G01X1552170Y876181D02*
X1551770Y876323D01*
Y877073D01*
X1552170Y877216D01*
X1552370D01*
Y876181D01*
X1552170D01*
G37*
G36*
G01Y873831D02*
X1551770Y873973D01*
Y874723D01*
X1552170Y874866D01*
X1552370D01*
Y873831D01*
X1552170D01*
G37*
G36*
G01X1552570Y878391D02*
X1552970Y878248D01*
Y877498D01*
X1552570Y877356D01*
X1552370D01*
Y878391D01*
X1552570D01*
G37*
G36*
G01Y880741D02*
X1552970Y880598D01*
Y879848D01*
X1552570Y879706D01*
X1552370D01*
Y880741D01*
X1552570D01*
G37*
G36*
G01Y883091D02*
X1552970Y882948D01*
Y882198D01*
X1552570Y882056D01*
X1552370D01*
Y883091D01*
X1552570D01*
G37*
G36*
G01X1552170Y878531D02*
X1551770Y878673D01*
Y879423D01*
X1552170Y879566D01*
X1552370D01*
Y878531D01*
X1552170D01*
G37*
G36*
G01X1553370Y883231D02*
X1552970Y883373D01*
Y884123D01*
X1553370Y884266D01*
X1553570D01*
Y883231D01*
X1553370D01*
G37*
G36*
G01X1553770Y883091D02*
X1554170Y882948D01*
Y882198D01*
X1553770Y882056D01*
X1553570D01*
Y883091D01*
X1553770D01*
G37*
G36*
G01X1553370Y873831D02*
X1552970Y873973D01*
Y874723D01*
X1553370Y874866D01*
X1553570D01*
Y873831D01*
X1553370D01*
G37*
G36*
G01Y876181D02*
X1552970Y876323D01*
Y877073D01*
X1553370Y877216D01*
X1553570D01*
Y876181D01*
X1553370D01*
G37*
G36*
G01X1553770Y873691D02*
X1554170Y873548D01*
Y872798D01*
X1553770Y872656D01*
X1553570D01*
Y873691D01*
X1553770D01*
G37*
G36*
G01Y876041D02*
X1554170Y875898D01*
Y875148D01*
X1553770Y875006D01*
X1553570D01*
Y876041D01*
X1553770D01*
G37*
G36*
G01X1553370Y871481D02*
X1552970Y871623D01*
Y872373D01*
X1553370Y872516D01*
X1553570D01*
Y871481D01*
X1553370D01*
G37*
G36*
G01X1553770Y871341D02*
X1554170Y871198D01*
Y870448D01*
X1553770Y870306D01*
X1553570D01*
Y871341D01*
X1553770D01*
G37*
G36*
G01X1553370Y869131D02*
X1552970Y869273D01*
Y870023D01*
X1553370Y870166D01*
X1553570D01*
Y869131D01*
X1553370D01*
G37*
G36*
G01Y878531D02*
X1552970Y878673D01*
Y879423D01*
X1553370Y879566D01*
X1553570D01*
Y878531D01*
X1553370D01*
G37*
G36*
G01Y880881D02*
X1552970Y881023D01*
Y881773D01*
X1553370Y881916D01*
X1553570D01*
Y880881D01*
X1553370D01*
G37*
G36*
G01X1553770Y878391D02*
X1554170Y878248D01*
Y877498D01*
X1553770Y877356D01*
X1553570D01*
Y878391D01*
X1553770D01*
G37*
G36*
G01Y880741D02*
X1554170Y880598D01*
Y879848D01*
X1553770Y879706D01*
X1553570D01*
Y880741D01*
X1553770D01*
G37*
G36*
G01X1550970Y883231D02*
X1550570Y883373D01*
Y884123D01*
X1550970Y884266D01*
X1551170D01*
Y883231D01*
X1550970D01*
G37*
G36*
G01X1551370Y873691D02*
X1551770Y873548D01*
Y872798D01*
X1551370Y872656D01*
X1551170D01*
Y873691D01*
X1551370D01*
G37*
G36*
G01Y876041D02*
X1551770Y875898D01*
Y875148D01*
X1551370Y875006D01*
X1551170D01*
Y876041D01*
X1551370D01*
G37*
G36*
G01X1550970Y873831D02*
X1550570Y873973D01*
Y874723D01*
X1550970Y874866D01*
X1551170D01*
Y873831D01*
X1550970D01*
G37*
G36*
G01Y876181D02*
X1550570Y876323D01*
Y877073D01*
X1550970Y877216D01*
X1551170D01*
Y876181D01*
X1550970D01*
G37*
G36*
G01Y871481D02*
X1550570Y871623D01*
Y872373D01*
X1550970Y872516D01*
X1551170D01*
Y871481D01*
X1550970D01*
G37*
G36*
G01X1551370Y871341D02*
X1551770Y871198D01*
Y870448D01*
X1551370Y870306D01*
X1551170D01*
Y871341D01*
X1551370D01*
G37*
G36*
G01X1550970Y869131D02*
X1550570Y869273D01*
Y870023D01*
X1550970Y870166D01*
X1551170D01*
Y869131D01*
X1550970D01*
G37*
G36*
G01X1551370Y878391D02*
X1551770Y878248D01*
Y877498D01*
X1551370Y877356D01*
X1551170D01*
Y878391D01*
X1551370D01*
G37*
G36*
G01Y880741D02*
X1551770Y880598D01*
Y879848D01*
X1551370Y879706D01*
X1551170D01*
Y880741D01*
X1551370D01*
G37*
G36*
G01Y883091D02*
X1551770Y882948D01*
Y882198D01*
X1551370Y882056D01*
X1551170D01*
Y883091D01*
X1551370D01*
G37*
G36*
G01X1550970Y878531D02*
X1550570Y878673D01*
Y879423D01*
X1550970Y879566D01*
X1551170D01*
Y878531D01*
X1550970D01*
G37*
G36*
G01Y880881D02*
X1550570Y881023D01*
Y881773D01*
X1550970Y881916D01*
X1551170D01*
Y880881D01*
X1550970D01*
G37*
G36*
G01X1544970Y883514D02*
X1544570Y883657D01*
Y884407D01*
X1544970Y884549D01*
X1545170D01*
Y883514D01*
X1544970D01*
G37*
G36*
G01X1545370Y883374D02*
X1545770Y883231D01*
Y882481D01*
X1545370Y882339D01*
X1545170D01*
Y883374D01*
X1545370D01*
G37*
G36*
G01X1544970Y869414D02*
X1544570Y869557D01*
Y870307D01*
X1544970Y870449D01*
X1545170D01*
Y869414D01*
X1544970D01*
G37*
G36*
G01Y871764D02*
X1544570Y871907D01*
Y872657D01*
X1544970Y872799D01*
X1545170D01*
Y871764D01*
X1544970D01*
G37*
G36*
G01Y876464D02*
X1544570Y876607D01*
Y877357D01*
X1544970Y877499D01*
X1545170D01*
Y876464D01*
X1544970D01*
G37*
G36*
G01Y874114D02*
X1544570Y874257D01*
Y875007D01*
X1544970Y875149D01*
X1545170D01*
Y874114D01*
X1544970D01*
G37*
G36*
G01Y881164D02*
X1544570Y881307D01*
Y882057D01*
X1544970Y882199D01*
X1545170D01*
Y881164D01*
X1544970D01*
G37*
G36*
G01Y878814D02*
X1544570Y878957D01*
Y879707D01*
X1544970Y879849D01*
X1545170D01*
Y878814D01*
X1544970D01*
G37*
G36*
G01X1545370Y869274D02*
X1545770Y869131D01*
Y868381D01*
X1545370Y868239D01*
X1545170D01*
Y869274D01*
X1545370D01*
G37*
G36*
G01Y871624D02*
X1545770Y871481D01*
Y870731D01*
X1545370Y870589D01*
X1545170D01*
Y871624D01*
X1545370D01*
G37*
G36*
G01Y876324D02*
X1545770Y876181D01*
Y875431D01*
X1545370Y875289D01*
X1545170D01*
Y876324D01*
X1545370D01*
G37*
G36*
G01Y873974D02*
X1545770Y873831D01*
Y873081D01*
X1545370Y872939D01*
X1545170D01*
Y873974D01*
X1545370D01*
G37*
G36*
G01Y881024D02*
X1545770Y880881D01*
Y880131D01*
X1545370Y879989D01*
X1545170D01*
Y881024D01*
X1545370D01*
G37*
G36*
G01Y878674D02*
X1545770Y878531D01*
Y877781D01*
X1545370Y877639D01*
X1545170D01*
Y878674D01*
X1545370D01*
G37*
G36*
G01X1542970Y869274D02*
X1543370Y869131D01*
Y868381D01*
X1542970Y868239D01*
X1542770D01*
Y869274D01*
X1542970D01*
G37*
G36*
G01X1542570Y878814D02*
X1542170Y878957D01*
Y879707D01*
X1542570Y879849D01*
X1542770D01*
Y878814D01*
X1542570D01*
G37*
G36*
G01Y881164D02*
X1542170Y881307D01*
Y882057D01*
X1542570Y882199D01*
X1542770D01*
Y881164D01*
X1542570D01*
G37*
G36*
G01Y883514D02*
X1542170Y883657D01*
Y884407D01*
X1542570Y884549D01*
X1542770D01*
Y883514D01*
X1542570D01*
G37*
G36*
G01X1542970Y878674D02*
X1543370Y878531D01*
Y877781D01*
X1542970Y877639D01*
X1542770D01*
Y878674D01*
X1542970D01*
G37*
G36*
G01Y881024D02*
X1543370Y880881D01*
Y880131D01*
X1542970Y879989D01*
X1542770D01*
Y881024D01*
X1542970D01*
G37*
G36*
G01Y883374D02*
X1543370Y883231D01*
Y882481D01*
X1542970Y882339D01*
X1542770D01*
Y883374D01*
X1542970D01*
G37*
G36*
G01X1542570Y871764D02*
X1542170Y871907D01*
Y872657D01*
X1542570Y872799D01*
X1542770D01*
Y871764D01*
X1542570D01*
G37*
G36*
G01Y874114D02*
X1542170Y874257D01*
Y875007D01*
X1542570Y875149D01*
X1542770D01*
Y874114D01*
X1542570D01*
G37*
G36*
G01Y876464D02*
X1542170Y876607D01*
Y877357D01*
X1542570Y877499D01*
X1542770D01*
Y876464D01*
X1542570D01*
G37*
G36*
G01X1542970Y873974D02*
X1543370Y873831D01*
Y873081D01*
X1542970Y872939D01*
X1542770D01*
Y873974D01*
X1542970D01*
G37*
G36*
G01Y876324D02*
X1543370Y876181D01*
Y875431D01*
X1542970Y875289D01*
X1542770D01*
Y876324D01*
X1542970D01*
G37*
G36*
G01X1542570Y869414D02*
X1542170Y869557D01*
Y870307D01*
X1542570Y870449D01*
X1542770D01*
Y869414D01*
X1542570D01*
G37*
G36*
G01X1542970Y871624D02*
X1543370Y871481D01*
Y870731D01*
X1542970Y870589D01*
X1542770D01*
Y871624D01*
X1542970D01*
G37*
G36*
G01X1543770Y883514D02*
X1543370Y883657D01*
Y884407D01*
X1543770Y884549D01*
X1543970D01*
Y883514D01*
X1543770D01*
G37*
G36*
G01X1544170Y883374D02*
X1544570Y883231D01*
Y882481D01*
X1544170Y882339D01*
X1543970D01*
Y883374D01*
X1544170D01*
G37*
G36*
G01Y873974D02*
X1544570Y873831D01*
Y873081D01*
X1544170Y872939D01*
X1543970D01*
Y873974D01*
X1544170D01*
G37*
G36*
G01X1543770Y881164D02*
X1543370Y881307D01*
Y882057D01*
X1543770Y882199D01*
X1543970D01*
Y881164D01*
X1543770D01*
G37*
G36*
G01Y878814D02*
X1543370Y878957D01*
Y879707D01*
X1543770Y879849D01*
X1543970D01*
Y878814D01*
X1543770D01*
G37*
G36*
G01X1544170Y881024D02*
X1544570Y880881D01*
Y880131D01*
X1544170Y879989D01*
X1543970D01*
Y881024D01*
X1544170D01*
G37*
G36*
G01Y878674D02*
X1544570Y878531D01*
Y877781D01*
X1544170Y877639D01*
X1543970D01*
Y878674D01*
X1544170D01*
G37*
G36*
G01Y869274D02*
X1544570Y869131D01*
Y868381D01*
X1544170Y868239D01*
X1543970D01*
Y869274D01*
X1544170D01*
G37*
G36*
G01Y871624D02*
X1544570Y871481D01*
Y870731D01*
X1544170Y870589D01*
X1543970D01*
Y871624D01*
X1544170D01*
G37*
G36*
G01X1543770Y869414D02*
X1543370Y869557D01*
Y870307D01*
X1543770Y870449D01*
X1543970D01*
Y869414D01*
X1543770D01*
G37*
G36*
G01Y876464D02*
X1543370Y876607D01*
Y877357D01*
X1543770Y877499D01*
X1543970D01*
Y876464D01*
X1543770D01*
G37*
G36*
G01Y874114D02*
X1543370Y874257D01*
Y875007D01*
X1543770Y875149D01*
X1543970D01*
Y874114D01*
X1543770D01*
G37*
G36*
G01Y871764D02*
X1543370Y871907D01*
Y872657D01*
X1543770Y872799D01*
X1543970D01*
Y871764D01*
X1543770D01*
G37*
G36*
G01X1544170Y876324D02*
X1544570Y876181D01*
Y875431D01*
X1544170Y875289D01*
X1543970D01*
Y876324D01*
X1544170D01*
G37*
G36*
G01X1557970Y895962D02*
X1557570Y896105D01*
Y896855D01*
X1557970Y896997D01*
X1558170D01*
Y895962D01*
X1557970D01*
G37*
G36*
G01Y893612D02*
X1557570Y893755D01*
Y894505D01*
X1557970Y894647D01*
X1558170D01*
Y893612D01*
X1557970D01*
G37*
G36*
G01Y898312D02*
X1557570Y898455D01*
Y899205D01*
X1557970Y899347D01*
X1558170D01*
Y898312D01*
X1557970D01*
G37*
G36*
G01Y891262D02*
X1557570Y891405D01*
Y892155D01*
X1557970Y892297D01*
X1558170D01*
Y891262D01*
X1557970D01*
G37*
G36*
G01X1556770Y898312D02*
X1556370Y898455D01*
Y899205D01*
X1556770Y899347D01*
X1556970D01*
Y898312D01*
X1556770D01*
G37*
G36*
G01X1557170Y900522D02*
X1557570Y900379D01*
Y899629D01*
X1557170Y899487D01*
X1556970D01*
Y900522D01*
X1557170D01*
G37*
G36*
G01Y898172D02*
X1557570Y898029D01*
Y897279D01*
X1557170Y897137D01*
X1556970D01*
Y898172D01*
X1557170D01*
G37*
G36*
G01Y895822D02*
X1557570Y895679D01*
Y894929D01*
X1557170Y894787D01*
X1556970D01*
Y895822D01*
X1557170D01*
G37*
G36*
G01Y893472D02*
X1557570Y893329D01*
Y892579D01*
X1557170Y892437D01*
X1556970D01*
Y893472D01*
X1557170D01*
G37*
G36*
G01X1556770Y895962D02*
X1556370Y896105D01*
Y896855D01*
X1556770Y896997D01*
X1556970D01*
Y895962D01*
X1556770D01*
G37*
G36*
G01Y893612D02*
X1556370Y893755D01*
Y894505D01*
X1556770Y894647D01*
X1556970D01*
Y893612D01*
X1556770D01*
G37*
G36*
G01Y891262D02*
X1556370Y891405D01*
Y892155D01*
X1556770Y892297D01*
X1556970D01*
Y891262D01*
X1556770D01*
G37*
G36*
G01X1554970Y885441D02*
X1555370Y885298D01*
Y884548D01*
X1554970Y884406D01*
X1554770D01*
Y885441D01*
X1554970D01*
G37*
G36*
G01Y899541D02*
X1555370Y899398D01*
Y898648D01*
X1554970Y898506D01*
X1554770D01*
Y899541D01*
X1554970D01*
G37*
G36*
G01X1554570Y899681D02*
X1554170Y899823D01*
Y900573D01*
X1554570Y900716D01*
X1554770D01*
Y899681D01*
X1554570D01*
G37*
G36*
G01Y897331D02*
X1554170Y897473D01*
Y898223D01*
X1554570Y898366D01*
X1554770D01*
Y897331D01*
X1554570D01*
G37*
G36*
G01Y894981D02*
X1554170Y895123D01*
Y895873D01*
X1554570Y896016D01*
X1554770D01*
Y894981D01*
X1554570D01*
G37*
G36*
G01Y892631D02*
X1554170Y892773D01*
Y893523D01*
X1554570Y893666D01*
X1554770D01*
Y892631D01*
X1554570D01*
G37*
G36*
G01X1554970Y897191D02*
X1555370Y897048D01*
Y896298D01*
X1554970Y896156D01*
X1554770D01*
Y897191D01*
X1554970D01*
G37*
G36*
G01Y894841D02*
X1555370Y894698D01*
Y893948D01*
X1554970Y893806D01*
X1554770D01*
Y894841D01*
X1554970D01*
G37*
G36*
G01Y887791D02*
X1555370Y887648D01*
Y886898D01*
X1554970Y886756D01*
X1554770D01*
Y887791D01*
X1554970D01*
G37*
G36*
G01X1554570Y885581D02*
X1554170Y885723D01*
Y886473D01*
X1554570Y886616D01*
X1554770D01*
Y885581D01*
X1554570D01*
G37*
G36*
G01Y890281D02*
X1554170Y890423D01*
Y891173D01*
X1554570Y891316D01*
X1554770D01*
Y890281D01*
X1554570D01*
G37*
G36*
G01Y887931D02*
X1554170Y888073D01*
Y888823D01*
X1554570Y888966D01*
X1554770D01*
Y887931D01*
X1554570D01*
G37*
G36*
G01X1554970Y892491D02*
X1555370Y892348D01*
Y891598D01*
X1554970Y891456D01*
X1554770D01*
Y892491D01*
X1554970D01*
G37*
G36*
G01Y890141D02*
X1555370Y889998D01*
Y889248D01*
X1554970Y889106D01*
X1554770D01*
Y890141D01*
X1554970D01*
G37*
G36*
G01X1552570Y885441D02*
X1552970Y885298D01*
Y884548D01*
X1552570Y884406D01*
X1552370D01*
Y885441D01*
X1552570D01*
G37*
G36*
G01X1552170Y887931D02*
X1551770Y888073D01*
Y888823D01*
X1552170Y888966D01*
X1552370D01*
Y887931D01*
X1552170D01*
G37*
G36*
G01Y890281D02*
X1551770Y890423D01*
Y891173D01*
X1552170Y891316D01*
X1552370D01*
Y890281D01*
X1552170D01*
G37*
G36*
G01Y885581D02*
X1551770Y885723D01*
Y886473D01*
X1552170Y886616D01*
X1552370D01*
Y885581D01*
X1552170D01*
G37*
G36*
G01X1552570Y887791D02*
X1552970Y887648D01*
Y886898D01*
X1552570Y886756D01*
X1552370D01*
Y887791D01*
X1552570D01*
G37*
G36*
G01Y890141D02*
X1552970Y889998D01*
Y889248D01*
X1552570Y889106D01*
X1552370D01*
Y890141D01*
X1552570D01*
G37*
G36*
G01Y892491D02*
X1552970Y892348D01*
Y891598D01*
X1552570Y891456D01*
X1552370D01*
Y892491D01*
X1552570D01*
G37*
G36*
G01Y894841D02*
X1552970Y894698D01*
Y893948D01*
X1552570Y893806D01*
X1552370D01*
Y894841D01*
X1552570D01*
G37*
G36*
G01Y897191D02*
X1552970Y897048D01*
Y896298D01*
X1552570Y896156D01*
X1552370D01*
Y897191D01*
X1552570D01*
G37*
G36*
G01X1552170Y892631D02*
X1551770Y892773D01*
Y893523D01*
X1552170Y893666D01*
X1552370D01*
Y892631D01*
X1552170D01*
G37*
G36*
G01Y894981D02*
X1551770Y895123D01*
Y895873D01*
X1552170Y896016D01*
X1552370D01*
Y894981D01*
X1552170D01*
G37*
G36*
G01Y897331D02*
X1551770Y897473D01*
Y898223D01*
X1552170Y898366D01*
X1552370D01*
Y897331D01*
X1552170D01*
G37*
G36*
G01X1552570Y899541D02*
X1552970Y899398D01*
Y898648D01*
X1552570Y898506D01*
X1552370D01*
Y899541D01*
X1552570D01*
G37*
G36*
G01X1553770Y885441D02*
X1554170Y885298D01*
Y884548D01*
X1553770Y884406D01*
X1553570D01*
Y885441D01*
X1553770D01*
G37*
G36*
G01Y899541D02*
X1554170Y899398D01*
Y898648D01*
X1553770Y898506D01*
X1553570D01*
Y899541D01*
X1553770D01*
G37*
G36*
G01X1553370Y897331D02*
X1552970Y897473D01*
Y898223D01*
X1553370Y898366D01*
X1553570D01*
Y897331D01*
X1553370D01*
G37*
G36*
G01Y894981D02*
X1552970Y895123D01*
Y895873D01*
X1553370Y896016D01*
X1553570D01*
Y894981D01*
X1553370D01*
G37*
G36*
G01Y892631D02*
X1552970Y892773D01*
Y893523D01*
X1553370Y893666D01*
X1553570D01*
Y892631D01*
X1553370D01*
G37*
G36*
G01X1553770Y897191D02*
X1554170Y897048D01*
Y896298D01*
X1553770Y896156D01*
X1553570D01*
Y897191D01*
X1553770D01*
G37*
G36*
G01Y894841D02*
X1554170Y894698D01*
Y893948D01*
X1553770Y893806D01*
X1553570D01*
Y894841D01*
X1553770D01*
G37*
G36*
G01Y887791D02*
X1554170Y887648D01*
Y886898D01*
X1553770Y886756D01*
X1553570D01*
Y887791D01*
X1553770D01*
G37*
G36*
G01X1553370Y885581D02*
X1552970Y885723D01*
Y886473D01*
X1553370Y886616D01*
X1553570D01*
Y885581D01*
X1553370D01*
G37*
G36*
G01Y890281D02*
X1552970Y890423D01*
Y891173D01*
X1553370Y891316D01*
X1553570D01*
Y890281D01*
X1553370D01*
G37*
G36*
G01Y887931D02*
X1552970Y888073D01*
Y888823D01*
X1553370Y888966D01*
X1553570D01*
Y887931D01*
X1553370D01*
G37*
G36*
G01X1553770Y892491D02*
X1554170Y892348D01*
Y891598D01*
X1553770Y891456D01*
X1553570D01*
Y892491D01*
X1553770D01*
G37*
G36*
G01Y890141D02*
X1554170Y889998D01*
Y889248D01*
X1553770Y889106D01*
X1553570D01*
Y890141D01*
X1553770D01*
G37*
G36*
G01X1551370Y885441D02*
X1551770Y885298D01*
Y884548D01*
X1551370Y884406D01*
X1551170D01*
Y885441D01*
X1551370D01*
G37*
G36*
G01Y899541D02*
X1551770Y899398D01*
Y898648D01*
X1551370Y898506D01*
X1551170D01*
Y899541D01*
X1551370D01*
G37*
G36*
G01Y897191D02*
X1551770Y897048D01*
Y896298D01*
X1551370Y896156D01*
X1551170D01*
Y897191D01*
X1551370D01*
G37*
G36*
G01Y894841D02*
X1551770Y894698D01*
Y893948D01*
X1551370Y893806D01*
X1551170D01*
Y894841D01*
X1551370D01*
G37*
G36*
G01X1550970Y892631D02*
X1550570Y892773D01*
Y893523D01*
X1550970Y893666D01*
X1551170D01*
Y892631D01*
X1550970D01*
G37*
G36*
G01Y897331D02*
X1550570Y897473D01*
Y898223D01*
X1550970Y898366D01*
X1551170D01*
Y897331D01*
X1550970D01*
G37*
G36*
G01Y894981D02*
X1550570Y895123D01*
Y895873D01*
X1550970Y896016D01*
X1551170D01*
Y894981D01*
X1550970D01*
G37*
G36*
G01X1551370Y887791D02*
X1551770Y887648D01*
Y886898D01*
X1551370Y886756D01*
X1551170D01*
Y887791D01*
X1551370D01*
G37*
G36*
G01X1550970Y885581D02*
X1550570Y885723D01*
Y886473D01*
X1550970Y886616D01*
X1551170D01*
Y885581D01*
X1550970D01*
G37*
G36*
G01X1551370Y892491D02*
X1551770Y892348D01*
Y891598D01*
X1551370Y891456D01*
X1551170D01*
Y892491D01*
X1551370D01*
G37*
G36*
G01Y890141D02*
X1551770Y889998D01*
Y889248D01*
X1551370Y889106D01*
X1551170D01*
Y890141D01*
X1551370D01*
G37*
G36*
G01X1550970Y890281D02*
X1550570Y890423D01*
Y891173D01*
X1550970Y891316D01*
X1551170D01*
Y890281D01*
X1550970D01*
G37*
G36*
G01Y887931D02*
X1550570Y888073D01*
Y888823D01*
X1550970Y888966D01*
X1551170D01*
Y887931D01*
X1550970D01*
G37*
G36*
G01X1545370Y885724D02*
X1545770Y885581D01*
Y884831D01*
X1545370Y884689D01*
X1545170D01*
Y885724D01*
X1545370D01*
G37*
G36*
G01X1544970Y895264D02*
X1544570Y895407D01*
Y896157D01*
X1544970Y896299D01*
X1545170D01*
Y895264D01*
X1544970D01*
G37*
G36*
G01Y892914D02*
X1544570Y893057D01*
Y893807D01*
X1544970Y893949D01*
X1545170D01*
Y892914D01*
X1544970D01*
G37*
G36*
G01X1545370Y892774D02*
X1545770Y892631D01*
Y891881D01*
X1545370Y891739D01*
X1545170D01*
Y892774D01*
X1545370D01*
G37*
G36*
G01Y895124D02*
X1545770Y894981D01*
Y894231D01*
X1545370Y894089D01*
X1545170D01*
Y895124D01*
X1545370D01*
G37*
G36*
G01X1544970Y885864D02*
X1544570Y886007D01*
Y886757D01*
X1544970Y886899D01*
X1545170D01*
Y885864D01*
X1544970D01*
G37*
G36*
G01Y890564D02*
X1544570Y890707D01*
Y891457D01*
X1544970Y891599D01*
X1545170D01*
Y890564D01*
X1544970D01*
G37*
G36*
G01Y888214D02*
X1544570Y888357D01*
Y889107D01*
X1544970Y889249D01*
X1545170D01*
Y888214D01*
X1544970D01*
G37*
G36*
G01X1545370Y888074D02*
X1545770Y887931D01*
Y887181D01*
X1545370Y887039D01*
X1545170D01*
Y888074D01*
X1545370D01*
G37*
G36*
G01Y890424D02*
X1545770Y890281D01*
Y889531D01*
X1545370Y889389D01*
X1545170D01*
Y890424D01*
X1545370D01*
G37*
G36*
G01X1544240Y898261D02*
X1543856Y898079D01*
X1543326Y898610D01*
X1543508Y898993D01*
X1543649Y899135D01*
X1544381Y898403D01*
X1544240Y898261D01*
G37*
G36*
G01X1542960Y900107D02*
X1543344Y900289D01*
X1543874Y899759D01*
X1543692Y899375D01*
X1543550Y899234D01*
X1542818Y899966D01*
X1542960Y900107D01*
G37*
G36*
G01X1542970Y885724D02*
X1543370Y885581D01*
Y884831D01*
X1542970Y884689D01*
X1542770D01*
Y885724D01*
X1542970D01*
G37*
G36*
G01X1542570Y888214D02*
X1542170Y888357D01*
Y889107D01*
X1542570Y889249D01*
X1542770D01*
Y888214D01*
X1542570D01*
G37*
G36*
G01Y890564D02*
X1542170Y890707D01*
Y891457D01*
X1542570Y891599D01*
X1542770D01*
Y890564D01*
X1542570D01*
G37*
G36*
G01Y885864D02*
X1542170Y886007D01*
Y886757D01*
X1542570Y886899D01*
X1542770D01*
Y885864D01*
X1542570D01*
G37*
G36*
G01X1542970Y890424D02*
X1543370Y890281D01*
Y889531D01*
X1542970Y889389D01*
X1542770D01*
Y890424D01*
X1542970D01*
G37*
G36*
G01Y888074D02*
X1543370Y887931D01*
Y887181D01*
X1542970Y887039D01*
X1542770D01*
Y888074D01*
X1542970D01*
G37*
G36*
G01Y895124D02*
X1543370Y894981D01*
Y894231D01*
X1542970Y894089D01*
X1542770D01*
Y895124D01*
X1542970D01*
G37*
G36*
G01X1542570Y892914D02*
X1542170Y893057D01*
Y893807D01*
X1542570Y893949D01*
X1542770D01*
Y892914D01*
X1542570D01*
G37*
G36*
G01X1542970Y892774D02*
X1543370Y892631D01*
Y891881D01*
X1542970Y891739D01*
X1542770D01*
Y892774D01*
X1542970D01*
G37*
G36*
G01X1544170Y885724D02*
X1544570Y885581D01*
Y884831D01*
X1544170Y884689D01*
X1543970D01*
Y885724D01*
X1544170D01*
G37*
G36*
G01X1543770Y892914D02*
X1543370Y893057D01*
Y893807D01*
X1543770Y893949D01*
X1543970D01*
Y892914D01*
X1543770D01*
G37*
G36*
G01X1544170Y892774D02*
X1544570Y892631D01*
Y891881D01*
X1544170Y891739D01*
X1543970D01*
Y892774D01*
X1544170D01*
G37*
G36*
G01X1543770Y895264D02*
X1543370Y895407D01*
Y896157D01*
X1543770Y896299D01*
X1543970D01*
Y895264D01*
X1543770D01*
G37*
G36*
G01X1544170Y895124D02*
X1544570Y894981D01*
Y894231D01*
X1544170Y894089D01*
X1543970D01*
Y895124D01*
X1544170D01*
G37*
G36*
G01X1543770Y885864D02*
X1543370Y886007D01*
Y886757D01*
X1543770Y886899D01*
X1543970D01*
Y885864D01*
X1543770D01*
G37*
G36*
G01X1544170Y888074D02*
X1544570Y887931D01*
Y887181D01*
X1544170Y887039D01*
X1543970D01*
Y888074D01*
X1544170D01*
G37*
G36*
G01X1543770Y890564D02*
X1543370Y890707D01*
Y891457D01*
X1543770Y891599D01*
X1543970D01*
Y890564D01*
X1543770D01*
G37*
G36*
G01Y888214D02*
X1543370Y888357D01*
Y889107D01*
X1543770Y889249D01*
X1543970D01*
Y888214D01*
X1543770D01*
G37*
G36*
G01X1544170Y890424D02*
X1544570Y890281D01*
Y889531D01*
X1544170Y889389D01*
X1543970D01*
Y890424D01*
X1544170D01*
G37*
G36*
G01X1542111Y899258D02*
X1542495Y899440D01*
X1543025Y898910D01*
X1542843Y898526D01*
X1542701Y898385D01*
X1541969Y899117D01*
X1542111Y899258D01*
G37*
G36*
G01X1543391Y897412D02*
X1543007Y897230D01*
X1542477Y897761D01*
X1542659Y898144D01*
X1542800Y898286D01*
X1543532Y897554D01*
X1543391Y897412D01*
G37*
G36*
G01X1557808Y915183D02*
X1557424Y915001D01*
X1556894Y915531D01*
X1557076Y915915D01*
X1557217Y916056D01*
X1557949Y915325D01*
X1557808Y915183D01*
G37*
G36*
G01X1556528Y917029D02*
X1556912Y917211D01*
X1557442Y916681D01*
X1557260Y916297D01*
X1557119Y916156D01*
X1556387Y916887D01*
X1556528Y917029D01*
G37*
G36*
G01X1556146Y916845D02*
X1555763Y916663D01*
X1555232Y917193D01*
X1555414Y917577D01*
X1555556Y917718D01*
X1556288Y916986D01*
X1556146Y916845D01*
G37*
G36*
G01X1548971Y916096D02*
X1549354Y916278D01*
X1549885Y915748D01*
X1549703Y915364D01*
X1549561Y915223D01*
X1548829Y915955D01*
X1548971Y916096D01*
G37*
G36*
G01X1548589Y915912D02*
X1548205Y915730D01*
X1547675Y916261D01*
X1547857Y916644D01*
X1547998Y916786D01*
X1548730Y916054D01*
X1548589Y915912D01*
G37*
G36*
G01X1551912Y912589D02*
X1551529Y912407D01*
X1550998Y912937D01*
X1551180Y913321D01*
X1551322Y913462D01*
X1552054Y912730D01*
X1551912Y912589D01*
G37*
G36*
G01X1550251Y914251D02*
X1549867Y914069D01*
X1549337Y914599D01*
X1549519Y914982D01*
X1549660Y915124D01*
X1550392Y914392D01*
X1550251Y914251D01*
G37*
G36*
G01X1550632Y914434D02*
X1551016Y914617D01*
X1551546Y914086D01*
X1551364Y913703D01*
X1551223Y913561D01*
X1550491Y914293D01*
X1550632Y914434D01*
G37*
G36*
G01X1558559Y905942D02*
X1558175Y905760D01*
X1557645Y906290D01*
X1557827Y906674D01*
X1557969Y906815D01*
X1558700Y906084D01*
X1558559Y905942D01*
G37*
G36*
G01X1556897Y907604D02*
X1556514Y907422D01*
X1555983Y907952D01*
X1556166Y908336D01*
X1556307Y908477D01*
X1557039Y907745D01*
X1556897Y907604D01*
G37*
G36*
G01X1555236Y909265D02*
X1554852Y909083D01*
X1554322Y909614D01*
X1554504Y909997D01*
X1554645Y910139D01*
X1555377Y909407D01*
X1555236Y909265D01*
G37*
G36*
G01X1557279Y907788D02*
X1557663Y907970D01*
X1558193Y907439D01*
X1558011Y907056D01*
X1557870Y906914D01*
X1557138Y907646D01*
X1557279Y907788D01*
G37*
G36*
G01X1555617Y909449D02*
X1556001Y909631D01*
X1556531Y909101D01*
X1556349Y908717D01*
X1556208Y908576D01*
X1555476Y909308D01*
X1555617Y909449D01*
G37*
G36*
G01X1553956Y911111D02*
X1554339Y911293D01*
X1554870Y910763D01*
X1554688Y910379D01*
X1554546Y910238D01*
X1553814Y910970D01*
X1553956Y911111D01*
G37*
G36*
G01X1553574Y910927D02*
X1553190Y910745D01*
X1552660Y911275D01*
X1552842Y911659D01*
X1552984Y911800D01*
X1553715Y911069D01*
X1553574Y910927D01*
G37*
G36*
G01X1552294Y912773D02*
X1552678Y912955D01*
X1553208Y912424D01*
X1553026Y912041D01*
X1552885Y911899D01*
X1552153Y912631D01*
X1552294Y912773D01*
G37*
G36*
G01X1545229Y915876D02*
X1544846Y915694D01*
X1544315Y916224D01*
X1544497Y916608D01*
X1544639Y916749D01*
X1545371Y916017D01*
X1545229Y915876D01*
G37*
G36*
G01X1545611Y916060D02*
X1545995Y916242D01*
X1546525Y915712D01*
X1546343Y915328D01*
X1546201Y915187D01*
X1545470Y915918D01*
X1545611Y916060D01*
G37*
G36*
G01X1546891Y914214D02*
X1546507Y914032D01*
X1545977Y914563D01*
X1546159Y914946D01*
X1546300Y915088D01*
X1547032Y914356D01*
X1546891Y914214D01*
G37*
G36*
G01X1547273Y914398D02*
X1547656Y914580D01*
X1548187Y914050D01*
X1548005Y913666D01*
X1547863Y913525D01*
X1547131Y914257D01*
X1547273Y914398D01*
G37*
G36*
G01X1548553Y912553D02*
X1548169Y912371D01*
X1547639Y912901D01*
X1547821Y913284D01*
X1547962Y913426D01*
X1548694Y912694D01*
X1548553Y912553D01*
G37*
G36*
G01X1548934Y912736D02*
X1549318Y912919D01*
X1549848Y912388D01*
X1549666Y912005D01*
X1549525Y911863D01*
X1548793Y912595D01*
X1548934Y912736D01*
G37*
G36*
G01X1550214Y910891D02*
X1549831Y910709D01*
X1549300Y911239D01*
X1549482Y911623D01*
X1549624Y911764D01*
X1550356Y911032D01*
X1550214Y910891D01*
G37*
G36*
G01X1550596Y911075D02*
X1550980Y911257D01*
X1551510Y910726D01*
X1551328Y910343D01*
X1551187Y910201D01*
X1550455Y910933D01*
X1550596Y911075D01*
G37*
G36*
G01X1551876Y909229D02*
X1551492Y909047D01*
X1550962Y909577D01*
X1551144Y909961D01*
X1551286Y910102D01*
X1552017Y909371D01*
X1551876Y909229D01*
G37*
G36*
G01X1557970Y900662D02*
X1557570Y900805D01*
Y901555D01*
X1557970Y901697D01*
X1558170D01*
Y900662D01*
X1557970D01*
G37*
G36*
G01X1552258Y909413D02*
X1552641Y909595D01*
X1553172Y909065D01*
X1552990Y908681D01*
X1552848Y908540D01*
X1552116Y909272D01*
X1552258Y909413D01*
G37*
G36*
G01X1553538Y907567D02*
X1553154Y907385D01*
X1552624Y907916D01*
X1552806Y908299D01*
X1552947Y908441D01*
X1553679Y907709D01*
X1553538Y907567D01*
G37*
G36*
G01X1553919Y907751D02*
X1554303Y907933D01*
X1554833Y907403D01*
X1554651Y907019D01*
X1554510Y906878D01*
X1553778Y907610D01*
X1553919Y907751D01*
G37*
G36*
G01X1555199Y905906D02*
X1554816Y905724D01*
X1554285Y906254D01*
X1554468Y906638D01*
X1554609Y906779D01*
X1555341Y906047D01*
X1555199Y905906D01*
G37*
G36*
G01X1555581Y906090D02*
X1555965Y906272D01*
X1556495Y905741D01*
X1556313Y905358D01*
X1556172Y905216D01*
X1555440Y905948D01*
X1555581Y906090D01*
G37*
G36*
G01X1556861Y904244D02*
X1556477Y904062D01*
X1555947Y904592D01*
X1556129Y904976D01*
X1556271Y905117D01*
X1557002Y904386D01*
X1556861Y904244D01*
G37*
G36*
G01X1546078Y916725D02*
X1545695Y916543D01*
X1545164Y917073D01*
X1545346Y917457D01*
X1545488Y917598D01*
X1546220Y916866D01*
X1546078Y916725D01*
G37*
G36*
G01X1546460Y916909D02*
X1546844Y917091D01*
X1547374Y916561D01*
X1547192Y916177D01*
X1547050Y916036D01*
X1546319Y916767D01*
X1546460Y916909D01*
G37*
G36*
G01X1551445Y911924D02*
X1551829Y912106D01*
X1552359Y911575D01*
X1552177Y911192D01*
X1552036Y911050D01*
X1551304Y911782D01*
X1551445Y911924D01*
G37*
G36*
G01X1549783Y913585D02*
X1550167Y913768D01*
X1550697Y913237D01*
X1550515Y912854D01*
X1550374Y912712D01*
X1549642Y913444D01*
X1549783Y913585D01*
G37*
G36*
G01X1548122Y915247D02*
X1548505Y915429D01*
X1549036Y914899D01*
X1548854Y914515D01*
X1548712Y914374D01*
X1547980Y915106D01*
X1548122Y915247D01*
G37*
G36*
G01X1551063Y911740D02*
X1550680Y911558D01*
X1550149Y912088D01*
X1550331Y912472D01*
X1550473Y912613D01*
X1551205Y911881D01*
X1551063Y911740D01*
G37*
G36*
G01X1549402Y913402D02*
X1549018Y913220D01*
X1548488Y913750D01*
X1548670Y914133D01*
X1548811Y914275D01*
X1549543Y913543D01*
X1549402Y913402D01*
G37*
G36*
G01X1547740Y915063D02*
X1547356Y914881D01*
X1546826Y915412D01*
X1547008Y915795D01*
X1547149Y915937D01*
X1547881Y915205D01*
X1547740Y915063D01*
G37*
G36*
G01X1558092Y905277D02*
X1558476Y905459D01*
X1559006Y904929D01*
X1558824Y904545D01*
X1558682Y904404D01*
X1557950Y905136D01*
X1558092Y905277D01*
G37*
G36*
G01X1557710Y905093D02*
X1557326Y904911D01*
X1556796Y905441D01*
X1556978Y905825D01*
X1557120Y905966D01*
X1557851Y905235D01*
X1557710Y905093D01*
G37*
G36*
G01X1556430Y906939D02*
X1556814Y907121D01*
X1557344Y906590D01*
X1557162Y906207D01*
X1557021Y906065D01*
X1556289Y906797D01*
X1556430Y906939D01*
G37*
G36*
G01X1554768Y908600D02*
X1555152Y908782D01*
X1555682Y908252D01*
X1555500Y907868D01*
X1555359Y907727D01*
X1554627Y908459D01*
X1554768Y908600D01*
G37*
G36*
G01X1556048Y906755D02*
X1555665Y906573D01*
X1555134Y907103D01*
X1555317Y907487D01*
X1555458Y907628D01*
X1556190Y906896D01*
X1556048Y906755D01*
G37*
G36*
G01X1554387Y908416D02*
X1554003Y908234D01*
X1553473Y908765D01*
X1553655Y909148D01*
X1553796Y909290D01*
X1554528Y908558D01*
X1554387Y908416D01*
G37*
G36*
G01X1553107Y910262D02*
X1553490Y910444D01*
X1554021Y909914D01*
X1553839Y909530D01*
X1553697Y909389D01*
X1552965Y910121D01*
X1553107Y910262D01*
G37*
G36*
G01X1552725Y910078D02*
X1552341Y909896D01*
X1551811Y910426D01*
X1551993Y910810D01*
X1552135Y910951D01*
X1552866Y910220D01*
X1552725Y910078D01*
G37*
G36*
G01X1543100Y916873D02*
X1543484Y917055D01*
X1544014Y916524D01*
X1543832Y916141D01*
X1543691Y915999D01*
X1542959Y916731D01*
X1543100Y916873D01*
G37*
G36*
G01X1544380Y915027D02*
X1543997Y914845D01*
X1543466Y915375D01*
X1543648Y915759D01*
X1543790Y915900D01*
X1544522Y915168D01*
X1544380Y915027D01*
G37*
G36*
G01X1542718Y916689D02*
X1542335Y916507D01*
X1541805Y917037D01*
X1541987Y917421D01*
X1542128Y917562D01*
X1542860Y916830D01*
X1542718Y916689D01*
G37*
G36*
G01X1544762Y915211D02*
X1545146Y915393D01*
X1545676Y914863D01*
X1545494Y914479D01*
X1545352Y914338D01*
X1544621Y915069D01*
X1544762Y915211D01*
G37*
G36*
G01X1551409Y908564D02*
X1551792Y908746D01*
X1552323Y908216D01*
X1552141Y907832D01*
X1551999Y907691D01*
X1551267Y908423D01*
X1551409Y908564D01*
G37*
G36*
G01X1549747Y910226D02*
X1550131Y910408D01*
X1550661Y909877D01*
X1550479Y909494D01*
X1550338Y909352D01*
X1549606Y910084D01*
X1549747Y910226D01*
G37*
G36*
G01X1551027Y908380D02*
X1550643Y908198D01*
X1550113Y908728D01*
X1550295Y909112D01*
X1550437Y909253D01*
X1551168Y908522D01*
X1551027Y908380D01*
G37*
G36*
G01X1549365Y910042D02*
X1548982Y909860D01*
X1548451Y910390D01*
X1548633Y910774D01*
X1548775Y910915D01*
X1549507Y910183D01*
X1549365Y910042D01*
G37*
G36*
G01X1548085Y911887D02*
X1548469Y912070D01*
X1548999Y911539D01*
X1548817Y911156D01*
X1548676Y911014D01*
X1547944Y911746D01*
X1548085Y911887D01*
G37*
G36*
G01X1546424Y913549D02*
X1546807Y913731D01*
X1547338Y913201D01*
X1547156Y912817D01*
X1547014Y912676D01*
X1546282Y913408D01*
X1546424Y913549D01*
G37*
G36*
G01X1547704Y911704D02*
X1547320Y911522D01*
X1546790Y912052D01*
X1546972Y912435D01*
X1547113Y912577D01*
X1547845Y911845D01*
X1547704Y911704D01*
G37*
G36*
G01X1546042Y913365D02*
X1545658Y913183D01*
X1545128Y913714D01*
X1545310Y914097D01*
X1545451Y914239D01*
X1546183Y913507D01*
X1546042Y913365D01*
G37*
G36*
G01X1556770Y900662D02*
X1556370Y900805D01*
Y901555D01*
X1556770Y901697D01*
X1556970D01*
Y900662D01*
X1556770D01*
G37*
G36*
G01X1556012Y903395D02*
X1555628Y903213D01*
X1555098Y903743D01*
X1555280Y904127D01*
X1555422Y904268D01*
X1556153Y903537D01*
X1556012Y903395D01*
G37*
G36*
G01X1554732Y905241D02*
X1555116Y905423D01*
X1555646Y904892D01*
X1555464Y904509D01*
X1555323Y904367D01*
X1554591Y905099D01*
X1554732Y905241D01*
G37*
G36*
G01X1554350Y905057D02*
X1553967Y904875D01*
X1553436Y905405D01*
X1553619Y905789D01*
X1553760Y905930D01*
X1554492Y905198D01*
X1554350Y905057D01*
G37*
G36*
G01X1553070Y906902D02*
X1553454Y907084D01*
X1553984Y906554D01*
X1553802Y906170D01*
X1553661Y906029D01*
X1552929Y906761D01*
X1553070Y906902D01*
G37*
G36*
G01X1552689Y906718D02*
X1552305Y906536D01*
X1551775Y907067D01*
X1551957Y907450D01*
X1552098Y907592D01*
X1552830Y906860D01*
X1552689Y906718D01*
G37*
G36*
G01X1544382Y911705D02*
X1543998Y911523D01*
X1543468Y912054D01*
X1543650Y912437D01*
X1543791Y912579D01*
X1544523Y911847D01*
X1544382Y911705D01*
G37*
G36*
G01X1543102Y913551D02*
X1543486Y913733D01*
X1544016Y913203D01*
X1543834Y912819D01*
X1543692Y912678D01*
X1542961Y913409D01*
X1543102Y913551D01*
G37*
G36*
G01X1542720Y913367D02*
X1542337Y913185D01*
X1541806Y913715D01*
X1541988Y914099D01*
X1542130Y914240D01*
X1542862Y913508D01*
X1542720Y913367D01*
G37*
G36*
G01X1551410Y905242D02*
X1551794Y905424D01*
X1552324Y904894D01*
X1552142Y904510D01*
X1552001Y904369D01*
X1551269Y905101D01*
X1551410Y905242D01*
G37*
G36*
G01X1551029Y905058D02*
X1550645Y904876D01*
X1550115Y905407D01*
X1550297Y905790D01*
X1550438Y905932D01*
X1551170Y905200D01*
X1551029Y905058D01*
G37*
G36*
G01X1544764Y911889D02*
X1545147Y912071D01*
X1545678Y911541D01*
X1545496Y911157D01*
X1545354Y911016D01*
X1544622Y911748D01*
X1544764Y911889D01*
G37*
G36*
G01X1546425Y910227D02*
X1546809Y910410D01*
X1547339Y909879D01*
X1547157Y909496D01*
X1547016Y909354D01*
X1546284Y910086D01*
X1546425Y910227D01*
G37*
G36*
G01X1546044Y910044D02*
X1545660Y909862D01*
X1545130Y910392D01*
X1545312Y910775D01*
X1545453Y910917D01*
X1546185Y910185D01*
X1546044Y910044D01*
G37*
G36*
G01X1549749Y906904D02*
X1550132Y907086D01*
X1550663Y906556D01*
X1550481Y906172D01*
X1550339Y906031D01*
X1549607Y906763D01*
X1549749Y906904D01*
G37*
G36*
G01X1547705Y908382D02*
X1547322Y908200D01*
X1546791Y908730D01*
X1546973Y909114D01*
X1547115Y909255D01*
X1547847Y908523D01*
X1547705Y908382D01*
G37*
G36*
G01X1548087Y908566D02*
X1548471Y908748D01*
X1549001Y908217D01*
X1548819Y907834D01*
X1548678Y907692D01*
X1547946Y908424D01*
X1548087Y908566D01*
G37*
G36*
G01X1549367Y906720D02*
X1548983Y906538D01*
X1548453Y907068D01*
X1548635Y907452D01*
X1548777Y907593D01*
X1549508Y906862D01*
X1549367Y906720D01*
G37*
G36*
G01X1553072Y903581D02*
X1553456Y903763D01*
X1553986Y903232D01*
X1553804Y902849D01*
X1553663Y902707D01*
X1552931Y903439D01*
X1553072Y903581D01*
G37*
G36*
G01X1552690Y903397D02*
X1552307Y903215D01*
X1551776Y903745D01*
X1551959Y904129D01*
X1552100Y904270D01*
X1552832Y903538D01*
X1552690Y903397D01*
G37*
G36*
G01X1551374Y901883D02*
X1551758Y902065D01*
X1552288Y901534D01*
X1552106Y901151D01*
X1551965Y901009D01*
X1551233Y901741D01*
X1551374Y901883D01*
G37*
G36*
G01X1542684Y910007D02*
X1542300Y909825D01*
X1541770Y910356D01*
X1541952Y910739D01*
X1542093Y910881D01*
X1542825Y910149D01*
X1542684Y910007D01*
G37*
G36*
G01X1543066Y910191D02*
X1543449Y910373D01*
X1543980Y909843D01*
X1543798Y909459D01*
X1543656Y909318D01*
X1542924Y910050D01*
X1543066Y910191D01*
G37*
G36*
G01X1544346Y908346D02*
X1543962Y908164D01*
X1543432Y908694D01*
X1543614Y909077D01*
X1543755Y909219D01*
X1544487Y908487D01*
X1544346Y908346D01*
G37*
G36*
G01X1546007Y906684D02*
X1545624Y906502D01*
X1545093Y907032D01*
X1545275Y907416D01*
X1545417Y907557D01*
X1546149Y906825D01*
X1546007Y906684D01*
G37*
G36*
G01X1544727Y908529D02*
X1545111Y908712D01*
X1545641Y908181D01*
X1545459Y907798D01*
X1545318Y907656D01*
X1544586Y908388D01*
X1544727Y908529D01*
G37*
G36*
G01X1546389Y906868D02*
X1546773Y907050D01*
X1547303Y906519D01*
X1547121Y906136D01*
X1546980Y905994D01*
X1546248Y906726D01*
X1546389Y906868D01*
G37*
G36*
G01X1547669Y905022D02*
X1547285Y904840D01*
X1546755Y905370D01*
X1546937Y905754D01*
X1547079Y905895D01*
X1547810Y905164D01*
X1547669Y905022D01*
G37*
G36*
G01X1548051Y905206D02*
X1548434Y905388D01*
X1548965Y904858D01*
X1548783Y904474D01*
X1548641Y904333D01*
X1547909Y905065D01*
X1548051Y905206D01*
G37*
G36*
G01X1549331Y903360D02*
X1548947Y903178D01*
X1548417Y903709D01*
X1548599Y904092D01*
X1548740Y904234D01*
X1549472Y903502D01*
X1549331Y903360D01*
G37*
G36*
G01X1549712Y903544D02*
X1550096Y903726D01*
X1550626Y903196D01*
X1550444Y902812D01*
X1550303Y902671D01*
X1549571Y903403D01*
X1549712Y903544D01*
G37*
G36*
G01X1550992Y901699D02*
X1550609Y901517D01*
X1550078Y902047D01*
X1550261Y902431D01*
X1550402Y902572D01*
X1551134Y901840D01*
X1550992Y901699D01*
G37*
G36*
G01X1543915Y911040D02*
X1544298Y911222D01*
X1544829Y910692D01*
X1544647Y910308D01*
X1544505Y910167D01*
X1543773Y910899D01*
X1543915Y911040D01*
G37*
G36*
G01X1545195Y909195D02*
X1544811Y909013D01*
X1544281Y909543D01*
X1544463Y909926D01*
X1544604Y910068D01*
X1545336Y909336D01*
X1545195Y909195D01*
G37*
G36*
G01X1543533Y910856D02*
X1543149Y910674D01*
X1542619Y911205D01*
X1542801Y911588D01*
X1542942Y911730D01*
X1543674Y910998D01*
X1543533Y910856D01*
G37*
G36*
G01X1542253Y912702D02*
X1542637Y912884D01*
X1543167Y912354D01*
X1542985Y911970D01*
X1542843Y911829D01*
X1542112Y912560D01*
X1542253Y912702D01*
G37*
G36*
G01X1550561Y904393D02*
X1550945Y904575D01*
X1551475Y904045D01*
X1551293Y903661D01*
X1551152Y903520D01*
X1550420Y904252D01*
X1550561Y904393D01*
G37*
G36*
G01X1551841Y902548D02*
X1551458Y902366D01*
X1550927Y902896D01*
X1551110Y903280D01*
X1551251Y903421D01*
X1551983Y902689D01*
X1551841Y902548D01*
G37*
G36*
G01X1550180Y904209D02*
X1549796Y904027D01*
X1549266Y904558D01*
X1549448Y904941D01*
X1549589Y905083D01*
X1550321Y904351D01*
X1550180Y904209D01*
G37*
G36*
G01X1548900Y906055D02*
X1549283Y906237D01*
X1549814Y905707D01*
X1549632Y905323D01*
X1549490Y905182D01*
X1548758Y905914D01*
X1548900Y906055D01*
G37*
G36*
G01X1545576Y909378D02*
X1545960Y909561D01*
X1546490Y909030D01*
X1546308Y908647D01*
X1546167Y908505D01*
X1545435Y909237D01*
X1545576Y909378D01*
G37*
G36*
G01X1546856Y907533D02*
X1546473Y907351D01*
X1545942Y907881D01*
X1546124Y908265D01*
X1546266Y908406D01*
X1546998Y907674D01*
X1546856Y907533D01*
G37*
G36*
G01X1547238Y907717D02*
X1547622Y907899D01*
X1548152Y907368D01*
X1547970Y906985D01*
X1547829Y906843D01*
X1547097Y907575D01*
X1547238Y907717D01*
G37*
G36*
G01X1548518Y905871D02*
X1548134Y905689D01*
X1547604Y906219D01*
X1547786Y906603D01*
X1547928Y906744D01*
X1548659Y906013D01*
X1548518Y905871D01*
G37*
G36*
G01X1552223Y902732D02*
X1552607Y902914D01*
X1553137Y902383D01*
X1552955Y902000D01*
X1552814Y901858D01*
X1552082Y902590D01*
X1552223Y902732D01*
G37*
G36*
G01X1550143Y900850D02*
X1549760Y900668D01*
X1549229Y901198D01*
X1549412Y901582D01*
X1549553Y901723D01*
X1550285Y900991D01*
X1550143Y900850D01*
G37*
G36*
G01X1543878Y907680D02*
X1544262Y907863D01*
X1544792Y907332D01*
X1544610Y906949D01*
X1544469Y906807D01*
X1543737Y907539D01*
X1543878Y907680D01*
G37*
G36*
G01X1545158Y905835D02*
X1544775Y905653D01*
X1544244Y906183D01*
X1544426Y906567D01*
X1544568Y906708D01*
X1545300Y905976D01*
X1545158Y905835D01*
G37*
G36*
G01X1543497Y907497D02*
X1543113Y907315D01*
X1542583Y907845D01*
X1542765Y908228D01*
X1542906Y908370D01*
X1543638Y907638D01*
X1543497Y907497D01*
G37*
G36*
G01X1542217Y909342D02*
X1542600Y909524D01*
X1543131Y908994D01*
X1542949Y908610D01*
X1542807Y908469D01*
X1542075Y909201D01*
X1542217Y909342D01*
G37*
G36*
G01X1548863Y902695D02*
X1549247Y902877D01*
X1549777Y902347D01*
X1549595Y901963D01*
X1549454Y901822D01*
X1548722Y902554D01*
X1548863Y902695D01*
G37*
G36*
G01X1547202Y904357D02*
X1547585Y904539D01*
X1548116Y904009D01*
X1547934Y903625D01*
X1547792Y903484D01*
X1547060Y904216D01*
X1547202Y904357D01*
G37*
G36*
G01X1548482Y902511D02*
X1548098Y902329D01*
X1547568Y902860D01*
X1547750Y903243D01*
X1547891Y903385D01*
X1548623Y902653D01*
X1548482Y902511D01*
G37*
G36*
G01X1545540Y906019D02*
X1545924Y906201D01*
X1546454Y905670D01*
X1546272Y905287D01*
X1546131Y905145D01*
X1545399Y905877D01*
X1545540Y906019D01*
G37*
G36*
G01X1546820Y904173D02*
X1546436Y903991D01*
X1545906Y904521D01*
X1546088Y904905D01*
X1546230Y905046D01*
X1546961Y904315D01*
X1546820Y904173D01*
G37*
G36*
G01X1558659Y916034D02*
X1558275Y915852D01*
X1557745Y916382D01*
X1557927Y916766D01*
X1558068Y916907D01*
X1558800Y916175D01*
X1558659Y916034D01*
G37*
G36*
G01X1554592Y931908D02*
X1554209Y931726D01*
X1553678Y932256D01*
X1553860Y932640D01*
X1554002Y932781D01*
X1554734Y932049D01*
X1554592Y931908D01*
G37*
G36*
G01X1553312Y933753D02*
X1553696Y933936D01*
X1554226Y933405D01*
X1554044Y933022D01*
X1553903Y932880D01*
X1553171Y933612D01*
X1553312Y933753D01*
G37*
G36*
G01X1549953Y933717D02*
X1550336Y933899D01*
X1550867Y933369D01*
X1550685Y932985D01*
X1550543Y932844D01*
X1549811Y933576D01*
X1549953Y933717D01*
G37*
G36*
G01X1551233Y931872D02*
X1550849Y931690D01*
X1550319Y932220D01*
X1550501Y932603D01*
X1550642Y932745D01*
X1551374Y932013D01*
X1551233Y931872D01*
G37*
G36*
G01X1551614Y932055D02*
X1551998Y932238D01*
X1552528Y931707D01*
X1552346Y931324D01*
X1552205Y931182D01*
X1551473Y931914D01*
X1551614Y932055D01*
G37*
G36*
G01X1553276Y930394D02*
X1553660Y930576D01*
X1554190Y930046D01*
X1554008Y929662D01*
X1553867Y929520D01*
X1553135Y930252D01*
X1553276Y930394D01*
G37*
G36*
G01X1552894Y930210D02*
X1552511Y930028D01*
X1551980Y930558D01*
X1552162Y930942D01*
X1552304Y931083D01*
X1553036Y930351D01*
X1552894Y930210D01*
G37*
G36*
G01X1552082Y932721D02*
X1551698Y932539D01*
X1551168Y933069D01*
X1551350Y933452D01*
X1551491Y933594D01*
X1552223Y932862D01*
X1552082Y932721D01*
G37*
G36*
G01X1554126Y931242D02*
X1554509Y931424D01*
X1555040Y930894D01*
X1554858Y930510D01*
X1554716Y930369D01*
X1553984Y931101D01*
X1554126Y931242D01*
G37*
G36*
G01X1552464Y932904D02*
X1552847Y933086D01*
X1553378Y932556D01*
X1553196Y932172D01*
X1553054Y932031D01*
X1552322Y932763D01*
X1552464Y932904D01*
G37*
G36*
G01X1553744Y931059D02*
X1553360Y930877D01*
X1552830Y931407D01*
X1553012Y931790D01*
X1553153Y931932D01*
X1553885Y931200D01*
X1553744Y931059D01*
G37*
G36*
G01X1549104Y932868D02*
X1549487Y933050D01*
X1550018Y932520D01*
X1549836Y932136D01*
X1549694Y931995D01*
X1548962Y932727D01*
X1549104Y932868D01*
G37*
G36*
G01X1550765Y931206D02*
X1551149Y931389D01*
X1551679Y930858D01*
X1551497Y930475D01*
X1551356Y930333D01*
X1550624Y931065D01*
X1550765Y931206D01*
G37*
G36*
G01X1552045Y929361D02*
X1551662Y929179D01*
X1551131Y929709D01*
X1551313Y930093D01*
X1551455Y930234D01*
X1552187Y929502D01*
X1552045Y929361D01*
G37*
G36*
G01X1550384Y931023D02*
X1550000Y930841D01*
X1549470Y931371D01*
X1549652Y931754D01*
X1549793Y931896D01*
X1550525Y931164D01*
X1550384Y931023D01*
G37*
G36*
G01X1548722Y932684D02*
X1548338Y932502D01*
X1547808Y933033D01*
X1547990Y933416D01*
X1548131Y933558D01*
X1548863Y932826D01*
X1548722Y932684D01*
G37*
G36*
G01X1552427Y929545D02*
X1552811Y929727D01*
X1553341Y929197D01*
X1553159Y928813D01*
X1553018Y928671D01*
X1552286Y929403D01*
X1552427Y929545D01*
G37*
G36*
G01X1543274Y933685D02*
X1543657Y933867D01*
X1544188Y933337D01*
X1544006Y932953D01*
X1543864Y932812D01*
X1543132Y933544D01*
X1543274Y933685D01*
G37*
G36*
G01X1544554Y931840D02*
X1544170Y931657D01*
X1543640Y932188D01*
X1543822Y932571D01*
X1543963Y932713D01*
X1544695Y931981D01*
X1544554Y931840D01*
G37*
G36*
G01X1546597Y930362D02*
X1546981Y930544D01*
X1547511Y930013D01*
X1547329Y929630D01*
X1547188Y929488D01*
X1546456Y930220D01*
X1546597Y930362D01*
G37*
G36*
G01X1547877Y928516D02*
X1547493Y928334D01*
X1546963Y928864D01*
X1547145Y929248D01*
X1547287Y929389D01*
X1548018Y928658D01*
X1547877Y928516D01*
G37*
G36*
G01X1548259Y928700D02*
X1548642Y928882D01*
X1549173Y928352D01*
X1548991Y927968D01*
X1548849Y927827D01*
X1548117Y928559D01*
X1548259Y928700D01*
G37*
G36*
G01X1549539Y926854D02*
X1549155Y926672D01*
X1548625Y927203D01*
X1548807Y927586D01*
X1548948Y927728D01*
X1549680Y926996D01*
X1549539Y926854D01*
G37*
G36*
G01X1546215Y930178D02*
X1545832Y929996D01*
X1545301Y930526D01*
X1545483Y930910D01*
X1545625Y931051D01*
X1546357Y930319D01*
X1546215Y930178D01*
G37*
G36*
G01X1544935Y932023D02*
X1545319Y932205D01*
X1545849Y931675D01*
X1545667Y931291D01*
X1545526Y931150D01*
X1544794Y931882D01*
X1544935Y932023D01*
G37*
G36*
G01X1551200Y925193D02*
X1550817Y925011D01*
X1550287Y925541D01*
X1550469Y925925D01*
X1550610Y926066D01*
X1551342Y925334D01*
X1551200Y925193D01*
G37*
G36*
G01X1549921Y927038D02*
X1550304Y927220D01*
X1550835Y926690D01*
X1550652Y926306D01*
X1550511Y926165D01*
X1549779Y926897D01*
X1549921Y927038D01*
G37*
G36*
G01X1551582Y925377D02*
X1551966Y925559D01*
X1552496Y925028D01*
X1552314Y924645D01*
X1552173Y924503D01*
X1551441Y925235D01*
X1551582Y925377D01*
G37*
G36*
G01X1553244Y923715D02*
X1553628Y923897D01*
X1554158Y923367D01*
X1553976Y922983D01*
X1553834Y922842D01*
X1553103Y923573D01*
X1553244Y923715D01*
G37*
G36*
G01X1552862Y923531D02*
X1552479Y923349D01*
X1551948Y923879D01*
X1552130Y924263D01*
X1552272Y924404D01*
X1553004Y923672D01*
X1552862Y923531D01*
G37*
G36*
G01X1556567Y920391D02*
X1556951Y920574D01*
X1557481Y920043D01*
X1557299Y919660D01*
X1557158Y919518D01*
X1556426Y920250D01*
X1556567Y920391D01*
G37*
G36*
G01X1557847Y918546D02*
X1557464Y918364D01*
X1556933Y918894D01*
X1557115Y919278D01*
X1557257Y919419D01*
X1557989Y918687D01*
X1557847Y918546D01*
G37*
G36*
G01X1554906Y922053D02*
X1555289Y922235D01*
X1555820Y921705D01*
X1555638Y921321D01*
X1555496Y921180D01*
X1554764Y921912D01*
X1554906Y922053D01*
G37*
G36*
G01X1556186Y920208D02*
X1555802Y920026D01*
X1555272Y920556D01*
X1555454Y920939D01*
X1555595Y921081D01*
X1556327Y920349D01*
X1556186Y920208D01*
G37*
G36*
G01X1554524Y921869D02*
X1554140Y921687D01*
X1553610Y922218D01*
X1553792Y922601D01*
X1553933Y922743D01*
X1554665Y922011D01*
X1554524Y921869D01*
G37*
G36*
G01X1544514Y928477D02*
X1544131Y928295D01*
X1543600Y928825D01*
X1543782Y929209D01*
X1543924Y929350D01*
X1544656Y928618D01*
X1544514Y928477D01*
G37*
G36*
G01X1543234Y930322D02*
X1543618Y930504D01*
X1544148Y929974D01*
X1543966Y929591D01*
X1543825Y929449D01*
X1543093Y930181D01*
X1543234Y930322D01*
G37*
G36*
G01X1542853Y930139D02*
X1542469Y929956D01*
X1541939Y930487D01*
X1542121Y930870D01*
X1542262Y931012D01*
X1542994Y930280D01*
X1542853Y930139D01*
G37*
G36*
G01X1546558Y926999D02*
X1546941Y927181D01*
X1547472Y926651D01*
X1547290Y926267D01*
X1547148Y926126D01*
X1546416Y926857D01*
X1546558Y926999D01*
G37*
G36*
G01X1544896Y928661D02*
X1545280Y928843D01*
X1545810Y928312D01*
X1545628Y927929D01*
X1545487Y927787D01*
X1544755Y928519D01*
X1544896Y928661D01*
G37*
G36*
G01X1546176Y926815D02*
X1545793Y926633D01*
X1545262Y927163D01*
X1545444Y927547D01*
X1545586Y927688D01*
X1546318Y926957D01*
X1546176Y926815D01*
G37*
G36*
G01X1547838Y925153D02*
X1547454Y924971D01*
X1546924Y925502D01*
X1547106Y925885D01*
X1547247Y926027D01*
X1547979Y925295D01*
X1547838Y925153D01*
G37*
G36*
G01X1548220Y925337D02*
X1548603Y925519D01*
X1549134Y924989D01*
X1548951Y924605D01*
X1548810Y924464D01*
X1548078Y925196D01*
X1548220Y925337D01*
G37*
G36*
G01X1549881Y923676D02*
X1550265Y923858D01*
X1550795Y923327D01*
X1550613Y922944D01*
X1550472Y922802D01*
X1549740Y923534D01*
X1549881Y923676D01*
G37*
G36*
G01X1549499Y923492D02*
X1549116Y923310D01*
X1548586Y923840D01*
X1548768Y924224D01*
X1548909Y924365D01*
X1549641Y923633D01*
X1549499Y923492D01*
G37*
G36*
G01X1551161Y921830D02*
X1550778Y921648D01*
X1550247Y922178D01*
X1550429Y922562D01*
X1550571Y922703D01*
X1551303Y921971D01*
X1551161Y921830D01*
G37*
G36*
G01X1551543Y922014D02*
X1551927Y922196D01*
X1552457Y921666D01*
X1552275Y921282D01*
X1552133Y921141D01*
X1551402Y921872D01*
X1551543Y922014D01*
G37*
G36*
G01X1554866Y918690D02*
X1555250Y918873D01*
X1555780Y918342D01*
X1555598Y917959D01*
X1555457Y917817D01*
X1554725Y918549D01*
X1554866Y918690D01*
G37*
G36*
G01X1554485Y918507D02*
X1554101Y918325D01*
X1553571Y918855D01*
X1553753Y919238D01*
X1553894Y919380D01*
X1554626Y918648D01*
X1554485Y918507D01*
G37*
G36*
G01X1553205Y920352D02*
X1553588Y920534D01*
X1554119Y920004D01*
X1553937Y919620D01*
X1553795Y919479D01*
X1553063Y920211D01*
X1553205Y920352D01*
G37*
G36*
G01X1552823Y920168D02*
X1552439Y919986D01*
X1551909Y920516D01*
X1552091Y920900D01*
X1552232Y921042D01*
X1552964Y920310D01*
X1552823Y920168D01*
G37*
G36*
G01X1547309Y917758D02*
X1547693Y917940D01*
X1548223Y917410D01*
X1548041Y917026D01*
X1547899Y916885D01*
X1547168Y917616D01*
X1547309Y917758D01*
G37*
G36*
G01X1546927Y917574D02*
X1546544Y917392D01*
X1546013Y917922D01*
X1546195Y918306D01*
X1546337Y918447D01*
X1547069Y917715D01*
X1546927Y917574D01*
G37*
G36*
G01X1545265Y919236D02*
X1544882Y919054D01*
X1544352Y919584D01*
X1544534Y919968D01*
X1544675Y920109D01*
X1545407Y919377D01*
X1545265Y919236D01*
G37*
G36*
G01X1543604Y920897D02*
X1543220Y920715D01*
X1542690Y921246D01*
X1542872Y921629D01*
X1543013Y921771D01*
X1543745Y921039D01*
X1543604Y920897D01*
G37*
G36*
G01X1543986Y921081D02*
X1544369Y921263D01*
X1544900Y920733D01*
X1544717Y920349D01*
X1544576Y920208D01*
X1543844Y920940D01*
X1543986Y921081D01*
G37*
G36*
G01X1542324Y922743D02*
X1542707Y922925D01*
X1543238Y922395D01*
X1543056Y922011D01*
X1542914Y921870D01*
X1542182Y922602D01*
X1542324Y922743D01*
G37*
G36*
G01X1545647Y919420D02*
X1546031Y919602D01*
X1546561Y919071D01*
X1546379Y918688D01*
X1546238Y918546D01*
X1545506Y919278D01*
X1545647Y919420D01*
G37*
G36*
G01X1543567Y917538D02*
X1543184Y917356D01*
X1542654Y917886D01*
X1542836Y918270D01*
X1542977Y918411D01*
X1543709Y917679D01*
X1543567Y917538D01*
G37*
G36*
G01X1543949Y917722D02*
X1544333Y917904D01*
X1544863Y917373D01*
X1544681Y916990D01*
X1544540Y916848D01*
X1543808Y917580D01*
X1543949Y917722D01*
G37*
G36*
G01X1542288Y919383D02*
X1542671Y919565D01*
X1543202Y919035D01*
X1543019Y918651D01*
X1542878Y918510D01*
X1542146Y919242D01*
X1542288Y919383D01*
G37*
G36*
G01X1544798Y918571D02*
X1545182Y918753D01*
X1545712Y918222D01*
X1545530Y917839D01*
X1545389Y917697D01*
X1544657Y918429D01*
X1544798Y918571D01*
G37*
G36*
G01X1544416Y918387D02*
X1544033Y918205D01*
X1543503Y918735D01*
X1543685Y919119D01*
X1543826Y919260D01*
X1544558Y918528D01*
X1544416Y918387D01*
G37*
G36*
G01X1543137Y920232D02*
X1543520Y920414D01*
X1544051Y919884D01*
X1543868Y919500D01*
X1543727Y919359D01*
X1542995Y920091D01*
X1543137Y920232D01*
G37*
G36*
G01X1542755Y920048D02*
X1542371Y919866D01*
X1541841Y920397D01*
X1542023Y920780D01*
X1542164Y920922D01*
X1542896Y920190D01*
X1542755Y920048D01*
G37*
G36*
G01X1545403Y932689D02*
X1545020Y932507D01*
X1544489Y933037D01*
X1544671Y933421D01*
X1544813Y933562D01*
X1545545Y932830D01*
X1545403Y932689D01*
G37*
G36*
G01X1552050Y926042D02*
X1551666Y925860D01*
X1551136Y926390D01*
X1551318Y926774D01*
X1551460Y926915D01*
X1552191Y926184D01*
X1552050Y926042D01*
G37*
G36*
G01X1548727Y929366D02*
X1548343Y929184D01*
X1547813Y929714D01*
X1547995Y930097D01*
X1548136Y930239D01*
X1548868Y929507D01*
X1548727Y929366D01*
G37*
G36*
G01X1549108Y929549D02*
X1549492Y929732D01*
X1550022Y929201D01*
X1549840Y928818D01*
X1549699Y928676D01*
X1548967Y929408D01*
X1549108Y929549D01*
G37*
G36*
G01X1550388Y927704D02*
X1550005Y927522D01*
X1549474Y928052D01*
X1549656Y928436D01*
X1549798Y928577D01*
X1550530Y927845D01*
X1550388Y927704D01*
G37*
G36*
G01X1550770Y927888D02*
X1551154Y928070D01*
X1551684Y927540D01*
X1551502Y927156D01*
X1551361Y927014D01*
X1550629Y927746D01*
X1550770Y927888D01*
G37*
G36*
G01X1545785Y932873D02*
X1546169Y933055D01*
X1546699Y932525D01*
X1546517Y932141D01*
X1546375Y932000D01*
X1545644Y932731D01*
X1545785Y932873D01*
G37*
G36*
G01X1547065Y931027D02*
X1546681Y930845D01*
X1546151Y931376D01*
X1546333Y931759D01*
X1546474Y931901D01*
X1547206Y931169D01*
X1547065Y931027D01*
G37*
G36*
G01X1547447Y931211D02*
X1547830Y931393D01*
X1548361Y930863D01*
X1548179Y930479D01*
X1548037Y930338D01*
X1547305Y931070D01*
X1547447Y931211D01*
G37*
G36*
G01X1555373Y922719D02*
X1554990Y922537D01*
X1554459Y923067D01*
X1554642Y923451D01*
X1554783Y923592D01*
X1555515Y922860D01*
X1555373Y922719D01*
G37*
G36*
G01X1554093Y924564D02*
X1554477Y924746D01*
X1555007Y924216D01*
X1554825Y923832D01*
X1554684Y923691D01*
X1553952Y924423D01*
X1554093Y924564D01*
G37*
G36*
G01X1553712Y924381D02*
X1553328Y924198D01*
X1552798Y924729D01*
X1552980Y925112D01*
X1553121Y925254D01*
X1553853Y924522D01*
X1553712Y924381D01*
G37*
G36*
G01X1552432Y926226D02*
X1552815Y926408D01*
X1553346Y925878D01*
X1553164Y925494D01*
X1553022Y925353D01*
X1552290Y926085D01*
X1552432Y926226D01*
G37*
G36*
G01X1558697Y919395D02*
X1558313Y919213D01*
X1557783Y919744D01*
X1557965Y920127D01*
X1558106Y920269D01*
X1558838Y919537D01*
X1558697Y919395D01*
G37*
G36*
G01X1557035Y921057D02*
X1556651Y920875D01*
X1556121Y921405D01*
X1556303Y921789D01*
X1556445Y921930D01*
X1557176Y921199D01*
X1557035Y921057D01*
G37*
G36*
G01X1557417Y921241D02*
X1557801Y921423D01*
X1558331Y920893D01*
X1558149Y920509D01*
X1558007Y920368D01*
X1557275Y921100D01*
X1557417Y921241D01*
G37*
G36*
G01X1555755Y922903D02*
X1556139Y923085D01*
X1556669Y922554D01*
X1556487Y922171D01*
X1556346Y922029D01*
X1555614Y922761D01*
X1555755Y922903D01*
G37*
G36*
G01X1542422Y932833D02*
X1542806Y933016D01*
X1543336Y932485D01*
X1543154Y932102D01*
X1543013Y931960D01*
X1542281Y932692D01*
X1542422Y932833D01*
G37*
G36*
G01X1543702Y930988D02*
X1543319Y930806D01*
X1542788Y931336D01*
X1542970Y931720D01*
X1543112Y931861D01*
X1543844Y931129D01*
X1543702Y930988D01*
G37*
G36*
G01X1544084Y931172D02*
X1544468Y931354D01*
X1544998Y930824D01*
X1544816Y930440D01*
X1544674Y930299D01*
X1543943Y931030D01*
X1544084Y931172D01*
G37*
G36*
G01X1545364Y929326D02*
X1544980Y929144D01*
X1544450Y929675D01*
X1544632Y930058D01*
X1544774Y930200D01*
X1545505Y929468D01*
X1545364Y929326D01*
G37*
G36*
G01X1545746Y929510D02*
X1546129Y929692D01*
X1546660Y929162D01*
X1546478Y928778D01*
X1546336Y928637D01*
X1545604Y929369D01*
X1545746Y929510D01*
G37*
G36*
G01X1547026Y927665D02*
X1546642Y927483D01*
X1546112Y928013D01*
X1546294Y928397D01*
X1546435Y928538D01*
X1547167Y927806D01*
X1547026Y927665D01*
G37*
G36*
G01X1547408Y927849D02*
X1547791Y928031D01*
X1548322Y927501D01*
X1548140Y927117D01*
X1547998Y926976D01*
X1547266Y927707D01*
X1547408Y927849D01*
G37*
G36*
G01X1548688Y926003D02*
X1548304Y925821D01*
X1547774Y926352D01*
X1547956Y926735D01*
X1548097Y926877D01*
X1548829Y926145D01*
X1548688Y926003D01*
G37*
G36*
G01X1549070Y926187D02*
X1549453Y926369D01*
X1549984Y925839D01*
X1549801Y925455D01*
X1549660Y925314D01*
X1548928Y926046D01*
X1549070Y926187D01*
G37*
G36*
G01X1550350Y924342D02*
X1549966Y924160D01*
X1549436Y924690D01*
X1549618Y925074D01*
X1549759Y925215D01*
X1550491Y924483D01*
X1550350Y924342D01*
G37*
G36*
G01X1552011Y922680D02*
X1551628Y922498D01*
X1551097Y923028D01*
X1551279Y923412D01*
X1551421Y923553D01*
X1552153Y922822D01*
X1552011Y922680D01*
G37*
G36*
G01X1550731Y924526D02*
X1551115Y924708D01*
X1551645Y924177D01*
X1551463Y923794D01*
X1551322Y923652D01*
X1550590Y924384D01*
X1550731Y924526D01*
G37*
G36*
G01X1556997Y917696D02*
X1556613Y917513D01*
X1556083Y918044D01*
X1556265Y918427D01*
X1556406Y918569D01*
X1557138Y917837D01*
X1556997Y917696D01*
G37*
G36*
G01X1557379Y917879D02*
X1557762Y918061D01*
X1558293Y917531D01*
X1558111Y917148D01*
X1557969Y917006D01*
X1557237Y917738D01*
X1557379Y917879D01*
G37*
G36*
G01X1553673Y921019D02*
X1553290Y920837D01*
X1552759Y921367D01*
X1552941Y921750D01*
X1553083Y921892D01*
X1553815Y921160D01*
X1553673Y921019D01*
G37*
G36*
G01X1552393Y922864D02*
X1552777Y923046D01*
X1553307Y922516D01*
X1553125Y922132D01*
X1552984Y921991D01*
X1552252Y922723D01*
X1552393Y922864D01*
G37*
G36*
G01X1554055Y921203D02*
X1554439Y921385D01*
X1554969Y920854D01*
X1554787Y920471D01*
X1554646Y920329D01*
X1553914Y921061D01*
X1554055Y921203D01*
G37*
G36*
G01X1555335Y919357D02*
X1554951Y919175D01*
X1554421Y919705D01*
X1554603Y920089D01*
X1554745Y920230D01*
X1555476Y919499D01*
X1555335Y919357D01*
G37*
G36*
G01X1555717Y919541D02*
X1556101Y919723D01*
X1556631Y919193D01*
X1556449Y918809D01*
X1556307Y918668D01*
X1555575Y919400D01*
X1555717Y919541D01*
G37*
G36*
G01X1549989Y937077D02*
X1550373Y937259D01*
X1550903Y936729D01*
X1550721Y936345D01*
X1550579Y936204D01*
X1549848Y936935D01*
X1549989Y937077D01*
G37*
G36*
G01X1549607Y936893D02*
X1549224Y936711D01*
X1548693Y937241D01*
X1548875Y937625D01*
X1549017Y937766D01*
X1549749Y937034D01*
X1549607Y936893D01*
G37*
G36*
G01X1547945Y938555D02*
X1547562Y938373D01*
X1547032Y938903D01*
X1547214Y939287D01*
X1547355Y939428D01*
X1548087Y938696D01*
X1547945Y938555D01*
G37*
G36*
G01X1548327Y938739D02*
X1548711Y938921D01*
X1549241Y938390D01*
X1549059Y938007D01*
X1548918Y937865D01*
X1548186Y938597D01*
X1548327Y938739D01*
G37*
G36*
G01X1551269Y935231D02*
X1550885Y935049D01*
X1550355Y935580D01*
X1550537Y935963D01*
X1550678Y936105D01*
X1551410Y935373D01*
X1551269Y935231D01*
G37*
G36*
G01X1544622Y941878D02*
X1544238Y941696D01*
X1543708Y942226D01*
X1543890Y942610D01*
X1544032Y942751D01*
X1544763Y942020D01*
X1544622Y941878D01*
G37*
G36*
G01X1543342Y943724D02*
X1543726Y943906D01*
X1544256Y943375D01*
X1544074Y942992D01*
X1543933Y942850D01*
X1543201Y943582D01*
X1543342Y943724D01*
G37*
G36*
G01X1542960Y943540D02*
X1542577Y943358D01*
X1542046Y943888D01*
X1542228Y944272D01*
X1542370Y944413D01*
X1543102Y943681D01*
X1542960Y943540D01*
G37*
G36*
G01X1546284Y940216D02*
X1545900Y940034D01*
X1545370Y940565D01*
X1545552Y940948D01*
X1545693Y941090D01*
X1546425Y940358D01*
X1546284Y940216D01*
G37*
G36*
G01X1546666Y940400D02*
X1547049Y940582D01*
X1547580Y940052D01*
X1547397Y939668D01*
X1547256Y939527D01*
X1546524Y940259D01*
X1546666Y940400D01*
G37*
G36*
G01X1545004Y942062D02*
X1545387Y942244D01*
X1545918Y941714D01*
X1545736Y941330D01*
X1545594Y941189D01*
X1544862Y941921D01*
X1545004Y942062D01*
G37*
G36*
G01X1551651Y935415D02*
X1552034Y935597D01*
X1552565Y935067D01*
X1552383Y934683D01*
X1552241Y934542D01*
X1551509Y935274D01*
X1551651Y935415D01*
G37*
G36*
G01X1552931Y933570D02*
X1552547Y933388D01*
X1552017Y933918D01*
X1552199Y934301D01*
X1552340Y934443D01*
X1553072Y933711D01*
X1552931Y933570D01*
G37*
G36*
G01X1548291Y935379D02*
X1548675Y935561D01*
X1549205Y935031D01*
X1549023Y934647D01*
X1548881Y934506D01*
X1548150Y935237D01*
X1548291Y935379D01*
G37*
G36*
G01X1549571Y933533D02*
X1549187Y933351D01*
X1548657Y933882D01*
X1548839Y934265D01*
X1548980Y934407D01*
X1549712Y933675D01*
X1549571Y933533D01*
G37*
G36*
G01X1544586Y938518D02*
X1544202Y938336D01*
X1543672Y938867D01*
X1543854Y939250D01*
X1543995Y939392D01*
X1544727Y938660D01*
X1544586Y938518D01*
G37*
G36*
G01X1546629Y937041D02*
X1547013Y937223D01*
X1547543Y936692D01*
X1547361Y936309D01*
X1547220Y936167D01*
X1546488Y936899D01*
X1546629Y937041D01*
G37*
G36*
G01X1546247Y936857D02*
X1545864Y936675D01*
X1545334Y937205D01*
X1545516Y937589D01*
X1545657Y937730D01*
X1546389Y936998D01*
X1546247Y936857D01*
G37*
G36*
G01X1544968Y938702D02*
X1545351Y938884D01*
X1545882Y938354D01*
X1545699Y937970D01*
X1545558Y937829D01*
X1544826Y938561D01*
X1544968Y938702D01*
G37*
G36*
G01X1547909Y935195D02*
X1547526Y935013D01*
X1546995Y935543D01*
X1547177Y935927D01*
X1547319Y936068D01*
X1548051Y935336D01*
X1547909Y935195D01*
G37*
G36*
G01X1543306Y940364D02*
X1543689Y940546D01*
X1544220Y940016D01*
X1544038Y939632D01*
X1543896Y939491D01*
X1543164Y940223D01*
X1543306Y940364D01*
G37*
G36*
G01X1542924Y940180D02*
X1542540Y939998D01*
X1542010Y940528D01*
X1542192Y940912D01*
X1542334Y941053D01*
X1543065Y940322D01*
X1542924Y940180D01*
G37*
G36*
G01X1550420Y934382D02*
X1550036Y934200D01*
X1549506Y934731D01*
X1549688Y935114D01*
X1549829Y935256D01*
X1550561Y934524D01*
X1550420Y934382D01*
G37*
G36*
G01X1550802Y934566D02*
X1551185Y934748D01*
X1551716Y934218D01*
X1551534Y933834D01*
X1551392Y933693D01*
X1550660Y934425D01*
X1550802Y934566D01*
G37*
G36*
G01X1545817Y939551D02*
X1546200Y939733D01*
X1546731Y939203D01*
X1546548Y938819D01*
X1546407Y938678D01*
X1545675Y939410D01*
X1545817Y939551D01*
G37*
G36*
G01X1547478Y937890D02*
X1547862Y938072D01*
X1548392Y937541D01*
X1548210Y937158D01*
X1548069Y937016D01*
X1547337Y937748D01*
X1547478Y937890D01*
G37*
G36*
G01X1547096Y937706D02*
X1546713Y937524D01*
X1546183Y938054D01*
X1546365Y938438D01*
X1546506Y938579D01*
X1547238Y937847D01*
X1547096Y937706D01*
G37*
G36*
G01X1549140Y936228D02*
X1549524Y936410D01*
X1550054Y935880D01*
X1549872Y935496D01*
X1549730Y935355D01*
X1548999Y936086D01*
X1549140Y936228D01*
G37*
G36*
G01X1548758Y936044D02*
X1548375Y935862D01*
X1547844Y936392D01*
X1548026Y936776D01*
X1548168Y936917D01*
X1548900Y936185D01*
X1548758Y936044D01*
G37*
G36*
G01X1544155Y941213D02*
X1544538Y941395D01*
X1545069Y940865D01*
X1544887Y940481D01*
X1544745Y940340D01*
X1544013Y941072D01*
X1544155Y941213D01*
G37*
G36*
G01X1543773Y941029D02*
X1543389Y940847D01*
X1542859Y941377D01*
X1543041Y941761D01*
X1543183Y941902D01*
X1543914Y941171D01*
X1543773Y941029D01*
G37*
G36*
G01X1542493Y942875D02*
X1542877Y943057D01*
X1543407Y942526D01*
X1543225Y942143D01*
X1543084Y942001D01*
X1542352Y942733D01*
X1542493Y942875D01*
G37*
G36*
G01X1545435Y939367D02*
X1545051Y939185D01*
X1544521Y939716D01*
X1544703Y940099D01*
X1544844Y940241D01*
X1545576Y939509D01*
X1545435Y939367D01*
G37*
G36*
G01X1547060Y934346D02*
X1546677Y934164D01*
X1546146Y934694D01*
X1546328Y935078D01*
X1546470Y935219D01*
X1547202Y934487D01*
X1547060Y934346D01*
G37*
G36*
G01X1547442Y934530D02*
X1547826Y934712D01*
X1548356Y934182D01*
X1548174Y933798D01*
X1548032Y933657D01*
X1547301Y934388D01*
X1547442Y934530D01*
G37*
G36*
G01X1544119Y937853D02*
X1544502Y938035D01*
X1545033Y937505D01*
X1544850Y937121D01*
X1544709Y936980D01*
X1543977Y937712D01*
X1544119Y937853D01*
G37*
G36*
G01X1543737Y937669D02*
X1543353Y937487D01*
X1542823Y938018D01*
X1543005Y938401D01*
X1543146Y938543D01*
X1543878Y937811D01*
X1543737Y937669D01*
G37*
G36*
G01X1542457Y939515D02*
X1542840Y939697D01*
X1543371Y939167D01*
X1543189Y938783D01*
X1543047Y938642D01*
X1542315Y939374D01*
X1542457Y939515D01*
G37*
G36*
G01X1545398Y936008D02*
X1545015Y935826D01*
X1544485Y936356D01*
X1544667Y936740D01*
X1544808Y936881D01*
X1545540Y936149D01*
X1545398Y936008D01*
G37*
G36*
G01X1545780Y936192D02*
X1546164Y936374D01*
X1546694Y935843D01*
X1546512Y935460D01*
X1546371Y935318D01*
X1545639Y936050D01*
X1545780Y936192D01*
G37*
G36*
G01X1548217Y948475D02*
X1547834Y948293D01*
X1547303Y948823D01*
X1547485Y949207D01*
X1547627Y949348D01*
X1548359Y948616D01*
X1548217Y948475D01*
G37*
G36*
G01X1548599Y948659D02*
X1548983Y948841D01*
X1549513Y948311D01*
X1549331Y947927D01*
X1549189Y947786D01*
X1548458Y948517D01*
X1548599Y948659D01*
G37*
G36*
G01X1549879Y946813D02*
X1549495Y946631D01*
X1548965Y947161D01*
X1549147Y947545D01*
X1549288Y947687D01*
X1550020Y946955D01*
X1549879Y946813D01*
G37*
G36*
G01X1551541Y945152D02*
X1551157Y944969D01*
X1550627Y945500D01*
X1550809Y945883D01*
X1550950Y946025D01*
X1551682Y945293D01*
X1551541Y945152D01*
G37*
G36*
G01X1550261Y946997D02*
X1550644Y947179D01*
X1551175Y946649D01*
X1550993Y946265D01*
X1550851Y946124D01*
X1550119Y946856D01*
X1550261Y946997D01*
G37*
G36*
G01X1549066Y949324D02*
X1548683Y949142D01*
X1548152Y949672D01*
X1548334Y950056D01*
X1548476Y950197D01*
X1549208Y949465D01*
X1549066Y949324D01*
G37*
G36*
G01X1549448Y949508D02*
X1549832Y949690D01*
X1550362Y949160D01*
X1550180Y948776D01*
X1550038Y948635D01*
X1549307Y949366D01*
X1549448Y949508D01*
G37*
G36*
G01X1550728Y947662D02*
X1550344Y947480D01*
X1549814Y948010D01*
X1549996Y948394D01*
X1550137Y948536D01*
X1550869Y947804D01*
X1550728Y947662D01*
G37*
G36*
G01X1546088Y949471D02*
X1546472Y949654D01*
X1547002Y949123D01*
X1546820Y948740D01*
X1546679Y948598D01*
X1545947Y949330D01*
X1546088Y949471D01*
G37*
G36*
G01X1547750Y947810D02*
X1548134Y947992D01*
X1548664Y947462D01*
X1548482Y947078D01*
X1548340Y946937D01*
X1547609Y947668D01*
X1547750Y947810D01*
G37*
G36*
G01X1547368Y947626D02*
X1546985Y947444D01*
X1546454Y947974D01*
X1546636Y948358D01*
X1546778Y948499D01*
X1547510Y947767D01*
X1547368Y947626D01*
G37*
G36*
G01X1545707Y949288D02*
X1545323Y949106D01*
X1544793Y949636D01*
X1544975Y950020D01*
X1545116Y950161D01*
X1545848Y949429D01*
X1545707Y949288D01*
G37*
G36*
G01X1550692Y944303D02*
X1550308Y944120D01*
X1549778Y944651D01*
X1549960Y945034D01*
X1550101Y945176D01*
X1550833Y944444D01*
X1550692Y944303D01*
G37*
G36*
G01X1549412Y946148D02*
X1549795Y946330D01*
X1550326Y945800D01*
X1550144Y945416D01*
X1550002Y945275D01*
X1549270Y946007D01*
X1549412Y946148D01*
G37*
G36*
G01X1549030Y945964D02*
X1548646Y945782D01*
X1548116Y946312D01*
X1548298Y946696D01*
X1548439Y946838D01*
X1549171Y946106D01*
X1549030Y945964D01*
G37*
G36*
G01X1542892Y933501D02*
X1542508Y933319D01*
X1541978Y933849D01*
X1542160Y934233D01*
X1542302Y934374D01*
X1543033Y933643D01*
X1542892Y933501D01*
G37*
G36*
G01X1543741Y934351D02*
X1543358Y934169D01*
X1542828Y934699D01*
X1543010Y935083D01*
X1543151Y935224D01*
X1543883Y934492D01*
X1543741Y934351D01*
G37*
G36*
G01X1544123Y934535D02*
X1544507Y934717D01*
X1545037Y934186D01*
X1544855Y933803D01*
X1544714Y933661D01*
X1543982Y934393D01*
X1544123Y934535D01*
G37*
G36*
G01X1542462Y936196D02*
X1542845Y936378D01*
X1543376Y935848D01*
X1543193Y935464D01*
X1543052Y935323D01*
X1542320Y936055D01*
X1542462Y936196D01*
G37*
G36*
G01X1548635Y952018D02*
X1549019Y952201D01*
X1549549Y951670D01*
X1549367Y951287D01*
X1549226Y951145D01*
X1548494Y951877D01*
X1548635Y952018D01*
G37*
G36*
G01X1549915Y950173D02*
X1549532Y949991D01*
X1549001Y950521D01*
X1549183Y950905D01*
X1549325Y951046D01*
X1550057Y950314D01*
X1549915Y950173D01*
G37*
G36*
G01X1546592Y953496D02*
X1546208Y953314D01*
X1545678Y953845D01*
X1545860Y954228D01*
X1546001Y954370D01*
X1546733Y953638D01*
X1546592Y953496D01*
G37*
G36*
G01X1546974Y953680D02*
X1547357Y953862D01*
X1547888Y953332D01*
X1547705Y952948D01*
X1547564Y952807D01*
X1546832Y953539D01*
X1546974Y953680D01*
G37*
G36*
G01X1548254Y951835D02*
X1547870Y951653D01*
X1547340Y952183D01*
X1547522Y952567D01*
X1547663Y952708D01*
X1548395Y951976D01*
X1548254Y951835D01*
G37*
G36*
G01X1543783Y955114D02*
X1543640Y954714D01*
X1542890D01*
X1542748Y955114D01*
Y955314D01*
X1543783D01*
Y955114D01*
G37*
G36*
G01X1545276Y951982D02*
X1545659Y952164D01*
X1546190Y951634D01*
X1546007Y951250D01*
X1545866Y951109D01*
X1545134Y951841D01*
X1545276Y951982D01*
G37*
G36*
G01X1546556Y950137D02*
X1546172Y949955D01*
X1545642Y950485D01*
X1545824Y950869D01*
X1545965Y951010D01*
X1546697Y950278D01*
X1546556Y950137D01*
G37*
G36*
G01X1546937Y950320D02*
X1547321Y950503D01*
X1547851Y949972D01*
X1547669Y949589D01*
X1547528Y949447D01*
X1546796Y950179D01*
X1546937Y950320D01*
G37*
G36*
G01X1547405Y950986D02*
X1547021Y950804D01*
X1546491Y951334D01*
X1546673Y951718D01*
X1546814Y951859D01*
X1547546Y951127D01*
X1547405Y950986D01*
G37*
G36*
G01X1547786Y951169D02*
X1548170Y951352D01*
X1548700Y950821D01*
X1548518Y950438D01*
X1548377Y950296D01*
X1547645Y951028D01*
X1547786Y951169D01*
G37*
G36*
G01X1546125Y952831D02*
X1546508Y953013D01*
X1547039Y952483D01*
X1546856Y952099D01*
X1546715Y951958D01*
X1545983Y952690D01*
X1546125Y952831D01*
G37*
G36*
G01X1545743Y952647D02*
X1545359Y952465D01*
X1544829Y952996D01*
X1545011Y953379D01*
X1545152Y953521D01*
X1545884Y952789D01*
X1545743Y952647D01*
G37*
G36*
G01X1543783Y953914D02*
X1543640Y953514D01*
X1542890D01*
X1542748Y953914D01*
Y954114D01*
X1543783D01*
Y953914D01*
G37*
G36*
G01X1544427Y951133D02*
X1544810Y951315D01*
X1545341Y950785D01*
X1545158Y950401D01*
X1545017Y950260D01*
X1544285Y950992D01*
X1544427Y951133D01*
G37*
G36*
G01X1544454Y980188D02*
X1544312Y979788D01*
X1543562D01*
X1543420Y980188D01*
Y980388D01*
X1544454D01*
Y980188D01*
G37*
G36*
G01X1542244Y980588D02*
X1542387Y980988D01*
X1543137D01*
X1543280Y980588D01*
Y980388D01*
X1542244D01*
Y980588D01*
G37*
G36*
G01X1544594D02*
X1544737Y980988D01*
X1545487D01*
X1545630Y980588D01*
Y980388D01*
X1544594D01*
Y980588D01*
G37*
G36*
G01X1546804Y980188D02*
X1546662Y979788D01*
X1545912D01*
X1545770Y980188D01*
Y980388D01*
X1546804D01*
Y980188D01*
G37*
G36*
G01X1544454Y978988D02*
X1544312Y978588D01*
X1543562D01*
X1543420Y978988D01*
Y979188D01*
X1544454D01*
Y978988D01*
G37*
G36*
G01X1542244Y979388D02*
X1542387Y979788D01*
X1543137D01*
X1543280Y979388D01*
Y979188D01*
X1542244D01*
Y979388D01*
G37*
G36*
G01X1544594D02*
X1544737Y979788D01*
X1545487D01*
X1545630Y979388D01*
Y979188D01*
X1544594D01*
Y979388D01*
G37*
G36*
G01X1544454Y977788D02*
X1544312Y977388D01*
X1543562D01*
X1543420Y977788D01*
Y977988D01*
X1544454D01*
Y977788D01*
G37*
G36*
G01X1542244Y978188D02*
X1542387Y978588D01*
X1543137D01*
X1543280Y978188D01*
Y977988D01*
X1542244D01*
Y978188D01*
G37*
G36*
G01X1544594D02*
X1544737Y978588D01*
X1545487D01*
X1545630Y978188D01*
Y977988D01*
X1544594D01*
Y978188D01*
G37*
G36*
G01X1542244Y976988D02*
X1542387Y977388D01*
X1543137D01*
X1543280Y976988D01*
Y976788D01*
X1542244D01*
Y976988D01*
G37*
G36*
G01X1544454Y976588D02*
X1544312Y976188D01*
X1543562D01*
X1543420Y976588D01*
Y976788D01*
X1544454D01*
Y976588D01*
G37*
G36*
G01X1544594Y976988D02*
X1544737Y977388D01*
X1545487D01*
X1545630Y976988D01*
Y976788D01*
X1544594D01*
Y976988D01*
G37*
G36*
G01X1544454Y975388D02*
X1544312Y974988D01*
X1543562D01*
X1543420Y975388D01*
Y975588D01*
X1544454D01*
Y975388D01*
G37*
G36*
G01X1542244Y975788D02*
X1542387Y976188D01*
X1543137D01*
X1543280Y975788D01*
Y975588D01*
X1542244D01*
Y975788D01*
G37*
G36*
G01Y974588D02*
X1542387Y974988D01*
X1543137D01*
X1543280Y974588D01*
Y974388D01*
X1542244D01*
Y974588D01*
G37*
G36*
G01X1544454Y974188D02*
X1544312Y973788D01*
X1543562D01*
X1543420Y974188D01*
Y974388D01*
X1544454D01*
Y974188D01*
G37*
G36*
G01X1542244Y973388D02*
X1542387Y973788D01*
X1543137D01*
X1543280Y973388D01*
Y973188D01*
X1542244D01*
Y973388D01*
G37*
G36*
G01Y972188D02*
X1542387Y972588D01*
X1543137D01*
X1543280Y972188D01*
Y971988D01*
X1542244D01*
Y972188D01*
G37*
G36*
G01X1543338Y1009513D02*
X1543520Y1009130D01*
X1542990Y1008599D01*
X1542606Y1008781D01*
X1542465Y1008923D01*
X1543197Y1009655D01*
X1543338Y1009513D01*
G37*
G36*
G01X1544187Y1008664D02*
X1544369Y1008281D01*
X1543839Y1007750D01*
X1543455Y1007932D01*
X1543314Y1008074D01*
X1544046Y1008806D01*
X1544187Y1008664D01*
G37*
G36*
G01X1542342Y1007384D02*
X1542159Y1007768D01*
X1542690Y1008298D01*
X1543073Y1008116D01*
X1543215Y1007975D01*
X1542483Y1007243D01*
X1542342Y1007384D01*
G37*
G36*
G01X1543374Y1006154D02*
X1543556Y1005770D01*
X1543026Y1005240D01*
X1542643Y1005422D01*
X1542501Y1005563D01*
X1543233Y1006295D01*
X1543374Y1006154D01*
G37*
G36*
G01X1543191Y1006535D02*
X1543008Y1006919D01*
X1543539Y1007449D01*
X1543922Y1007267D01*
X1544064Y1007126D01*
X1543332Y1006394D01*
X1543191Y1006535D01*
G37*
G36*
G01X1542669Y1030323D02*
X1542851Y1029939D01*
X1542320Y1029409D01*
X1541937Y1029591D01*
X1541795Y1029732D01*
X1542527Y1030464D01*
X1542669Y1030323D01*
G37*
G36*
G01X1542485Y1030705D02*
X1542303Y1031088D01*
X1542833Y1031619D01*
X1543217Y1031437D01*
X1543358Y1031295D01*
X1542626Y1030563D01*
X1542485Y1030705D01*
G37*
G36*
G01X1543256Y1046195D02*
X1543438Y1045811D01*
X1542908Y1045281D01*
X1542524Y1045463D01*
X1542383Y1045605D01*
X1543114Y1046336D01*
X1543256Y1046195D01*
G37*
G36*
G01X1543072Y1046577D02*
X1542890Y1046960D01*
X1543420Y1047491D01*
X1543804Y1047309D01*
X1543945Y1047167D01*
X1543213Y1046435D01*
X1543072Y1046577D01*
G37*
G36*
G01X1543921Y1045728D02*
X1543739Y1046111D01*
X1544269Y1046642D01*
X1544653Y1046460D01*
X1544794Y1046318D01*
X1544062Y1045586D01*
X1543921Y1045728D01*
G37*
G36*
G01X1544105Y1045346D02*
X1544287Y1044962D01*
X1543757Y1044432D01*
X1543373Y1044614D01*
X1543232Y1044756D01*
X1543963Y1045487D01*
X1544105Y1045346D01*
G37*
G36*
G01X1542259Y1044066D02*
X1542077Y1044450D01*
X1542608Y1044980D01*
X1542991Y1044798D01*
X1543133Y1044657D01*
X1542401Y1043925D01*
X1542259Y1044066D01*
G37*
G36*
G01X1545767Y1047008D02*
X1545949Y1046624D01*
X1545418Y1046094D01*
X1545035Y1046276D01*
X1544893Y1046417D01*
X1545625Y1047149D01*
X1545767Y1047008D01*
G37*
G36*
G01X1548246Y1041560D02*
X1548064Y1041944D01*
X1548595Y1042474D01*
X1548978Y1042292D01*
X1549120Y1042151D01*
X1548388Y1041419D01*
X1548246Y1041560D01*
G37*
G36*
G01X1546769Y1039517D02*
X1546951Y1039133D01*
X1546420Y1038603D01*
X1546037Y1038785D01*
X1545895Y1038926D01*
X1546627Y1039658D01*
X1546769Y1039517D01*
G37*
G36*
G01X1548430Y1041178D02*
X1548612Y1040795D01*
X1548082Y1040264D01*
X1547698Y1040447D01*
X1547557Y1040588D01*
X1548289Y1041320D01*
X1548430Y1041178D01*
G37*
G36*
G01X1546585Y1039899D02*
X1546403Y1040282D01*
X1546933Y1040812D01*
X1547317Y1040630D01*
X1547458Y1040489D01*
X1546726Y1039757D01*
X1546585Y1039899D01*
G37*
G36*
G01X1544923Y1038237D02*
X1544741Y1038620D01*
X1545271Y1039151D01*
X1545655Y1038969D01*
X1545796Y1038827D01*
X1545064Y1038095D01*
X1544923Y1038237D01*
G37*
G36*
G01X1550092Y1042840D02*
X1550274Y1042456D01*
X1549744Y1041926D01*
X1549360Y1042108D01*
X1549219Y1042250D01*
X1549951Y1042982D01*
X1550092Y1042840D01*
G37*
G36*
G01X1551754Y1044502D02*
X1551936Y1044118D01*
X1551405Y1043588D01*
X1551022Y1043770D01*
X1550880Y1043911D01*
X1551612Y1044643D01*
X1551754Y1044502D01*
G37*
G36*
G01X1549908Y1043222D02*
X1549726Y1043606D01*
X1550256Y1044136D01*
X1550640Y1043954D01*
X1550781Y1043812D01*
X1550050Y1043081D01*
X1549908Y1043222D01*
G37*
G36*
G01X1545107Y1037855D02*
X1545289Y1037471D01*
X1544759Y1036941D01*
X1544375Y1037123D01*
X1544234Y1037265D01*
X1544965Y1037996D01*
X1545107Y1037855D01*
G37*
G36*
G01X1543261Y1036575D02*
X1543079Y1036959D01*
X1543610Y1037489D01*
X1543993Y1037307D01*
X1544135Y1037166D01*
X1543403Y1036434D01*
X1543261Y1036575D01*
G37*
G36*
G01X1543445Y1036193D02*
X1543627Y1035810D01*
X1543097Y1035279D01*
X1542713Y1035461D01*
X1542572Y1035603D01*
X1543304Y1036335D01*
X1543445Y1036193D01*
G37*
G36*
G01X1551570Y1044884D02*
X1551388Y1045267D01*
X1551918Y1045798D01*
X1552302Y1045615D01*
X1552443Y1045474D01*
X1551711Y1044742D01*
X1551570Y1044884D01*
G37*
G36*
G01X1555077Y1047825D02*
X1555259Y1047442D01*
X1554729Y1046911D01*
X1554345Y1047093D01*
X1554204Y1047235D01*
X1554936Y1047967D01*
X1555077Y1047825D01*
G37*
G36*
G01X1553415Y1046164D02*
X1553597Y1045780D01*
X1553067Y1045250D01*
X1552683Y1045432D01*
X1552542Y1045573D01*
X1553274Y1046305D01*
X1553415Y1046164D01*
G37*
G36*
G01X1553232Y1046545D02*
X1553049Y1046929D01*
X1553580Y1047459D01*
X1553963Y1047277D01*
X1554105Y1047136D01*
X1553373Y1046404D01*
X1553232Y1046545D01*
G37*
G36*
G01X1543481Y1032834D02*
X1543664Y1032450D01*
X1543133Y1031920D01*
X1542750Y1032102D01*
X1542608Y1032243D01*
X1543340Y1032975D01*
X1543481Y1032834D01*
G37*
G36*
G01X1543298Y1033215D02*
X1543116Y1033599D01*
X1543646Y1034129D01*
X1544029Y1033947D01*
X1544171Y1033806D01*
X1543439Y1033074D01*
X1543298Y1033215D01*
G37*
G36*
G01X1545143Y1034495D02*
X1545325Y1034112D01*
X1544795Y1033581D01*
X1544411Y1033763D01*
X1544270Y1033905D01*
X1545002Y1034637D01*
X1545143Y1034495D01*
G37*
G36*
G01X1544959Y1034877D02*
X1544777Y1035261D01*
X1545308Y1035791D01*
X1545691Y1035609D01*
X1545833Y1035468D01*
X1545101Y1034736D01*
X1544959Y1034877D01*
G37*
G36*
G01X1551790Y1041142D02*
X1551972Y1040758D01*
X1551442Y1040228D01*
X1551058Y1040410D01*
X1550917Y1040552D01*
X1551649Y1041284D01*
X1551790Y1041142D01*
G37*
G36*
G01X1550128Y1039480D02*
X1550310Y1039097D01*
X1549780Y1038566D01*
X1549396Y1038749D01*
X1549255Y1038890D01*
X1549987Y1039622D01*
X1550128Y1039480D01*
G37*
G36*
G01X1548283Y1038201D02*
X1548101Y1038584D01*
X1548631Y1039114D01*
X1549015Y1038932D01*
X1549156Y1038791D01*
X1548424Y1038059D01*
X1548283Y1038201D01*
G37*
G36*
G01X1549944Y1039862D02*
X1549762Y1040246D01*
X1550293Y1040776D01*
X1550676Y1040594D01*
X1550818Y1040453D01*
X1550086Y1039721D01*
X1549944Y1039862D01*
G37*
G36*
G01X1546805Y1036157D02*
X1546987Y1035773D01*
X1546457Y1035243D01*
X1546073Y1035425D01*
X1545932Y1035567D01*
X1546663Y1036298D01*
X1546805Y1036157D01*
G37*
G36*
G01X1548467Y1037819D02*
X1548649Y1037435D01*
X1548118Y1036905D01*
X1547735Y1037087D01*
X1547593Y1037228D01*
X1548325Y1037960D01*
X1548467Y1037819D01*
G37*
G36*
G01X1546621Y1036539D02*
X1546439Y1036922D01*
X1546969Y1037453D01*
X1547353Y1037271D01*
X1547494Y1037129D01*
X1546762Y1036397D01*
X1546621Y1036539D01*
G37*
G36*
G01X1551606Y1041524D02*
X1551424Y1041908D01*
X1551954Y1042438D01*
X1552338Y1042256D01*
X1552479Y1042114D01*
X1551748Y1041383D01*
X1551606Y1041524D01*
G37*
G36*
G01X1556775Y1046127D02*
X1556957Y1045744D01*
X1556427Y1045213D01*
X1556043Y1045395D01*
X1555902Y1045537D01*
X1556634Y1046269D01*
X1556775Y1046127D01*
G37*
G36*
G01X1554930Y1044847D02*
X1554747Y1045231D01*
X1555278Y1045761D01*
X1555661Y1045579D01*
X1555803Y1045438D01*
X1555071Y1044706D01*
X1554930Y1044847D01*
G37*
G36*
G01X1555113Y1044466D02*
X1555295Y1044082D01*
X1554765Y1043552D01*
X1554381Y1043734D01*
X1554240Y1043875D01*
X1554972Y1044607D01*
X1555113Y1044466D01*
G37*
G36*
G01X1558437Y1047789D02*
X1558619Y1047405D01*
X1558089Y1046875D01*
X1557705Y1047057D01*
X1557563Y1047198D01*
X1558295Y1047930D01*
X1558437Y1047789D01*
G37*
G36*
G01X1556591Y1046509D02*
X1556409Y1046893D01*
X1556939Y1047423D01*
X1557323Y1047241D01*
X1557464Y1047099D01*
X1556733Y1046368D01*
X1556591Y1046509D01*
G37*
G36*
G01X1553452Y1042804D02*
X1553634Y1042420D01*
X1553103Y1041890D01*
X1552720Y1042072D01*
X1552578Y1042213D01*
X1553310Y1042945D01*
X1553452Y1042804D01*
G37*
G36*
G01X1553268Y1043186D02*
X1553086Y1043569D01*
X1553616Y1044100D01*
X1554000Y1043917D01*
X1554141Y1043776D01*
X1553409Y1043044D01*
X1553268Y1043186D01*
G37*
G36*
G01X1542632Y1033683D02*
X1542815Y1033299D01*
X1542284Y1032769D01*
X1541901Y1032951D01*
X1541759Y1033092D01*
X1542491Y1033824D01*
X1542632Y1033683D01*
G37*
G36*
G01X1544294Y1035344D02*
X1544476Y1034961D01*
X1543946Y1034430D01*
X1543562Y1034612D01*
X1543421Y1034754D01*
X1544153Y1035486D01*
X1544294Y1035344D01*
G37*
G36*
G01X1542449Y1034064D02*
X1542267Y1034448D01*
X1542797Y1034978D01*
X1543180Y1034796D01*
X1543322Y1034655D01*
X1542590Y1033923D01*
X1542449Y1034064D01*
G37*
G36*
G01X1549279Y1040329D02*
X1549461Y1039946D01*
X1548931Y1039415D01*
X1548547Y1039598D01*
X1548406Y1039739D01*
X1549138Y1040471D01*
X1549279Y1040329D01*
G37*
G36*
G01X1550941Y1041991D02*
X1551123Y1041607D01*
X1550593Y1041077D01*
X1550209Y1041259D01*
X1550068Y1041401D01*
X1550800Y1042133D01*
X1550941Y1041991D01*
G37*
G36*
G01X1547434Y1039050D02*
X1547252Y1039433D01*
X1547782Y1039963D01*
X1548166Y1039781D01*
X1548307Y1039640D01*
X1547575Y1038908D01*
X1547434Y1039050D01*
G37*
G36*
G01X1549095Y1040711D02*
X1548913Y1041095D01*
X1549444Y1041625D01*
X1549827Y1041443D01*
X1549969Y1041302D01*
X1549237Y1040570D01*
X1549095Y1040711D01*
G37*
G36*
G01X1550757Y1042373D02*
X1550575Y1042757D01*
X1551105Y1043287D01*
X1551489Y1043105D01*
X1551630Y1042963D01*
X1550899Y1042232D01*
X1550757Y1042373D01*
G37*
G36*
G01X1544110Y1035726D02*
X1543928Y1036110D01*
X1544459Y1036640D01*
X1544842Y1036458D01*
X1544984Y1036317D01*
X1544252Y1035585D01*
X1544110Y1035726D01*
G37*
G36*
G01X1545956Y1037006D02*
X1546138Y1036622D01*
X1545608Y1036092D01*
X1545224Y1036274D01*
X1545083Y1036416D01*
X1545814Y1037147D01*
X1545956Y1037006D01*
G37*
G36*
G01X1545772Y1037388D02*
X1545590Y1037771D01*
X1546120Y1038302D01*
X1546504Y1038120D01*
X1546645Y1037978D01*
X1545913Y1037246D01*
X1545772Y1037388D01*
G37*
G36*
G01X1547618Y1038668D02*
X1547800Y1038284D01*
X1547269Y1037754D01*
X1546886Y1037936D01*
X1546744Y1038077D01*
X1547476Y1038809D01*
X1547618Y1038668D01*
G37*
G36*
G01X1552603Y1043653D02*
X1552785Y1043269D01*
X1552254Y1042739D01*
X1551871Y1042921D01*
X1551729Y1043062D01*
X1552461Y1043794D01*
X1552603Y1043653D01*
G37*
G36*
G01X1552419Y1044035D02*
X1552237Y1044418D01*
X1552767Y1044949D01*
X1553151Y1044766D01*
X1553292Y1044625D01*
X1552560Y1043893D01*
X1552419Y1044035D01*
G37*
G36*
G01X1554081Y1045696D02*
X1553898Y1046080D01*
X1554429Y1046610D01*
X1554812Y1046428D01*
X1554954Y1046287D01*
X1554222Y1045555D01*
X1554081Y1045696D01*
G37*
G36*
G01X1555926Y1046976D02*
X1556108Y1046593D01*
X1555578Y1046062D01*
X1555194Y1046244D01*
X1555053Y1046386D01*
X1555785Y1047118D01*
X1555926Y1046976D01*
G37*
G36*
G01X1554264Y1045315D02*
X1554446Y1044931D01*
X1553916Y1044401D01*
X1553532Y1044583D01*
X1553391Y1044724D01*
X1554123Y1045456D01*
X1554264Y1045315D01*
G37*
G36*
G01X1544147Y1032366D02*
X1543965Y1032750D01*
X1544495Y1033280D01*
X1544878Y1033098D01*
X1545020Y1032957D01*
X1544288Y1032225D01*
X1544147Y1032366D01*
G37*
G36*
G01X1544330Y1031985D02*
X1544513Y1031601D01*
X1543982Y1031071D01*
X1543599Y1031253D01*
X1543457Y1031394D01*
X1544189Y1032126D01*
X1544330Y1031985D01*
G37*
G36*
G01X1545992Y1033646D02*
X1546174Y1033263D01*
X1545644Y1032732D01*
X1545260Y1032914D01*
X1545119Y1033056D01*
X1545851Y1033788D01*
X1545992Y1033646D01*
G37*
G36*
G01X1545808Y1034028D02*
X1545626Y1034412D01*
X1546157Y1034942D01*
X1546540Y1034760D01*
X1546682Y1034619D01*
X1545950Y1033887D01*
X1545808Y1034028D01*
G37*
G36*
G01X1547654Y1035308D02*
X1547836Y1034924D01*
X1547306Y1034394D01*
X1546922Y1034576D01*
X1546781Y1034718D01*
X1547512Y1035449D01*
X1547654Y1035308D01*
G37*
G36*
G01X1550793Y1039013D02*
X1550611Y1039397D01*
X1551142Y1039927D01*
X1551525Y1039745D01*
X1551667Y1039604D01*
X1550935Y1038872D01*
X1550793Y1039013D01*
G37*
G36*
G01X1547470Y1035690D02*
X1547288Y1036073D01*
X1547818Y1036604D01*
X1548202Y1036422D01*
X1548343Y1036280D01*
X1547611Y1035548D01*
X1547470Y1035690D01*
G37*
G36*
G01X1549132Y1037352D02*
X1548950Y1037735D01*
X1549480Y1038265D01*
X1549864Y1038083D01*
X1550005Y1037942D01*
X1549273Y1037210D01*
X1549132Y1037352D01*
G37*
G36*
G01X1549316Y1036970D02*
X1549498Y1036586D01*
X1548967Y1036056D01*
X1548584Y1036238D01*
X1548442Y1036379D01*
X1549174Y1037111D01*
X1549316Y1036970D01*
G37*
G36*
G01X1550977Y1038631D02*
X1551159Y1038248D01*
X1550629Y1037717D01*
X1550245Y1037900D01*
X1550104Y1038041D01*
X1550836Y1038773D01*
X1550977Y1038631D01*
G37*
G36*
G01X1557624Y1045278D02*
X1557806Y1044895D01*
X1557276Y1044364D01*
X1556892Y1044546D01*
X1556751Y1044688D01*
X1557483Y1045420D01*
X1557624Y1045278D01*
G37*
G36*
G01X1555779Y1043998D02*
X1555596Y1044382D01*
X1556127Y1044912D01*
X1556510Y1044730D01*
X1556652Y1044589D01*
X1555920Y1043857D01*
X1555779Y1043998D01*
G37*
G36*
G01X1555962Y1043617D02*
X1556144Y1043233D01*
X1555614Y1042703D01*
X1555230Y1042885D01*
X1555089Y1043026D01*
X1555821Y1043758D01*
X1555962Y1043617D01*
G37*
G36*
G01X1557440Y1045660D02*
X1557258Y1046044D01*
X1557788Y1046574D01*
X1558172Y1046392D01*
X1558313Y1046250D01*
X1557582Y1045519D01*
X1557440Y1045660D01*
G37*
G36*
G01X1552455Y1040675D02*
X1552273Y1041059D01*
X1552803Y1041589D01*
X1553187Y1041407D01*
X1553328Y1041265D01*
X1552597Y1040534D01*
X1552455Y1040675D01*
G37*
G36*
G01X1554301Y1041955D02*
X1554483Y1041571D01*
X1553952Y1041041D01*
X1553569Y1041223D01*
X1553427Y1041364D01*
X1554159Y1042096D01*
X1554301Y1041955D01*
G37*
G36*
G01X1552639Y1040293D02*
X1552821Y1039909D01*
X1552291Y1039379D01*
X1551907Y1039561D01*
X1551766Y1039703D01*
X1552498Y1040435D01*
X1552639Y1040293D01*
G37*
G36*
G01X1554117Y1042337D02*
X1553935Y1042720D01*
X1554465Y1043251D01*
X1554849Y1043068D01*
X1554990Y1042927D01*
X1554258Y1042195D01*
X1554117Y1042337D01*
G37*
G36*
G01X1543036Y1049937D02*
X1542854Y1050320D01*
X1543384Y1050851D01*
X1543768Y1050668D01*
X1543909Y1050527D01*
X1543177Y1049795D01*
X1543036Y1049937D01*
G37*
G36*
G01X1544881Y1051216D02*
X1545063Y1050833D01*
X1544533Y1050303D01*
X1544149Y1050485D01*
X1544008Y1050626D01*
X1544740Y1051358D01*
X1544881Y1051216D01*
G37*
G36*
G01X1543220Y1049555D02*
X1543402Y1049171D01*
X1542871Y1048641D01*
X1542488Y1048823D01*
X1542346Y1048964D01*
X1543078Y1049696D01*
X1543220Y1049555D01*
G37*
G36*
G01X1544697Y1051598D02*
X1544515Y1051982D01*
X1545046Y1052512D01*
X1545429Y1052330D01*
X1545571Y1052189D01*
X1544839Y1051457D01*
X1544697Y1051598D01*
G37*
G36*
G01X1546359Y1053260D02*
X1546177Y1053644D01*
X1546707Y1054174D01*
X1547091Y1053992D01*
X1547232Y1053850D01*
X1546501Y1053119D01*
X1546359Y1053260D01*
G37*
G36*
G01X1548021Y1054922D02*
X1547839Y1055305D01*
X1548369Y1055836D01*
X1548753Y1055654D01*
X1548894Y1055512D01*
X1548162Y1054780D01*
X1548021Y1054922D01*
G37*
G36*
G01X1549683Y1056583D02*
X1549500Y1056967D01*
X1550031Y1057497D01*
X1550414Y1057315D01*
X1550556Y1057174D01*
X1549824Y1056442D01*
X1549683Y1056583D01*
G37*
G36*
G01X1549866Y1056202D02*
X1550048Y1055818D01*
X1549518Y1055288D01*
X1549135Y1055470D01*
X1548993Y1055611D01*
X1549725Y1056343D01*
X1549866Y1056202D01*
G37*
G36*
G01X1548205Y1054540D02*
X1548387Y1054156D01*
X1547856Y1053626D01*
X1547473Y1053808D01*
X1547331Y1053949D01*
X1548063Y1054681D01*
X1548205Y1054540D01*
G37*
G36*
G01X1551528Y1057863D02*
X1551710Y1057480D01*
X1551180Y1056949D01*
X1550796Y1057131D01*
X1550655Y1057273D01*
X1551387Y1058005D01*
X1551528Y1057863D01*
G37*
G36*
G01X1546543Y1052878D02*
X1546725Y1052495D01*
X1546195Y1051964D01*
X1545811Y1052146D01*
X1545670Y1052288D01*
X1546402Y1053020D01*
X1546543Y1052878D01*
G37*
G36*
G01X1551344Y1058245D02*
X1551162Y1058629D01*
X1551693Y1059159D01*
X1552076Y1058977D01*
X1552218Y1058836D01*
X1551486Y1058104D01*
X1551344Y1058245D01*
G37*
G36*
G01X1556329Y1063230D02*
X1556147Y1063614D01*
X1556678Y1064144D01*
X1557061Y1063962D01*
X1557203Y1063821D01*
X1556471Y1063089D01*
X1556329Y1063230D01*
G37*
G36*
G01X1554852Y1061187D02*
X1555034Y1060803D01*
X1554503Y1060273D01*
X1554120Y1060455D01*
X1553978Y1060596D01*
X1554710Y1061328D01*
X1554852Y1061187D01*
G37*
G36*
G01X1554668Y1061568D02*
X1554486Y1061952D01*
X1555016Y1062482D01*
X1555400Y1062300D01*
X1555541Y1062159D01*
X1554809Y1061427D01*
X1554668Y1061568D01*
G37*
G36*
G01X1556513Y1062848D02*
X1556695Y1062465D01*
X1556165Y1061934D01*
X1555781Y1062117D01*
X1555640Y1062258D01*
X1556372Y1062990D01*
X1556513Y1062848D01*
G37*
G36*
G01X1553006Y1059907D02*
X1552824Y1060290D01*
X1553354Y1060821D01*
X1553738Y1060639D01*
X1553879Y1060497D01*
X1553147Y1059765D01*
X1553006Y1059907D01*
G37*
G36*
G01X1553190Y1059525D02*
X1553372Y1059141D01*
X1552842Y1058611D01*
X1552458Y1058793D01*
X1552317Y1058935D01*
X1553048Y1059666D01*
X1553190Y1059525D01*
G37*
G36*
G01X1546395Y1049900D02*
X1546213Y1050284D01*
X1546744Y1050814D01*
X1547127Y1050632D01*
X1547269Y1050491D01*
X1546537Y1049759D01*
X1546395Y1049900D01*
G37*
G36*
G01X1548057Y1051562D02*
X1547875Y1051946D01*
X1548405Y1052476D01*
X1548789Y1052294D01*
X1548930Y1052152D01*
X1548199Y1051421D01*
X1548057Y1051562D01*
G37*
G36*
G01X1548241Y1051180D02*
X1548423Y1050797D01*
X1547893Y1050266D01*
X1547509Y1050448D01*
X1547368Y1050590D01*
X1548100Y1051322D01*
X1548241Y1051180D01*
G37*
G36*
G01X1549903Y1052842D02*
X1550085Y1052458D01*
X1549554Y1051928D01*
X1549171Y1052110D01*
X1549029Y1052251D01*
X1549761Y1052983D01*
X1549903Y1052842D01*
G37*
G36*
G01X1551564Y1054504D02*
X1551746Y1054120D01*
X1551216Y1053590D01*
X1550833Y1053772D01*
X1550691Y1053913D01*
X1551423Y1054645D01*
X1551564Y1054504D01*
G37*
G36*
G01X1551381Y1054885D02*
X1551198Y1055269D01*
X1551729Y1055799D01*
X1552112Y1055617D01*
X1552254Y1055476D01*
X1551522Y1054744D01*
X1551381Y1054885D01*
G37*
G36*
G01X1549719Y1053224D02*
X1549537Y1053607D01*
X1550067Y1054138D01*
X1550451Y1053956D01*
X1550592Y1053814D01*
X1549860Y1053082D01*
X1549719Y1053224D01*
G37*
G36*
G01X1544918Y1047857D02*
X1545100Y1047473D01*
X1544569Y1046943D01*
X1544186Y1047125D01*
X1544044Y1047266D01*
X1544776Y1047998D01*
X1544918Y1047857D01*
G37*
G36*
G01X1546579Y1049518D02*
X1546761Y1049135D01*
X1546231Y1048605D01*
X1545847Y1048787D01*
X1545706Y1048928D01*
X1546438Y1049660D01*
X1546579Y1049518D01*
G37*
G36*
G01X1544734Y1048239D02*
X1544552Y1048622D01*
X1545082Y1049153D01*
X1545466Y1048970D01*
X1545607Y1048829D01*
X1544875Y1048097D01*
X1544734Y1048239D01*
G37*
G36*
G01X1556550Y1059489D02*
X1556732Y1059105D01*
X1556201Y1058575D01*
X1555818Y1058757D01*
X1555676Y1058898D01*
X1556408Y1059630D01*
X1556550Y1059489D01*
G37*
G36*
G01X1556366Y1059870D02*
X1556184Y1060254D01*
X1556714Y1060784D01*
X1557098Y1060602D01*
X1557239Y1060461D01*
X1556507Y1059729D01*
X1556366Y1059870D01*
G37*
G36*
G01X1553226Y1056165D02*
X1553408Y1055782D01*
X1552878Y1055251D01*
X1552494Y1055433D01*
X1552353Y1055575D01*
X1553085Y1056307D01*
X1553226Y1056165D01*
G37*
G36*
G01X1553042Y1056547D02*
X1552860Y1056931D01*
X1553391Y1057461D01*
X1553774Y1057279D01*
X1553916Y1057138D01*
X1553184Y1056406D01*
X1553042Y1056547D01*
G37*
G36*
G01X1554888Y1057827D02*
X1555070Y1057443D01*
X1554540Y1056913D01*
X1554156Y1057095D01*
X1554015Y1057237D01*
X1554746Y1057968D01*
X1554888Y1057827D01*
G37*
G36*
G01X1554704Y1058209D02*
X1554522Y1058592D01*
X1555052Y1059123D01*
X1555436Y1058941D01*
X1555577Y1058799D01*
X1554845Y1058067D01*
X1554704Y1058209D01*
G37*
G36*
G01X1558027Y1061532D02*
X1557845Y1061916D01*
X1558376Y1062446D01*
X1558759Y1062264D01*
X1558901Y1062123D01*
X1558169Y1061391D01*
X1558027Y1061532D01*
G37*
G36*
G01X1558211Y1061150D02*
X1558393Y1060767D01*
X1557863Y1060236D01*
X1557479Y1060419D01*
X1557338Y1060560D01*
X1558070Y1061292D01*
X1558211Y1061150D01*
G37*
G36*
G01X1543885Y1049088D02*
X1543703Y1049471D01*
X1544233Y1050002D01*
X1544617Y1049819D01*
X1544758Y1049678D01*
X1544026Y1048946D01*
X1543885Y1049088D01*
G37*
G36*
G01X1544069Y1048706D02*
X1544251Y1048322D01*
X1543720Y1047792D01*
X1543337Y1047974D01*
X1543195Y1048115D01*
X1543927Y1048847D01*
X1544069Y1048706D01*
G37*
G36*
G01X1542223Y1047426D02*
X1542041Y1047809D01*
X1542571Y1048340D01*
X1542955Y1048158D01*
X1543096Y1048016D01*
X1542364Y1047284D01*
X1542223Y1047426D01*
G37*
G36*
G01X1545546Y1050749D02*
X1545364Y1051133D01*
X1545895Y1051663D01*
X1546278Y1051481D01*
X1546420Y1051340D01*
X1545688Y1050608D01*
X1545546Y1050749D01*
G37*
G36*
G01X1547392Y1052029D02*
X1547574Y1051646D01*
X1547044Y1051115D01*
X1546660Y1051297D01*
X1546519Y1051439D01*
X1547251Y1052171D01*
X1547392Y1052029D01*
G37*
G36*
G01X1545730Y1050367D02*
X1545912Y1049984D01*
X1545382Y1049454D01*
X1544998Y1049636D01*
X1544857Y1049777D01*
X1545589Y1050509D01*
X1545730Y1050367D01*
G37*
G36*
G01X1548870Y1054073D02*
X1548688Y1054456D01*
X1549218Y1054987D01*
X1549602Y1054805D01*
X1549743Y1054663D01*
X1549011Y1053931D01*
X1548870Y1054073D01*
G37*
G36*
G01X1550532Y1055734D02*
X1550349Y1056118D01*
X1550880Y1056648D01*
X1551263Y1056466D01*
X1551405Y1056325D01*
X1550673Y1055593D01*
X1550532Y1055734D01*
G37*
G36*
G01X1550715Y1055353D02*
X1550897Y1054969D01*
X1550367Y1054439D01*
X1549984Y1054621D01*
X1549842Y1054762D01*
X1550574Y1055494D01*
X1550715Y1055353D01*
G37*
G36*
G01X1547208Y1052411D02*
X1547026Y1052795D01*
X1547556Y1053325D01*
X1547940Y1053143D01*
X1548081Y1053001D01*
X1547350Y1052270D01*
X1547208Y1052411D01*
G37*
G36*
G01X1549054Y1053691D02*
X1549236Y1053307D01*
X1548705Y1052777D01*
X1548322Y1052959D01*
X1548180Y1053100D01*
X1548912Y1053832D01*
X1549054Y1053691D01*
G37*
G36*
G01X1552377Y1057014D02*
X1552559Y1056631D01*
X1552029Y1056100D01*
X1551645Y1056282D01*
X1551504Y1056424D01*
X1552236Y1057156D01*
X1552377Y1057014D01*
G37*
G36*
G01X1557178Y1062381D02*
X1556996Y1062765D01*
X1557527Y1063295D01*
X1557910Y1063113D01*
X1558052Y1062972D01*
X1557320Y1062240D01*
X1557178Y1062381D01*
G37*
G36*
G01X1554039Y1058676D02*
X1554221Y1058292D01*
X1553691Y1057762D01*
X1553307Y1057944D01*
X1553166Y1058086D01*
X1553897Y1058817D01*
X1554039Y1058676D01*
G37*
G36*
G01X1552193Y1057396D02*
X1552011Y1057780D01*
X1552542Y1058310D01*
X1552925Y1058128D01*
X1553067Y1057987D01*
X1552335Y1057255D01*
X1552193Y1057396D01*
G37*
G36*
G01X1555517Y1060719D02*
X1555335Y1061103D01*
X1555865Y1061633D01*
X1556249Y1061451D01*
X1556390Y1061310D01*
X1555658Y1060578D01*
X1555517Y1060719D01*
G37*
G36*
G01X1557362Y1061999D02*
X1557544Y1061616D01*
X1557014Y1061085D01*
X1556630Y1061268D01*
X1556489Y1061409D01*
X1557221Y1062141D01*
X1557362Y1061999D01*
G37*
G36*
G01X1553855Y1059058D02*
X1553673Y1059441D01*
X1554203Y1059972D01*
X1554587Y1059790D01*
X1554728Y1059648D01*
X1553996Y1058916D01*
X1553855Y1059058D01*
G37*
G36*
G01X1555701Y1060338D02*
X1555883Y1059954D01*
X1555352Y1059424D01*
X1554969Y1059606D01*
X1554827Y1059747D01*
X1555559Y1060479D01*
X1555701Y1060338D01*
G37*
G36*
G01X1550752Y1051993D02*
X1550934Y1051609D01*
X1550403Y1051079D01*
X1550020Y1051261D01*
X1549878Y1051402D01*
X1550610Y1052134D01*
X1550752Y1051993D01*
G37*
G36*
G01X1547244Y1049051D02*
X1547062Y1049435D01*
X1547593Y1049965D01*
X1547976Y1049783D01*
X1548118Y1049642D01*
X1547386Y1048910D01*
X1547244Y1049051D01*
G37*
G36*
G01X1549090Y1050331D02*
X1549272Y1049948D01*
X1548742Y1049417D01*
X1548358Y1049599D01*
X1548217Y1049741D01*
X1548949Y1050473D01*
X1549090Y1050331D01*
G37*
G36*
G01X1547428Y1048669D02*
X1547610Y1048286D01*
X1547080Y1047756D01*
X1546696Y1047938D01*
X1546555Y1048079D01*
X1547287Y1048811D01*
X1547428Y1048669D01*
G37*
G36*
G01X1548906Y1050713D02*
X1548724Y1051097D01*
X1549254Y1051627D01*
X1549638Y1051445D01*
X1549779Y1051303D01*
X1549048Y1050572D01*
X1548906Y1050713D01*
G37*
G36*
G01X1545583Y1047390D02*
X1545401Y1047773D01*
X1545931Y1048304D01*
X1546315Y1048121D01*
X1546456Y1047980D01*
X1545724Y1047248D01*
X1545583Y1047390D01*
G37*
G36*
G01X1550568Y1052375D02*
X1550386Y1052758D01*
X1550916Y1053289D01*
X1551300Y1053107D01*
X1551441Y1052965D01*
X1550709Y1052233D01*
X1550568Y1052375D01*
G37*
G36*
G01X1552413Y1053655D02*
X1552595Y1053271D01*
X1552065Y1052741D01*
X1551682Y1052923D01*
X1551540Y1053064D01*
X1552272Y1053796D01*
X1552413Y1053655D01*
G37*
G36*
G01X1557215Y1059021D02*
X1557033Y1059405D01*
X1557563Y1059935D01*
X1557947Y1059753D01*
X1558088Y1059612D01*
X1557356Y1058880D01*
X1557215Y1059021D01*
G37*
G36*
G01X1553891Y1055698D02*
X1553709Y1056082D01*
X1554240Y1056612D01*
X1554623Y1056430D01*
X1554765Y1056289D01*
X1554033Y1055557D01*
X1553891Y1055698D01*
G37*
G36*
G01X1555737Y1056978D02*
X1555919Y1056594D01*
X1555389Y1056064D01*
X1555005Y1056246D01*
X1554864Y1056388D01*
X1555595Y1057119D01*
X1555737Y1056978D01*
G37*
G36*
G01X1555553Y1057360D02*
X1555371Y1057743D01*
X1555901Y1058274D01*
X1556285Y1058092D01*
X1556426Y1057950D01*
X1555694Y1057218D01*
X1555553Y1057360D01*
G37*
G36*
G01X1557399Y1058640D02*
X1557581Y1058256D01*
X1557050Y1057726D01*
X1556667Y1057908D01*
X1556525Y1058049D01*
X1557257Y1058781D01*
X1557399Y1058640D01*
G37*
G36*
G01X1554075Y1055316D02*
X1554257Y1054933D01*
X1553727Y1054402D01*
X1553343Y1054584D01*
X1553202Y1054726D01*
X1553934Y1055458D01*
X1554075Y1055316D01*
G37*
G36*
G01X1552230Y1054036D02*
X1552047Y1054420D01*
X1552578Y1054950D01*
X1552961Y1054768D01*
X1553103Y1054627D01*
X1552371Y1053895D01*
X1552230Y1054036D01*
G37*
G36*
G01X1558400Y1051149D02*
X1558583Y1050765D01*
X1558052Y1050235D01*
X1557669Y1050417D01*
X1557527Y1050558D01*
X1558259Y1051290D01*
X1558400Y1051149D01*
G37*
G36*
G01X1556739Y1049487D02*
X1556921Y1049103D01*
X1556391Y1048573D01*
X1556007Y1048755D01*
X1555865Y1048896D01*
X1556597Y1049628D01*
X1556739Y1049487D01*
G37*
G36*
G01X1554893Y1048207D02*
X1554711Y1048591D01*
X1555241Y1049121D01*
X1555625Y1048939D01*
X1555766Y1048797D01*
X1555035Y1048066D01*
X1554893Y1048207D01*
G37*
G36*
G01X1556555Y1049869D02*
X1556373Y1050252D01*
X1556903Y1050783D01*
X1557287Y1050601D01*
X1557428Y1050459D01*
X1556696Y1049727D01*
X1556555Y1049869D01*
G37*
G36*
G01X1557588Y1048638D02*
X1557770Y1048254D01*
X1557240Y1047724D01*
X1556856Y1047906D01*
X1556714Y1048047D01*
X1557446Y1048779D01*
X1557588Y1048638D01*
G37*
G36*
G01X1555742Y1047358D02*
X1555560Y1047742D01*
X1556090Y1048272D01*
X1556474Y1048090D01*
X1556615Y1047948D01*
X1555884Y1047217D01*
X1555742Y1047358D01*
G37*
G36*
G01X1557404Y1049020D02*
X1557222Y1049403D01*
X1557752Y1049934D01*
X1558136Y1049752D01*
X1558277Y1049610D01*
X1557545Y1048878D01*
X1557404Y1049020D01*
G37*
G36*
G01X1544164Y1058581D02*
X1544346Y1058197D01*
X1543815Y1057667D01*
X1543432Y1057849D01*
X1543290Y1057990D01*
X1544022Y1058722D01*
X1544164Y1058581D01*
G37*
G36*
G01X1542318Y1057301D02*
X1542136Y1057685D01*
X1542666Y1058215D01*
X1543050Y1058033D01*
X1543191Y1057891D01*
X1542460Y1057160D01*
X1542318Y1057301D01*
G37*
G36*
G01X1543980Y1058963D02*
X1543798Y1059346D01*
X1544328Y1059877D01*
X1544712Y1059695D01*
X1544853Y1059553D01*
X1544121Y1058821D01*
X1543980Y1058963D01*
G37*
G36*
G01X1549149Y1063566D02*
X1549331Y1063182D01*
X1548801Y1062652D01*
X1548417Y1062834D01*
X1548276Y1062976D01*
X1549007Y1063707D01*
X1549149Y1063566D01*
G37*
G36*
G01X1547303Y1062286D02*
X1547121Y1062670D01*
X1547652Y1063200D01*
X1548035Y1063018D01*
X1548177Y1062877D01*
X1547445Y1062145D01*
X1547303Y1062286D01*
G37*
G36*
G01X1545825Y1060243D02*
X1546007Y1059859D01*
X1545477Y1059329D01*
X1545094Y1059511D01*
X1544952Y1059652D01*
X1545684Y1060384D01*
X1545825Y1060243D01*
G37*
G36*
G01X1545642Y1060624D02*
X1545459Y1061008D01*
X1545990Y1061538D01*
X1546373Y1061356D01*
X1546515Y1061215D01*
X1545783Y1060483D01*
X1545642Y1060624D01*
G37*
G36*
G01X1547487Y1061904D02*
X1547669Y1061521D01*
X1547139Y1060990D01*
X1546755Y1061172D01*
X1546614Y1061314D01*
X1547346Y1062046D01*
X1547487Y1061904D01*
G37*
G36*
G01X1544017Y1055602D02*
X1543835Y1055986D01*
X1544365Y1056516D01*
X1544749Y1056334D01*
X1544890Y1056193D01*
X1544158Y1055461D01*
X1544017Y1055602D01*
G37*
G36*
G01X1544200Y1055221D02*
X1544383Y1054837D01*
X1543852Y1054307D01*
X1543469Y1054489D01*
X1543327Y1054630D01*
X1544059Y1055362D01*
X1544200Y1055221D01*
G37*
G36*
G01X1542355Y1053941D02*
X1542173Y1054324D01*
X1542703Y1054855D01*
X1543087Y1054673D01*
X1543228Y1054531D01*
X1542496Y1053799D01*
X1542355Y1053941D01*
G37*
G36*
G01X1549002Y1060588D02*
X1548820Y1060971D01*
X1549350Y1061502D01*
X1549734Y1061319D01*
X1549875Y1061178D01*
X1549143Y1060446D01*
X1549002Y1060588D01*
G37*
G36*
G01X1550847Y1061867D02*
X1551029Y1061484D01*
X1550499Y1060954D01*
X1550115Y1061136D01*
X1549974Y1061277D01*
X1550706Y1062009D01*
X1550847Y1061867D01*
G37*
G36*
G01X1547340Y1058926D02*
X1547158Y1059310D01*
X1547688Y1059840D01*
X1548072Y1059658D01*
X1548213Y1059516D01*
X1547481Y1058784D01*
X1547340Y1058926D01*
G37*
G36*
G01X1549186Y1060206D02*
X1549368Y1059822D01*
X1548837Y1059292D01*
X1548454Y1059474D01*
X1548312Y1059615D01*
X1549044Y1060347D01*
X1549186Y1060206D01*
G37*
G36*
G01X1550663Y1062249D02*
X1550481Y1062633D01*
X1551012Y1063163D01*
X1551395Y1062981D01*
X1551537Y1062840D01*
X1550805Y1062108D01*
X1550663Y1062249D01*
G37*
G36*
G01X1545862Y1056882D02*
X1546044Y1056499D01*
X1545514Y1055968D01*
X1545130Y1056151D01*
X1544989Y1056292D01*
X1545721Y1057024D01*
X1545862Y1056882D01*
G37*
G36*
G01X1545678Y1057264D02*
X1545496Y1057648D01*
X1546027Y1058178D01*
X1546410Y1057996D01*
X1546552Y1057855D01*
X1545820Y1057123D01*
X1545678Y1057264D01*
G37*
G36*
G01X1547524Y1058544D02*
X1547706Y1058160D01*
X1547176Y1057630D01*
X1546792Y1057812D01*
X1546651Y1057954D01*
X1547382Y1058685D01*
X1547524Y1058544D01*
G37*
G36*
G01X1552509Y1063529D02*
X1552691Y1063146D01*
X1552161Y1062615D01*
X1551777Y1062797D01*
X1551636Y1062939D01*
X1552368Y1063671D01*
X1552509Y1063529D01*
G37*
G36*
G01X1543351Y1056070D02*
X1543533Y1055687D01*
X1543003Y1055156D01*
X1542619Y1055338D01*
X1542478Y1055480D01*
X1543210Y1056212D01*
X1543351Y1056070D01*
G37*
G36*
G01X1543167Y1056452D02*
X1542985Y1056836D01*
X1543515Y1057366D01*
X1543899Y1057184D01*
X1544040Y1057042D01*
X1543309Y1056311D01*
X1543167Y1056452D01*
G37*
G36*
G01X1545013Y1057732D02*
X1545195Y1057348D01*
X1544664Y1056818D01*
X1544281Y1057000D01*
X1544139Y1057141D01*
X1544871Y1057873D01*
X1545013Y1057732D01*
G37*
G36*
G01X1546674Y1059394D02*
X1546856Y1059010D01*
X1546326Y1058480D01*
X1545943Y1058662D01*
X1545801Y1058803D01*
X1546533Y1059535D01*
X1546674Y1059394D01*
G37*
G36*
G01X1544829Y1058114D02*
X1544647Y1058497D01*
X1545177Y1059028D01*
X1545561Y1058846D01*
X1545702Y1058704D01*
X1544970Y1057972D01*
X1544829Y1058114D01*
G37*
G36*
G01X1549814Y1063099D02*
X1549632Y1063482D01*
X1550162Y1064013D01*
X1550546Y1063831D01*
X1550687Y1063689D01*
X1549955Y1062957D01*
X1549814Y1063099D01*
G37*
G36*
G01X1548336Y1061055D02*
X1548518Y1060672D01*
X1547988Y1060141D01*
X1547604Y1060323D01*
X1547463Y1060465D01*
X1548195Y1061197D01*
X1548336Y1061055D01*
G37*
G36*
G01X1548152Y1061437D02*
X1547970Y1061821D01*
X1548501Y1062351D01*
X1548884Y1062169D01*
X1549026Y1062028D01*
X1548294Y1061296D01*
X1548152Y1061437D01*
G37*
G36*
G01X1549998Y1062717D02*
X1550180Y1062333D01*
X1549650Y1061803D01*
X1549266Y1061985D01*
X1549125Y1062127D01*
X1549856Y1062858D01*
X1549998Y1062717D01*
G37*
G36*
G01X1546491Y1059775D02*
X1546308Y1060159D01*
X1546839Y1060689D01*
X1547222Y1060507D01*
X1547364Y1060366D01*
X1546632Y1059634D01*
X1546491Y1059775D01*
G37*
G36*
G01X1543204Y1053091D02*
X1543022Y1053475D01*
X1543553Y1054005D01*
X1543936Y1053823D01*
X1544078Y1053682D01*
X1543346Y1052950D01*
X1543204Y1053091D01*
G37*
G36*
G01X1543388Y1052709D02*
X1543570Y1052326D01*
X1543040Y1051796D01*
X1542656Y1051978D01*
X1542515Y1052119D01*
X1543247Y1052851D01*
X1543388Y1052709D01*
G37*
G36*
G01X1545050Y1054371D02*
X1545232Y1053988D01*
X1544702Y1053457D01*
X1544318Y1053639D01*
X1544177Y1053781D01*
X1544909Y1054513D01*
X1545050Y1054371D01*
G37*
G36*
G01X1544866Y1054753D02*
X1544684Y1055137D01*
X1545214Y1055667D01*
X1545598Y1055485D01*
X1545739Y1055343D01*
X1545008Y1054612D01*
X1544866Y1054753D01*
G37*
G36*
G01X1546528Y1056415D02*
X1546346Y1056798D01*
X1546876Y1057329D01*
X1547260Y1057147D01*
X1547401Y1057005D01*
X1546669Y1056273D01*
X1546528Y1056415D01*
G37*
G36*
G01X1546712Y1056033D02*
X1546894Y1055649D01*
X1546363Y1055119D01*
X1545980Y1055301D01*
X1545838Y1055442D01*
X1546570Y1056174D01*
X1546712Y1056033D01*
G37*
G36*
G01X1548373Y1057695D02*
X1548555Y1057311D01*
X1548025Y1056781D01*
X1547642Y1056963D01*
X1547500Y1057104D01*
X1548232Y1057836D01*
X1548373Y1057695D01*
G37*
G36*
G01X1550035Y1059356D02*
X1550217Y1058973D01*
X1549687Y1058442D01*
X1549303Y1058624D01*
X1549162Y1058766D01*
X1549894Y1059498D01*
X1550035Y1059356D01*
G37*
G36*
G01X1548190Y1058076D02*
X1548007Y1058460D01*
X1548538Y1058990D01*
X1548921Y1058808D01*
X1549063Y1058667D01*
X1548331Y1057935D01*
X1548190Y1058076D01*
G37*
G36*
G01X1551697Y1061018D02*
X1551879Y1060634D01*
X1551349Y1060104D01*
X1550965Y1060286D01*
X1550824Y1060428D01*
X1551555Y1061159D01*
X1551697Y1061018D01*
G37*
G36*
G01X1549851Y1059738D02*
X1549669Y1060122D01*
X1550200Y1060652D01*
X1550583Y1060470D01*
X1550725Y1060329D01*
X1549993Y1059597D01*
X1549851Y1059738D01*
G37*
G36*
G01X1551513Y1061400D02*
X1551331Y1061783D01*
X1551861Y1062314D01*
X1552245Y1062132D01*
X1552386Y1061990D01*
X1551654Y1061258D01*
X1551513Y1061400D01*
G37*
G36*
G01X1553359Y1062680D02*
X1553541Y1062296D01*
X1553010Y1061766D01*
X1552627Y1061948D01*
X1552485Y1062089D01*
X1553217Y1062821D01*
X1553359Y1062680D01*
G37*
G36*
G01X1553175Y1063061D02*
X1552993Y1063445D01*
X1553523Y1063975D01*
X1553907Y1063793D01*
X1554048Y1063652D01*
X1553316Y1062920D01*
X1553175Y1063061D01*
G37*
G36*
G01X1557991Y1064892D02*
X1557809Y1065276D01*
X1558339Y1065806D01*
X1558723Y1065624D01*
X1558864Y1065482D01*
X1558132Y1064750D01*
X1557991Y1064892D01*
G37*
G36*
G01X1558175Y1064510D02*
X1558357Y1064126D01*
X1557827Y1063596D01*
X1557443Y1063778D01*
X1557302Y1063920D01*
X1558033Y1064651D01*
X1558175Y1064510D01*
G37*
G36*
G01X1542407Y1079536D02*
X1542225Y1079920D01*
X1542755Y1080450D01*
X1543139Y1080268D01*
X1543280Y1080127D01*
X1542548Y1079395D01*
X1542407Y1079536D01*
G37*
G36*
G01X1545951Y1079118D02*
X1546133Y1078734D01*
X1545602Y1078204D01*
X1545219Y1078386D01*
X1545077Y1078527D01*
X1545809Y1079259D01*
X1545951Y1079118D01*
G37*
G36*
G01X1544105Y1077838D02*
X1543923Y1078221D01*
X1544453Y1078752D01*
X1544837Y1078570D01*
X1544978Y1078428D01*
X1544246Y1077696D01*
X1544105Y1077838D01*
G37*
G36*
G01X1544289Y1077456D02*
X1544471Y1077072D01*
X1543941Y1076542D01*
X1543557Y1076724D01*
X1543416Y1076866D01*
X1544147Y1077597D01*
X1544289Y1077456D01*
G37*
G36*
G01X1542443Y1076176D02*
X1542261Y1076560D01*
X1542792Y1077090D01*
X1543175Y1076908D01*
X1543317Y1076767D01*
X1542585Y1076035D01*
X1542443Y1076176D01*
G37*
G36*
G01X1542627Y1075794D02*
X1542809Y1075411D01*
X1542279Y1074880D01*
X1541895Y1075062D01*
X1541754Y1075204D01*
X1542486Y1075936D01*
X1542627Y1075794D01*
G37*
G36*
G01X1543256Y1078687D02*
X1543074Y1079071D01*
X1543604Y1079601D01*
X1543988Y1079419D01*
X1544129Y1079277D01*
X1543398Y1078546D01*
X1543256Y1078687D01*
G37*
G36*
G01X1545102Y1079967D02*
X1545284Y1079583D01*
X1544753Y1079053D01*
X1544370Y1079235D01*
X1544228Y1079376D01*
X1544960Y1080108D01*
X1545102Y1079967D01*
G37*
G36*
G01X1543440Y1078305D02*
X1543622Y1077922D01*
X1543092Y1077391D01*
X1542708Y1077573D01*
X1542567Y1077715D01*
X1543299Y1078447D01*
X1543440Y1078305D01*
G37*
G36*
G01X1546616Y1078650D02*
X1546434Y1079033D01*
X1546964Y1079564D01*
X1547348Y1079382D01*
X1547489Y1079240D01*
X1546757Y1078508D01*
X1546616Y1078650D01*
G37*
G36*
G01X1543293Y1075326D02*
X1543111Y1075710D01*
X1543641Y1076240D01*
X1544025Y1076058D01*
X1544166Y1075917D01*
X1543434Y1075185D01*
X1543293Y1075326D01*
G37*
G36*
G01X1543476Y1074945D02*
X1543659Y1074561D01*
X1543128Y1074031D01*
X1542745Y1074213D01*
X1542603Y1074354D01*
X1543335Y1075086D01*
X1543476Y1074945D01*
G37*
G36*
G01X1545138Y1076606D02*
X1545320Y1076223D01*
X1544790Y1075692D01*
X1544406Y1075874D01*
X1544265Y1076016D01*
X1544997Y1076748D01*
X1545138Y1076606D01*
G37*
G36*
G01X1546800Y1078268D02*
X1546982Y1077884D01*
X1546452Y1077354D01*
X1546068Y1077536D01*
X1545927Y1077678D01*
X1546658Y1078409D01*
X1546800Y1078268D01*
G37*
G36*
G01X1544954Y1076988D02*
X1544772Y1077372D01*
X1545303Y1077902D01*
X1545686Y1077720D01*
X1545828Y1077579D01*
X1545096Y1076847D01*
X1544954Y1076988D01*
G37*
G36*
G01X1550627Y1080041D02*
X1550991Y1079823D01*
X1550844Y1079087D01*
X1550424Y1079026D01*
X1550228Y1079065D01*
X1550431Y1080080D01*
X1550627Y1080041D01*
G37*
G36*
G01X1545137Y1073284D02*
X1545319Y1072900D01*
X1544788Y1072370D01*
X1544405Y1072552D01*
X1544263Y1072693D01*
X1544995Y1073425D01*
X1545137Y1073284D01*
G37*
G36*
G01X1543475Y1071622D02*
X1543657Y1071239D01*
X1543127Y1070708D01*
X1542743Y1070890D01*
X1542602Y1071032D01*
X1543334Y1071764D01*
X1543475Y1071622D01*
G37*
G36*
G01X1543291Y1072004D02*
X1543109Y1072388D01*
X1543639Y1072918D01*
X1544023Y1072736D01*
X1544164Y1072594D01*
X1543433Y1071863D01*
X1543291Y1072004D01*
G37*
G36*
G01X1546615Y1075327D02*
X1546432Y1075711D01*
X1546963Y1076241D01*
X1547346Y1076059D01*
X1547488Y1075918D01*
X1546756Y1075186D01*
X1546615Y1075327D01*
G37*
G36*
G01X1548460Y1076607D02*
X1548642Y1076224D01*
X1548112Y1075693D01*
X1547728Y1075875D01*
X1547587Y1076017D01*
X1548319Y1076749D01*
X1548460Y1076607D01*
G37*
G36*
G01X1546798Y1074946D02*
X1546981Y1074562D01*
X1546450Y1074032D01*
X1546067Y1074214D01*
X1545925Y1074355D01*
X1546657Y1075087D01*
X1546798Y1074946D01*
G37*
G36*
G01X1544953Y1073666D02*
X1544771Y1074049D01*
X1545301Y1074580D01*
X1545685Y1074398D01*
X1545826Y1074256D01*
X1545094Y1073524D01*
X1544953Y1073666D01*
G37*
G36*
G01X1548276Y1076989D02*
X1548094Y1077373D01*
X1548625Y1077903D01*
X1549008Y1077721D01*
X1549150Y1077580D01*
X1548418Y1076848D01*
X1548276Y1076989D01*
G37*
G36*
G01X1543511Y1068262D02*
X1543693Y1067879D01*
X1543163Y1067348D01*
X1542779Y1067530D01*
X1542638Y1067672D01*
X1543370Y1068404D01*
X1543511Y1068262D01*
G37*
G36*
G01X1543327Y1068644D02*
X1543145Y1069028D01*
X1543675Y1069558D01*
X1544059Y1069376D01*
X1544200Y1069234D01*
X1543469Y1068503D01*
X1543327Y1068644D01*
G37*
G36*
G01X1545173Y1069924D02*
X1545355Y1069540D01*
X1544824Y1069010D01*
X1544441Y1069192D01*
X1544299Y1069333D01*
X1545031Y1070065D01*
X1545173Y1069924D01*
G37*
G36*
G01X1548312Y1073629D02*
X1548130Y1074013D01*
X1548661Y1074543D01*
X1549044Y1074361D01*
X1549186Y1074220D01*
X1548454Y1073488D01*
X1548312Y1073629D01*
G37*
G36*
G01X1551820Y1076571D02*
X1552002Y1076187D01*
X1551471Y1075657D01*
X1551088Y1075839D01*
X1550946Y1075980D01*
X1551678Y1076712D01*
X1551820Y1076571D01*
G37*
G36*
G01X1550158Y1074909D02*
X1550340Y1074525D01*
X1549810Y1073995D01*
X1549426Y1074177D01*
X1549285Y1074319D01*
X1550016Y1075050D01*
X1550158Y1074909D01*
G37*
G36*
G01X1546651Y1071967D02*
X1546469Y1072351D01*
X1546999Y1072881D01*
X1547382Y1072699D01*
X1547524Y1072558D01*
X1546792Y1071826D01*
X1546651Y1071967D01*
G37*
G36*
G01X1548496Y1073247D02*
X1548678Y1072864D01*
X1548148Y1072333D01*
X1547764Y1072515D01*
X1547623Y1072657D01*
X1548355Y1073389D01*
X1548496Y1073247D01*
G37*
G36*
G01X1544989Y1070306D02*
X1544807Y1070689D01*
X1545337Y1071220D01*
X1545721Y1071038D01*
X1545862Y1070896D01*
X1545130Y1070164D01*
X1544989Y1070306D01*
G37*
G36*
G01X1546834Y1071586D02*
X1547017Y1071202D01*
X1546486Y1070672D01*
X1546103Y1070854D01*
X1545961Y1070995D01*
X1546693Y1071727D01*
X1546834Y1071586D01*
G37*
G36*
G01X1549974Y1075291D02*
X1549792Y1075674D01*
X1550322Y1076205D01*
X1550706Y1076023D01*
X1550847Y1075881D01*
X1550115Y1075149D01*
X1549974Y1075291D01*
G37*
G36*
G01X1552982Y1079570D02*
X1553346Y1079352D01*
X1553199Y1078616D01*
X1552779Y1078555D01*
X1552583Y1078594D01*
X1552786Y1079609D01*
X1552982Y1079570D01*
G37*
G36*
G01X1542662Y1069111D02*
X1542844Y1068728D01*
X1542314Y1068197D01*
X1541930Y1068379D01*
X1541789Y1068521D01*
X1542521Y1069253D01*
X1542662Y1069111D01*
G37*
G36*
G01X1544324Y1070773D02*
X1544506Y1070389D01*
X1543976Y1069859D01*
X1543592Y1070041D01*
X1543451Y1070183D01*
X1544182Y1070914D01*
X1544324Y1070773D01*
G37*
G36*
G01X1544140Y1071155D02*
X1543958Y1071538D01*
X1544488Y1072069D01*
X1544872Y1071887D01*
X1545013Y1071745D01*
X1544281Y1071013D01*
X1544140Y1071155D01*
G37*
G36*
G01X1542478Y1069493D02*
X1542296Y1069877D01*
X1542827Y1070407D01*
X1543210Y1070225D01*
X1543352Y1070084D01*
X1542620Y1069352D01*
X1542478Y1069493D01*
G37*
G36*
G01X1550971Y1077420D02*
X1551153Y1077036D01*
X1550622Y1076506D01*
X1550239Y1076688D01*
X1550097Y1076829D01*
X1550829Y1077561D01*
X1550971Y1077420D01*
G37*
G36*
G01X1549125Y1076140D02*
X1548943Y1076524D01*
X1549473Y1077054D01*
X1549857Y1076872D01*
X1549998Y1076730D01*
X1549267Y1075999D01*
X1549125Y1076140D01*
G37*
G36*
G01X1549309Y1075758D02*
X1549491Y1075375D01*
X1548961Y1074844D01*
X1548577Y1075026D01*
X1548436Y1075168D01*
X1549168Y1075900D01*
X1549309Y1075758D01*
G37*
G36*
G01X1547463Y1074478D02*
X1547281Y1074862D01*
X1547812Y1075392D01*
X1548195Y1075210D01*
X1548337Y1075069D01*
X1547605Y1074337D01*
X1547463Y1074478D01*
G37*
G36*
G01X1545802Y1072817D02*
X1545620Y1073200D01*
X1546150Y1073731D01*
X1546534Y1073548D01*
X1546675Y1073407D01*
X1545943Y1072675D01*
X1545802Y1072817D01*
G37*
G36*
G01X1547647Y1074096D02*
X1547829Y1073713D01*
X1547299Y1073183D01*
X1546915Y1073365D01*
X1546774Y1073506D01*
X1547506Y1074238D01*
X1547647Y1074096D01*
G37*
G36*
G01X1545986Y1072435D02*
X1546168Y1072051D01*
X1545637Y1071521D01*
X1545254Y1071703D01*
X1545112Y1071844D01*
X1545844Y1072576D01*
X1545986Y1072435D01*
G37*
G36*
G01X1551804Y1079805D02*
X1552169Y1079587D01*
X1552021Y1078852D01*
X1551601Y1078790D01*
X1551405Y1078830D01*
X1551608Y1079845D01*
X1551804Y1079805D01*
G37*
G36*
G01X1542514Y1066133D02*
X1542332Y1066517D01*
X1542863Y1067047D01*
X1543246Y1066865D01*
X1543388Y1066724D01*
X1542656Y1065992D01*
X1542514Y1066133D01*
G37*
G36*
G01X1542698Y1065751D02*
X1542880Y1065368D01*
X1542350Y1064837D01*
X1541966Y1065020D01*
X1541825Y1065161D01*
X1542557Y1065893D01*
X1542698Y1065751D01*
G37*
G36*
G01X1544360Y1067413D02*
X1544542Y1067029D01*
X1544012Y1066499D01*
X1543628Y1066681D01*
X1543487Y1066823D01*
X1544218Y1067554D01*
X1544360Y1067413D01*
G37*
G36*
G01X1544176Y1067795D02*
X1543994Y1068179D01*
X1544524Y1068709D01*
X1544908Y1068527D01*
X1545049Y1068385D01*
X1544317Y1067653D01*
X1544176Y1067795D01*
G37*
G36*
G01X1550823Y1074442D02*
X1550641Y1074825D01*
X1551171Y1075356D01*
X1551555Y1075174D01*
X1551696Y1075032D01*
X1550964Y1074300D01*
X1550823Y1074442D01*
G37*
G36*
G01X1549161Y1072780D02*
X1548979Y1073164D01*
X1549509Y1073694D01*
X1549893Y1073512D01*
X1550034Y1073370D01*
X1549303Y1072639D01*
X1549161Y1072780D01*
G37*
G36*
G01X1551007Y1074060D02*
X1551189Y1073676D01*
X1550658Y1073146D01*
X1550275Y1073328D01*
X1550133Y1073469D01*
X1550865Y1074201D01*
X1551007Y1074060D01*
G37*
G36*
G01X1546022Y1069075D02*
X1546204Y1068691D01*
X1545673Y1068161D01*
X1545290Y1068343D01*
X1545148Y1068484D01*
X1545880Y1069216D01*
X1546022Y1069075D01*
G37*
G36*
G01X1549345Y1072398D02*
X1549527Y1072015D01*
X1548997Y1071484D01*
X1548613Y1071666D01*
X1548472Y1071808D01*
X1549204Y1072540D01*
X1549345Y1072398D01*
G37*
G36*
G01X1545838Y1069457D02*
X1545656Y1069840D01*
X1546186Y1070371D01*
X1546570Y1070188D01*
X1546711Y1070047D01*
X1545979Y1069315D01*
X1545838Y1069457D01*
G37*
G36*
G01X1547683Y1070736D02*
X1547865Y1070353D01*
X1547335Y1069823D01*
X1546951Y1070005D01*
X1546810Y1070146D01*
X1547542Y1070878D01*
X1547683Y1070736D01*
G37*
G36*
G01X1547499Y1071118D02*
X1547317Y1071502D01*
X1547848Y1072032D01*
X1548231Y1071850D01*
X1548373Y1071709D01*
X1547641Y1070977D01*
X1547499Y1071118D01*
G37*
G36*
G01X1554161Y1079334D02*
X1554525Y1079116D01*
X1554378Y1078380D01*
X1553957Y1078319D01*
X1553761Y1078358D01*
X1553964Y1079373D01*
X1554161Y1079334D01*
G37*
G36*
G01X1552668Y1075722D02*
X1552850Y1075338D01*
X1552320Y1074808D01*
X1551937Y1074990D01*
X1551795Y1075131D01*
X1552527Y1075863D01*
X1552668Y1075722D01*
G37*
G36*
G01X1550627Y1065609D02*
X1550445Y1065993D01*
X1550975Y1066523D01*
X1551359Y1066341D01*
X1551500Y1066200D01*
X1550768Y1065468D01*
X1550627Y1065609D01*
G37*
G36*
G01X1550811Y1065228D02*
X1550993Y1064844D01*
X1550462Y1064314D01*
X1550079Y1064496D01*
X1549937Y1064637D01*
X1550669Y1065369D01*
X1550811Y1065228D01*
G37*
G36*
G01X1548965Y1063948D02*
X1548783Y1064331D01*
X1549313Y1064862D01*
X1549697Y1064680D01*
X1549838Y1064538D01*
X1549106Y1063806D01*
X1548965Y1063948D01*
G37*
G36*
G01X1554134Y1068551D02*
X1554316Y1068167D01*
X1553786Y1067637D01*
X1553402Y1067819D01*
X1553261Y1067961D01*
X1553992Y1068692D01*
X1554134Y1068551D01*
G37*
G36*
G01X1552472Y1066889D02*
X1552654Y1066506D01*
X1552124Y1065975D01*
X1551740Y1066158D01*
X1551599Y1066299D01*
X1552331Y1067031D01*
X1552472Y1066889D01*
G37*
G36*
G01X1552288Y1067271D02*
X1552106Y1067655D01*
X1552637Y1068185D01*
X1553020Y1068003D01*
X1553162Y1067862D01*
X1552430Y1067130D01*
X1552288Y1067271D01*
G37*
G36*
G01X1555796Y1070213D02*
X1555978Y1069829D01*
X1555447Y1069299D01*
X1555064Y1069481D01*
X1554922Y1069622D01*
X1555654Y1070354D01*
X1555796Y1070213D01*
G37*
G36*
G01X1555612Y1070595D02*
X1555430Y1070978D01*
X1555960Y1071509D01*
X1556344Y1071326D01*
X1556485Y1071185D01*
X1555753Y1070453D01*
X1555612Y1070595D01*
G37*
G36*
G01X1553950Y1068933D02*
X1553768Y1069317D01*
X1554298Y1069847D01*
X1554682Y1069665D01*
X1554823Y1069523D01*
X1554091Y1068791D01*
X1553950Y1068933D01*
G37*
G36*
G01X1557457Y1071874D02*
X1557639Y1071491D01*
X1557109Y1070961D01*
X1556725Y1071143D01*
X1556584Y1071284D01*
X1557316Y1072016D01*
X1557457Y1071874D01*
G37*
G36*
G01X1557273Y1072256D02*
X1557091Y1072640D01*
X1557622Y1073170D01*
X1558005Y1072988D01*
X1558147Y1072847D01*
X1557415Y1072115D01*
X1557273Y1072256D01*
G37*
G36*
G01X1557494Y1068514D02*
X1557676Y1068131D01*
X1557146Y1067600D01*
X1556762Y1067782D01*
X1556621Y1067924D01*
X1557353Y1068656D01*
X1557494Y1068514D01*
G37*
G36*
G01X1555649Y1067234D02*
X1555466Y1067618D01*
X1555997Y1068148D01*
X1556380Y1067966D01*
X1556522Y1067825D01*
X1555790Y1067093D01*
X1555649Y1067234D01*
G37*
G36*
G01X1553987Y1065573D02*
X1553805Y1065956D01*
X1554335Y1066487D01*
X1554719Y1066305D01*
X1554860Y1066163D01*
X1554128Y1065431D01*
X1553987Y1065573D01*
G37*
G36*
G01X1555832Y1066853D02*
X1556014Y1066469D01*
X1555484Y1065939D01*
X1555101Y1066121D01*
X1554959Y1066262D01*
X1555691Y1066994D01*
X1555832Y1066853D01*
G37*
G36*
G01X1552325Y1063911D02*
X1552143Y1064295D01*
X1552673Y1064825D01*
X1553057Y1064643D01*
X1553198Y1064501D01*
X1552467Y1063770D01*
X1552325Y1063911D01*
G37*
G36*
G01X1554171Y1065191D02*
X1554353Y1064807D01*
X1553822Y1064277D01*
X1553439Y1064459D01*
X1553297Y1064600D01*
X1554029Y1065332D01*
X1554171Y1065191D01*
G37*
G36*
G01X1557310Y1068896D02*
X1557128Y1069280D01*
X1557659Y1069810D01*
X1558042Y1069628D01*
X1558184Y1069487D01*
X1557452Y1068755D01*
X1557310Y1068896D01*
G37*
G36*
G01X1551476Y1064760D02*
X1551294Y1065144D01*
X1551824Y1065674D01*
X1552208Y1065492D01*
X1552349Y1065351D01*
X1551617Y1064619D01*
X1551476Y1064760D01*
G37*
G36*
G01X1551660Y1064379D02*
X1551842Y1063995D01*
X1551311Y1063465D01*
X1550928Y1063647D01*
X1550786Y1063788D01*
X1551518Y1064520D01*
X1551660Y1064379D01*
G37*
G36*
G01X1554799Y1068084D02*
X1554617Y1068468D01*
X1555147Y1068998D01*
X1555531Y1068816D01*
X1555672Y1068674D01*
X1554940Y1067942D01*
X1554799Y1068084D01*
G37*
G36*
G01X1554983Y1067702D02*
X1555165Y1067318D01*
X1554635Y1066788D01*
X1554251Y1066970D01*
X1554110Y1067112D01*
X1554841Y1067843D01*
X1554983Y1067702D01*
G37*
G36*
G01X1553137Y1066422D02*
X1552955Y1066806D01*
X1553486Y1067336D01*
X1553869Y1067154D01*
X1554011Y1067013D01*
X1553279Y1066281D01*
X1553137Y1066422D01*
G37*
G36*
G01X1553321Y1066040D02*
X1553503Y1065657D01*
X1552973Y1065126D01*
X1552589Y1065309D01*
X1552448Y1065450D01*
X1553180Y1066182D01*
X1553321Y1066040D01*
G37*
G36*
G01X1556645Y1069364D02*
X1556827Y1068980D01*
X1556296Y1068450D01*
X1555913Y1068632D01*
X1555771Y1068773D01*
X1556503Y1069505D01*
X1556645Y1069364D01*
G37*
G36*
G01X1556461Y1069746D02*
X1556279Y1070129D01*
X1556809Y1070660D01*
X1557193Y1070477D01*
X1557334Y1070336D01*
X1556602Y1069604D01*
X1556461Y1069746D01*
G37*
G36*
G01X1558306Y1071025D02*
X1558488Y1070642D01*
X1557958Y1070112D01*
X1557574Y1070294D01*
X1557433Y1070435D01*
X1558165Y1071167D01*
X1558306Y1071025D01*
G37*
G36*
G01X1558122Y1071407D02*
X1557940Y1071791D01*
X1558471Y1072321D01*
X1558854Y1072139D01*
X1558996Y1071998D01*
X1558264Y1071266D01*
X1558122Y1071407D01*
G37*
G36*
G01X1558160Y1068047D02*
X1557978Y1068430D01*
X1558508Y1068961D01*
X1558892Y1068778D01*
X1559033Y1068637D01*
X1558301Y1067905D01*
X1558160Y1068047D01*
G37*
G36*
G01X1556498Y1066385D02*
X1556316Y1066769D01*
X1556846Y1067299D01*
X1557230Y1067117D01*
X1557371Y1066975D01*
X1556639Y1066243D01*
X1556498Y1066385D01*
G37*
G36*
G01X1554836Y1064723D02*
X1554654Y1065107D01*
X1555185Y1065637D01*
X1555568Y1065455D01*
X1555710Y1065314D01*
X1554978Y1064582D01*
X1554836Y1064723D01*
G37*
G36*
G01X1558344Y1067665D02*
X1558526Y1067281D01*
X1557995Y1066751D01*
X1557612Y1066933D01*
X1557470Y1067074D01*
X1558202Y1067806D01*
X1558344Y1067665D01*
G37*
G36*
G01X1556682Y1066003D02*
X1556864Y1065619D01*
X1556334Y1065089D01*
X1555950Y1065271D01*
X1555809Y1065413D01*
X1556540Y1066144D01*
X1556682Y1066003D01*
G37*
G36*
G01X1555020Y1064341D02*
X1555202Y1063958D01*
X1554672Y1063427D01*
X1554288Y1063610D01*
X1554147Y1063751D01*
X1554879Y1064483D01*
X1555020Y1064341D01*
G37*
G36*
G01X1545030Y1083831D02*
X1544666Y1084049D01*
X1544813Y1084784D01*
X1545233Y1084846D01*
X1545429Y1084806D01*
X1545226Y1083792D01*
X1545030Y1083831D01*
G37*
G36*
G01X1545395Y1083615D02*
X1545759Y1083397D01*
X1545612Y1082661D01*
X1545192Y1082600D01*
X1544996Y1082639D01*
X1545199Y1083654D01*
X1545395Y1083615D01*
G37*
G36*
G01X1544253Y1080816D02*
X1544435Y1080433D01*
X1543904Y1079902D01*
X1543521Y1080084D01*
X1543379Y1080226D01*
X1544111Y1080958D01*
X1544253Y1080816D01*
G37*
G36*
G01X1545856Y1085919D02*
X1546220Y1085701D01*
X1546073Y1084966D01*
X1545653Y1084905D01*
X1545457Y1084944D01*
X1545659Y1085959D01*
X1545856Y1085919D01*
G37*
G36*
G01X1546316Y1088224D02*
X1546680Y1088006D01*
X1546533Y1087270D01*
X1546113Y1087209D01*
X1545917Y1087248D01*
X1546120Y1088263D01*
X1546316Y1088224D01*
G37*
G36*
G01X1546777Y1090528D02*
X1547141Y1090310D01*
X1546994Y1089575D01*
X1546574Y1089513D01*
X1546378Y1089553D01*
X1546580Y1090568D01*
X1546777Y1090528D01*
G37*
G36*
G01X1546412Y1090744D02*
X1546047Y1090962D01*
X1546194Y1091698D01*
X1546615Y1091759D01*
X1546811Y1091720D01*
X1546608Y1090705D01*
X1546412Y1090744D01*
G37*
G36*
G01X1545951Y1088440D02*
X1545587Y1088658D01*
X1545734Y1089393D01*
X1546154Y1089455D01*
X1546350Y1089415D01*
X1546147Y1088400D01*
X1545951Y1088440D01*
G37*
G36*
G01X1545491Y1086135D02*
X1545126Y1086353D01*
X1545273Y1087089D01*
X1545694Y1087150D01*
X1545890Y1087111D01*
X1545687Y1086096D01*
X1545491Y1086135D01*
G37*
G36*
G01X1547237Y1092833D02*
X1547601Y1092615D01*
X1547454Y1091879D01*
X1547034Y1091818D01*
X1546838Y1091857D01*
X1547041Y1092872D01*
X1547237Y1092833D01*
G37*
G36*
G01X1547698Y1095137D02*
X1548062Y1094919D01*
X1547915Y1094184D01*
X1547495Y1094122D01*
X1547299Y1094161D01*
X1547501Y1095176D01*
X1547698Y1095137D01*
G37*
G36*
G01X1546872Y1093048D02*
X1546508Y1093267D01*
X1546655Y1094002D01*
X1547075Y1094063D01*
X1547271Y1094024D01*
X1547068Y1093009D01*
X1546872Y1093048D01*
G37*
G36*
G01X1547333Y1095353D02*
X1546968Y1095571D01*
X1547115Y1096307D01*
X1547536Y1096368D01*
X1547732Y1096329D01*
X1547529Y1095314D01*
X1547333Y1095353D01*
G37*
G36*
G01X1547751Y1083144D02*
X1548115Y1082926D01*
X1547968Y1082190D01*
X1547548Y1082129D01*
X1547352Y1082168D01*
X1547555Y1083183D01*
X1547751Y1083144D01*
G37*
G36*
G01X1546925Y1081055D02*
X1546561Y1081273D01*
X1546708Y1082009D01*
X1547128Y1082070D01*
X1547324Y1082031D01*
X1547121Y1081016D01*
X1546925Y1081055D01*
G37*
G36*
G01X1547386Y1083360D02*
X1547022Y1083578D01*
X1547169Y1084313D01*
X1547589Y1084374D01*
X1547785Y1084335D01*
X1547582Y1083320D01*
X1547386Y1083360D01*
G37*
G36*
G01X1548212Y1085448D02*
X1548576Y1085230D01*
X1548429Y1084494D01*
X1548009Y1084433D01*
X1547813Y1084472D01*
X1548016Y1085487D01*
X1548212Y1085448D01*
G37*
G36*
G01X1548673Y1087752D02*
X1549037Y1087534D01*
X1548890Y1086799D01*
X1548470Y1086738D01*
X1548274Y1086777D01*
X1548477Y1087792D01*
X1548673Y1087752D01*
G37*
G36*
G01X1549134Y1090057D02*
X1549498Y1089839D01*
X1549351Y1089103D01*
X1548931Y1089042D01*
X1548735Y1089081D01*
X1548938Y1090096D01*
X1549134Y1090057D01*
G37*
G36*
G01X1549595Y1092361D02*
X1549959Y1092143D01*
X1549812Y1091408D01*
X1549392Y1091346D01*
X1549196Y1091385D01*
X1549399Y1092400D01*
X1549595Y1092361D01*
G37*
G36*
G01X1548769Y1090273D02*
X1548405Y1090491D01*
X1548552Y1091226D01*
X1548972Y1091287D01*
X1549168Y1091248D01*
X1548965Y1090233D01*
X1548769Y1090273D01*
G37*
G36*
G01X1547847Y1085664D02*
X1547483Y1085882D01*
X1547630Y1086617D01*
X1548050Y1086679D01*
X1548246Y1086640D01*
X1548043Y1085625D01*
X1547847Y1085664D01*
G37*
G36*
G01X1548308Y1087968D02*
X1547944Y1088186D01*
X1548091Y1088922D01*
X1548511Y1088983D01*
X1548707Y1088944D01*
X1548504Y1087929D01*
X1548308Y1087968D01*
G37*
G36*
G01X1549230Y1092577D02*
X1548866Y1092795D01*
X1549013Y1093530D01*
X1549433Y1093592D01*
X1549629Y1093553D01*
X1549426Y1092538D01*
X1549230Y1092577D01*
G37*
G36*
G01X1550056Y1094665D02*
X1550420Y1094447D01*
X1550273Y1093712D01*
X1549853Y1093651D01*
X1549657Y1093690D01*
X1549860Y1094705D01*
X1550056Y1094665D01*
G37*
G36*
G01X1549691Y1094881D02*
X1549327Y1095099D01*
X1549474Y1095835D01*
X1549894Y1095896D01*
X1550090Y1095857D01*
X1549887Y1094842D01*
X1549691Y1094881D01*
G37*
G36*
G01X1546573Y1083379D02*
X1546937Y1083161D01*
X1546790Y1082426D01*
X1546370Y1082365D01*
X1546174Y1082404D01*
X1546377Y1083419D01*
X1546573Y1083379D01*
G37*
G36*
G01X1546208Y1083595D02*
X1545844Y1083813D01*
X1545991Y1084549D01*
X1546411Y1084610D01*
X1546607Y1084571D01*
X1546404Y1083556D01*
X1546208Y1083595D01*
G37*
G36*
G01X1547034Y1085684D02*
X1547398Y1085466D01*
X1547251Y1084730D01*
X1546830Y1084669D01*
X1546634Y1084708D01*
X1546837Y1085723D01*
X1547034Y1085684D01*
G37*
G36*
G01X1547955Y1090293D02*
X1548319Y1090074D01*
X1548172Y1089339D01*
X1547752Y1089278D01*
X1547556Y1089317D01*
X1547759Y1090332D01*
X1547955Y1090293D01*
G37*
G36*
G01X1547590Y1090508D02*
X1547226Y1090726D01*
X1547373Y1091462D01*
X1547793Y1091523D01*
X1547989Y1091484D01*
X1547787Y1090469D01*
X1547590Y1090508D01*
G37*
G36*
G01X1546669Y1085900D02*
X1546304Y1086118D01*
X1546451Y1086853D01*
X1546872Y1086914D01*
X1547068Y1086875D01*
X1546865Y1085860D01*
X1546669Y1085900D01*
G37*
G36*
G01X1547130Y1088204D02*
X1546765Y1088422D01*
X1546912Y1089158D01*
X1547333Y1089219D01*
X1547529Y1089180D01*
X1547326Y1088165D01*
X1547130Y1088204D01*
G37*
G36*
G01X1548416Y1092597D02*
X1548780Y1092379D01*
X1548633Y1091643D01*
X1548213Y1091582D01*
X1548017Y1091621D01*
X1548220Y1092636D01*
X1548416Y1092597D01*
G37*
G36*
G01X1548512Y1095117D02*
X1548148Y1095335D01*
X1548295Y1096071D01*
X1548715Y1096132D01*
X1548911Y1096093D01*
X1548708Y1095078D01*
X1548512Y1095117D01*
G37*
G36*
G01X1548877Y1094901D02*
X1549241Y1094683D01*
X1549094Y1093948D01*
X1548674Y1093886D01*
X1548478Y1093926D01*
X1548681Y1094941D01*
X1548877Y1094901D01*
G37*
G36*
G01X1548051Y1092813D02*
X1547687Y1093031D01*
X1547834Y1093766D01*
X1548254Y1093828D01*
X1548450Y1093788D01*
X1548247Y1092773D01*
X1548051Y1092813D01*
G37*
G36*
G01X1547494Y1087988D02*
X1547859Y1087770D01*
X1547712Y1087035D01*
X1547291Y1086973D01*
X1547095Y1087013D01*
X1547298Y1088027D01*
X1547494Y1087988D01*
G37*
G36*
G01X1548564Y1083124D02*
X1548200Y1083342D01*
X1548347Y1084077D01*
X1548767Y1084139D01*
X1548963Y1084100D01*
X1548760Y1083085D01*
X1548564Y1083124D01*
G37*
G36*
G01X1548103Y1080819D02*
X1547739Y1081038D01*
X1547886Y1081773D01*
X1548306Y1081834D01*
X1548502Y1081795D01*
X1548299Y1080780D01*
X1548103Y1080819D01*
G37*
G36*
G01X1548929Y1082908D02*
X1549293Y1082690D01*
X1549146Y1081954D01*
X1548726Y1081893D01*
X1548530Y1081932D01*
X1548733Y1082947D01*
X1548929Y1082908D01*
G37*
G36*
G01X1549390Y1085212D02*
X1549754Y1084994D01*
X1549607Y1084259D01*
X1549187Y1084198D01*
X1548991Y1084237D01*
X1549194Y1085252D01*
X1549390Y1085212D01*
G37*
G36*
G01X1549947Y1090037D02*
X1549583Y1090255D01*
X1549730Y1090991D01*
X1550150Y1091052D01*
X1550346Y1091013D01*
X1550143Y1089998D01*
X1549947Y1090037D01*
G37*
G36*
G01X1549025Y1085428D02*
X1548661Y1085646D01*
X1548808Y1086382D01*
X1549228Y1086443D01*
X1549424Y1086404D01*
X1549221Y1085389D01*
X1549025Y1085428D01*
G37*
G36*
G01X1549486Y1087733D02*
X1549122Y1087951D01*
X1549269Y1088686D01*
X1549689Y1088747D01*
X1549885Y1088708D01*
X1549682Y1087693D01*
X1549486Y1087733D01*
G37*
G36*
G01X1550773Y1092126D02*
X1551137Y1091907D01*
X1550990Y1091172D01*
X1550570Y1091111D01*
X1550374Y1091150D01*
X1550577Y1092165D01*
X1550773Y1092126D01*
G37*
G36*
G01X1549851Y1087517D02*
X1550215Y1087299D01*
X1550068Y1086563D01*
X1549648Y1086502D01*
X1549452Y1086541D01*
X1549655Y1087556D01*
X1549851Y1087517D01*
G37*
G36*
G01X1550312Y1089821D02*
X1550676Y1089603D01*
X1550529Y1088868D01*
X1550109Y1088806D01*
X1549913Y1088846D01*
X1550116Y1089860D01*
X1550312Y1089821D01*
G37*
G36*
G01X1550408Y1092341D02*
X1550044Y1092559D01*
X1550191Y1093295D01*
X1550611Y1093356D01*
X1550807Y1093317D01*
X1550604Y1092302D01*
X1550408Y1092341D01*
G37*
G36*
G01X1550869Y1094646D02*
X1550505Y1094864D01*
X1550652Y1095599D01*
X1551072Y1095661D01*
X1551268Y1095621D01*
X1551065Y1094606D01*
X1550869Y1094646D01*
G37*
G36*
G01X1551234Y1094430D02*
X1551598Y1094212D01*
X1551451Y1093476D01*
X1551031Y1093415D01*
X1550834Y1093454D01*
X1551037Y1094469D01*
X1551234Y1094430D01*
G37*
G36*
G01X1551695Y1096734D02*
X1552059Y1096516D01*
X1551912Y1095781D01*
X1551492Y1095719D01*
X1551295Y1095759D01*
X1551498Y1096773D01*
X1551695Y1096734D01*
G37*
G36*
G01X1551549Y1084650D02*
X1551913Y1084431D01*
X1551766Y1083696D01*
X1551346Y1083635D01*
X1551150Y1083674D01*
X1551353Y1084689D01*
X1551549Y1084650D01*
G37*
G36*
G01X1551088Y1082345D02*
X1551452Y1082127D01*
X1551305Y1081392D01*
X1550885Y1081330D01*
X1550689Y1081370D01*
X1550892Y1082384D01*
X1551088Y1082345D01*
G37*
G36*
G01X1550262Y1080257D02*
X1549898Y1080475D01*
X1550045Y1081210D01*
X1550465Y1081271D01*
X1550661Y1081232D01*
X1550458Y1080217D01*
X1550262Y1080257D01*
G37*
G36*
G01X1550723Y1082561D02*
X1550359Y1082779D01*
X1550506Y1083515D01*
X1550926Y1083576D01*
X1551122Y1083537D01*
X1550919Y1082522D01*
X1550723Y1082561D01*
G37*
G36*
G01X1551184Y1084865D02*
X1550820Y1085083D01*
X1550967Y1085819D01*
X1551387Y1085880D01*
X1551583Y1085841D01*
X1551380Y1084826D01*
X1551184Y1084865D01*
G37*
G36*
G01X1551645Y1087170D02*
X1551281Y1087388D01*
X1551428Y1088123D01*
X1551848Y1088185D01*
X1552044Y1088145D01*
X1551841Y1087130D01*
X1551645Y1087170D01*
G37*
G36*
G01X1552010Y1086954D02*
X1552374Y1086736D01*
X1552227Y1086000D01*
X1551807Y1085939D01*
X1551611Y1085978D01*
X1551814Y1086993D01*
X1552010Y1086954D01*
G37*
G36*
G01X1552471Y1089258D02*
X1552835Y1089040D01*
X1552688Y1088305D01*
X1552268Y1088243D01*
X1552072Y1088283D01*
X1552275Y1089297D01*
X1552471Y1089258D01*
G37*
G36*
G01X1552932Y1091563D02*
X1553296Y1091344D01*
X1553149Y1090609D01*
X1552729Y1090548D01*
X1552532Y1090587D01*
X1552736Y1091602D01*
X1552932Y1091563D01*
G37*
G36*
G01X1552106Y1089474D02*
X1551742Y1089692D01*
X1551889Y1090428D01*
X1552309Y1090489D01*
X1552505Y1090450D01*
X1552302Y1089435D01*
X1552106Y1089474D01*
G37*
G36*
G01X1552567Y1091778D02*
X1552203Y1091997D01*
X1552350Y1092732D01*
X1552770Y1092793D01*
X1552966Y1092754D01*
X1552763Y1091739D01*
X1552567Y1091778D01*
G37*
G36*
G01X1553393Y1093867D02*
X1553757Y1093649D01*
X1553610Y1092913D01*
X1553190Y1092852D01*
X1552993Y1092891D01*
X1553196Y1093906D01*
X1553393Y1093867D01*
G37*
G36*
G01X1553028Y1094083D02*
X1552663Y1094301D01*
X1552811Y1095036D01*
X1553231Y1095098D01*
X1553427Y1095058D01*
X1553224Y1094043D01*
X1553028Y1094083D01*
G37*
G36*
G01X1553853Y1096171D02*
X1554218Y1095953D01*
X1554071Y1095218D01*
X1553650Y1095156D01*
X1553454Y1095196D01*
X1553657Y1096211D01*
X1553853Y1096171D01*
G37*
G36*
G01X1553904Y1084178D02*
X1554268Y1083960D01*
X1554121Y1083225D01*
X1553701Y1083164D01*
X1553505Y1083203D01*
X1553708Y1084218D01*
X1553904Y1084178D01*
G37*
G36*
G01X1552617Y1079786D02*
X1552253Y1080004D01*
X1552400Y1080739D01*
X1552820Y1080800D01*
X1553016Y1080761D01*
X1552813Y1079746D01*
X1552617Y1079786D01*
G37*
G36*
G01X1553078Y1082090D02*
X1552714Y1082308D01*
X1552861Y1083044D01*
X1553281Y1083105D01*
X1553477Y1083066D01*
X1553274Y1082051D01*
X1553078Y1082090D01*
G37*
G36*
G01X1553443Y1081874D02*
X1553807Y1081656D01*
X1553660Y1080920D01*
X1553240Y1080859D01*
X1553044Y1080898D01*
X1553247Y1081913D01*
X1553443Y1081874D01*
G37*
G36*
G01X1553539Y1084394D02*
X1553175Y1084612D01*
X1553322Y1085348D01*
X1553742Y1085409D01*
X1553939Y1085370D01*
X1553735Y1084355D01*
X1553539Y1084394D01*
G37*
G36*
G01X1555749Y1093396D02*
X1556113Y1093177D01*
X1555966Y1092442D01*
X1555546Y1092381D01*
X1555350Y1092420D01*
X1555553Y1093435D01*
X1555749Y1093396D01*
G37*
G36*
G01X1555384Y1093611D02*
X1555020Y1093830D01*
X1555167Y1094565D01*
X1555587Y1094626D01*
X1555783Y1094587D01*
X1555580Y1093572D01*
X1555384Y1093611D01*
G37*
G36*
G01X1556210Y1095700D02*
X1556574Y1095482D01*
X1556427Y1094746D01*
X1556007Y1094685D01*
X1555811Y1094724D01*
X1556014Y1095739D01*
X1556210Y1095700D01*
G37*
G36*
G01X1554462Y1089003D02*
X1554097Y1089221D01*
X1554245Y1089956D01*
X1554665Y1090018D01*
X1554861Y1089978D01*
X1554658Y1088964D01*
X1554462Y1089003D01*
G37*
G36*
G01X1554923Y1091307D02*
X1554559Y1091525D01*
X1554706Y1092261D01*
X1555126Y1092322D01*
X1555322Y1092283D01*
X1555119Y1091268D01*
X1554923Y1091307D01*
G37*
G36*
G01X1554365Y1086483D02*
X1554729Y1086265D01*
X1554582Y1085529D01*
X1554162Y1085468D01*
X1553966Y1085507D01*
X1554169Y1086522D01*
X1554365Y1086483D01*
G37*
G36*
G01X1554826Y1088787D02*
X1555191Y1088569D01*
X1555044Y1087833D01*
X1554623Y1087772D01*
X1554427Y1087811D01*
X1554630Y1088826D01*
X1554826Y1088787D01*
G37*
G36*
G01X1555288Y1091091D02*
X1555652Y1090873D01*
X1555505Y1090138D01*
X1555084Y1090076D01*
X1554888Y1090116D01*
X1555091Y1091131D01*
X1555288Y1091091D01*
G37*
G36*
G01X1554001Y1086698D02*
X1553636Y1086917D01*
X1553783Y1087652D01*
X1554204Y1087713D01*
X1554400Y1087674D01*
X1554197Y1086659D01*
X1554001Y1086698D01*
G37*
G36*
G01X1551440Y1080021D02*
X1551075Y1080239D01*
X1551222Y1080975D01*
X1551643Y1081036D01*
X1551839Y1080997D01*
X1551636Y1079982D01*
X1551440Y1080021D01*
G37*
G36*
G01X1551900Y1082325D02*
X1551536Y1082544D01*
X1551683Y1083279D01*
X1552103Y1083340D01*
X1552300Y1083301D01*
X1552097Y1082286D01*
X1551900Y1082325D01*
G37*
G36*
G01X1552726Y1084414D02*
X1553090Y1084196D01*
X1552943Y1083460D01*
X1552523Y1083399D01*
X1552327Y1083438D01*
X1552530Y1084453D01*
X1552726Y1084414D01*
G37*
G36*
G01X1552265Y1082110D02*
X1552630Y1081891D01*
X1552482Y1081156D01*
X1552062Y1081095D01*
X1551866Y1081134D01*
X1552069Y1082149D01*
X1552265Y1082110D01*
G37*
G36*
G01X1552361Y1084630D02*
X1551997Y1084848D01*
X1552144Y1085583D01*
X1552564Y1085645D01*
X1552761Y1085605D01*
X1552558Y1084591D01*
X1552361Y1084630D01*
G37*
G36*
G01X1554205Y1093847D02*
X1553841Y1094065D01*
X1553988Y1094801D01*
X1554408Y1094862D01*
X1554604Y1094823D01*
X1554401Y1093808D01*
X1554205Y1093847D01*
G37*
G36*
G01X1554570Y1093631D02*
X1554934Y1093413D01*
X1554787Y1092678D01*
X1554367Y1092617D01*
X1554171Y1092656D01*
X1554374Y1093671D01*
X1554570Y1093631D01*
G37*
G36*
G01X1555031Y1095936D02*
X1555395Y1095718D01*
X1555248Y1094982D01*
X1554828Y1094921D01*
X1554632Y1094960D01*
X1554835Y1095975D01*
X1555031Y1095936D01*
G37*
G36*
G01X1552822Y1086934D02*
X1552458Y1087152D01*
X1552605Y1087888D01*
X1553025Y1087949D01*
X1553221Y1087910D01*
X1553018Y1086895D01*
X1552822Y1086934D01*
G37*
G36*
G01X1553283Y1089238D02*
X1552919Y1089457D01*
X1553066Y1090192D01*
X1553486Y1090253D01*
X1553682Y1090214D01*
X1553479Y1089199D01*
X1553283Y1089238D01*
G37*
G36*
G01X1553744Y1091543D02*
X1553380Y1091761D01*
X1553527Y1092496D01*
X1553947Y1092558D01*
X1554143Y1092518D01*
X1553940Y1091504D01*
X1553744Y1091543D01*
G37*
G36*
G01X1553187Y1086718D02*
X1553551Y1086500D01*
X1553404Y1085765D01*
X1552984Y1085703D01*
X1552788Y1085743D01*
X1552991Y1086758D01*
X1553187Y1086718D01*
G37*
G36*
G01X1553648Y1089023D02*
X1554012Y1088804D01*
X1553865Y1088069D01*
X1553445Y1088008D01*
X1553249Y1088047D01*
X1553452Y1089062D01*
X1553648Y1089023D01*
G37*
G36*
G01X1554109Y1091327D02*
X1554473Y1091109D01*
X1554326Y1090373D01*
X1553906Y1090312D01*
X1553710Y1090351D01*
X1553913Y1091366D01*
X1554109Y1091327D01*
G37*
G36*
G01X1555083Y1083943D02*
X1555447Y1083725D01*
X1555300Y1082989D01*
X1554880Y1082928D01*
X1554683Y1082967D01*
X1554886Y1083982D01*
X1555083Y1083943D01*
G37*
G36*
G01X1554257Y1081854D02*
X1553893Y1082072D01*
X1554040Y1082808D01*
X1554460Y1082869D01*
X1554656Y1082830D01*
X1554453Y1081815D01*
X1554257Y1081854D01*
G37*
G36*
G01X1554622Y1081638D02*
X1554986Y1081420D01*
X1554839Y1080685D01*
X1554419Y1080623D01*
X1554222Y1080663D01*
X1554425Y1081678D01*
X1554622Y1081638D01*
G37*
G36*
G01X1553796Y1079550D02*
X1553432Y1079768D01*
X1553579Y1080503D01*
X1553999Y1080565D01*
X1554195Y1080525D01*
X1553992Y1079511D01*
X1553796Y1079550D01*
G37*
G36*
G01X1554718Y1084158D02*
X1554354Y1084377D01*
X1554501Y1085112D01*
X1554921Y1085173D01*
X1555117Y1085134D01*
X1554914Y1084119D01*
X1554718Y1084158D01*
G37*
G36*
G01X1555179Y1086463D02*
X1554815Y1086681D01*
X1554962Y1087416D01*
X1555382Y1087478D01*
X1555578Y1087438D01*
X1555375Y1086424D01*
X1555179Y1086463D01*
G37*
G36*
G01X1555640Y1088767D02*
X1555276Y1088985D01*
X1555423Y1089721D01*
X1555843Y1089782D01*
X1556039Y1089743D01*
X1555836Y1088728D01*
X1555640Y1088767D01*
G37*
G36*
G01X1556101Y1091071D02*
X1555737Y1091290D01*
X1555884Y1092025D01*
X1556304Y1092086D01*
X1556500Y1092047D01*
X1556297Y1091032D01*
X1556101Y1091071D01*
G37*
G36*
G01X1555544Y1086247D02*
X1555908Y1086029D01*
X1555761Y1085293D01*
X1555341Y1085232D01*
X1555144Y1085271D01*
X1555347Y1086286D01*
X1555544Y1086247D01*
G37*
G36*
G01X1556005Y1088551D02*
X1556369Y1088333D01*
X1556222Y1087598D01*
X1555802Y1087536D01*
X1555605Y1087576D01*
X1555808Y1088591D01*
X1556005Y1088551D01*
G37*
G36*
G01X1556466Y1090856D02*
X1556830Y1090638D01*
X1556683Y1089902D01*
X1556263Y1089841D01*
X1556066Y1089880D01*
X1556269Y1090895D01*
X1556466Y1090856D01*
G37*
G36*
G01X1556927Y1093160D02*
X1557291Y1092942D01*
X1557144Y1092206D01*
X1556724Y1092145D01*
X1556527Y1092184D01*
X1556731Y1093199D01*
X1556927Y1093160D01*
G37*
G36*
G01X1556562Y1093376D02*
X1556198Y1093594D01*
X1556345Y1094329D01*
X1556765Y1094391D01*
X1556961Y1094351D01*
X1556758Y1093337D01*
X1556562Y1093376D01*
G37*
G36*
G01X1557388Y1095464D02*
X1557752Y1095246D01*
X1557605Y1094511D01*
X1557185Y1094449D01*
X1556988Y1094489D01*
X1557192Y1095504D01*
X1557388Y1095464D01*
G37*
G36*
G01X1557023Y1095680D02*
X1556659Y1095898D01*
X1556806Y1096634D01*
X1557226Y1096695D01*
X1557422Y1096656D01*
X1557219Y1095641D01*
X1557023Y1095680D01*
G37*
G36*
G01X1542067Y1112780D02*
X1542467Y1112637D01*
Y1111887D01*
X1542067Y1111745D01*
X1541867D01*
Y1112780D01*
X1542067D01*
G37*
G36*
G01Y1110430D02*
X1542467Y1110287D01*
Y1109537D01*
X1542067Y1109395D01*
X1541867D01*
Y1110430D01*
X1542067D01*
G37*
G36*
G01Y1108080D02*
X1542467Y1107937D01*
Y1107187D01*
X1542067Y1107045D01*
X1541867D01*
Y1108080D01*
X1542067D01*
G37*
G36*
G01X1542578Y1100482D02*
X1542943Y1100264D01*
X1542796Y1099529D01*
X1542376Y1099468D01*
X1542180Y1099507D01*
X1542382Y1100522D01*
X1542578Y1100482D01*
G37*
G36*
G01X1542214Y1100698D02*
X1541849Y1100916D01*
X1541996Y1101652D01*
X1542416Y1101713D01*
X1542612Y1101674D01*
X1542410Y1100659D01*
X1542214Y1100698D01*
G37*
G36*
G01X1542867Y1108219D02*
X1542467Y1108362D01*
Y1109112D01*
X1542867Y1109255D01*
X1543067D01*
Y1108219D01*
X1542867D01*
G37*
G36*
G01X1543267Y1108080D02*
X1543667Y1107937D01*
Y1107187D01*
X1543267Y1107045D01*
X1543067D01*
Y1108080D01*
X1543267D01*
G37*
G36*
G01X1542867Y1105869D02*
X1542467Y1106012D01*
Y1106762D01*
X1542867Y1106905D01*
X1543067D01*
Y1105869D01*
X1542867D01*
G37*
G36*
G01X1543039Y1102787D02*
X1543403Y1102569D01*
X1543256Y1101833D01*
X1542836Y1101772D01*
X1542640Y1101811D01*
X1542843Y1102826D01*
X1543039Y1102787D01*
G37*
G36*
G01X1542867Y1110569D02*
X1542467Y1110712D01*
Y1111462D01*
X1542867Y1111605D01*
X1543067D01*
Y1110569D01*
X1542867D01*
G37*
G36*
G01X1543267Y1110430D02*
X1543667Y1110287D01*
Y1109537D01*
X1543267Y1109395D01*
X1543067D01*
Y1110430D01*
X1543267D01*
G37*
G36*
G01Y1112780D02*
X1543667Y1112637D01*
Y1111887D01*
X1543267Y1111745D01*
X1543067D01*
Y1112780D01*
X1543267D01*
G37*
G36*
G01X1549079Y1102050D02*
X1549443Y1101832D01*
X1549296Y1101097D01*
X1548876Y1101036D01*
X1548680Y1101075D01*
X1548883Y1102090D01*
X1549079Y1102050D01*
G37*
G36*
G01X1548619Y1099746D02*
X1548983Y1099528D01*
X1548836Y1098792D01*
X1548416Y1098731D01*
X1548220Y1098770D01*
X1548422Y1099785D01*
X1548619Y1099746D01*
G37*
G36*
G01X1548254Y1099962D02*
X1547889Y1100180D01*
X1548036Y1100915D01*
X1548457Y1100977D01*
X1548653Y1100937D01*
X1548450Y1099923D01*
X1548254Y1099962D01*
G37*
G36*
G01X1548158Y1097442D02*
X1548522Y1097223D01*
X1548375Y1096488D01*
X1547955Y1096427D01*
X1547759Y1096466D01*
X1547962Y1097481D01*
X1548158Y1097442D01*
G37*
G36*
G01X1547793Y1097657D02*
X1547429Y1097876D01*
X1547576Y1098611D01*
X1547996Y1098672D01*
X1548192Y1098633D01*
X1547989Y1097618D01*
X1547793Y1097657D01*
G37*
G36*
G01X1549282Y1110723D02*
X1549682Y1110580D01*
Y1109830D01*
X1549282Y1109687D01*
X1549082D01*
Y1110723D01*
X1549282D01*
G37*
G36*
G01X1548882Y1110862D02*
X1548482Y1111005D01*
Y1111755D01*
X1548882Y1111897D01*
X1549082D01*
Y1110862D01*
X1548882D01*
G37*
G36*
G01X1549282Y1106023D02*
X1549682Y1105880D01*
Y1105130D01*
X1549282Y1104987D01*
X1549082D01*
Y1106023D01*
X1549282D01*
G37*
G36*
G01X1548882Y1106162D02*
X1548482Y1106305D01*
Y1107055D01*
X1548882Y1107197D01*
X1549082D01*
Y1106162D01*
X1548882D01*
G37*
G36*
G01Y1108512D02*
X1548482Y1108655D01*
Y1109405D01*
X1548882Y1109547D01*
X1549082D01*
Y1108512D01*
X1548882D01*
G37*
G36*
G01X1549282Y1108373D02*
X1549682Y1108230D01*
Y1107480D01*
X1549282Y1107337D01*
X1549082D01*
Y1108373D01*
X1549282D01*
G37*
G36*
G01X1551439Y1101578D02*
X1551803Y1101360D01*
X1551656Y1100625D01*
X1551236Y1100564D01*
X1551040Y1100603D01*
X1551243Y1101618D01*
X1551439Y1101578D01*
G37*
G36*
G01X1550978Y1099274D02*
X1551342Y1099056D01*
X1551195Y1098321D01*
X1550775Y1098259D01*
X1550579Y1098298D01*
X1550782Y1099313D01*
X1550978Y1099274D01*
G37*
G36*
G01X1550613Y1099490D02*
X1550249Y1099708D01*
X1550396Y1100443D01*
X1550816Y1100505D01*
X1551012Y1100466D01*
X1550809Y1099451D01*
X1550613Y1099490D01*
G37*
G36*
G01X1550517Y1096970D02*
X1550881Y1096752D01*
X1550734Y1096016D01*
X1550314Y1095955D01*
X1550118Y1095994D01*
X1550321Y1097009D01*
X1550517Y1096970D01*
G37*
G36*
G01X1550152Y1097186D02*
X1549788Y1097404D01*
X1549935Y1098139D01*
X1550355Y1098200D01*
X1550551Y1098161D01*
X1550348Y1097146D01*
X1550152Y1097186D01*
G37*
G36*
G01X1551282Y1106162D02*
X1550882Y1106305D01*
Y1107055D01*
X1551282Y1107197D01*
X1551482D01*
Y1106162D01*
X1551282D01*
G37*
G36*
G01Y1108512D02*
X1550882Y1108655D01*
Y1109405D01*
X1551282Y1109547D01*
X1551482D01*
Y1108512D01*
X1551282D01*
G37*
G36*
G01Y1110862D02*
X1550882Y1111005D01*
Y1111755D01*
X1551282Y1111897D01*
X1551482D01*
Y1110862D01*
X1551282D01*
G37*
G36*
G01Y1103812D02*
X1550882Y1103955D01*
Y1104705D01*
X1551282Y1104847D01*
X1551482D01*
Y1103812D01*
X1551282D01*
G37*
G36*
G01X1551682Y1106023D02*
X1552082Y1105880D01*
Y1105130D01*
X1551682Y1104987D01*
X1551482D01*
Y1106023D01*
X1551682D01*
G37*
G36*
G01Y1110723D02*
X1552082Y1110580D01*
Y1109830D01*
X1551682Y1109687D01*
X1551482D01*
Y1110723D01*
X1551682D01*
G37*
G36*
G01Y1108373D02*
X1552082Y1108230D01*
Y1107480D01*
X1551682Y1107337D01*
X1551482D01*
Y1108373D01*
X1551682D01*
G37*
G36*
G01X1549799Y1099510D02*
X1550163Y1099292D01*
X1550016Y1098556D01*
X1549596Y1098495D01*
X1549399Y1098534D01*
X1549603Y1099549D01*
X1549799Y1099510D01*
G37*
G36*
G01X1549434Y1099726D02*
X1549070Y1099944D01*
X1549217Y1100679D01*
X1549637Y1100741D01*
X1549833Y1100701D01*
X1549630Y1099687D01*
X1549434Y1099726D01*
G37*
G36*
G01X1549338Y1097206D02*
X1549702Y1096987D01*
X1549555Y1096252D01*
X1549135Y1096191D01*
X1548939Y1096230D01*
X1549142Y1097245D01*
X1549338Y1097206D01*
G37*
G36*
G01X1548973Y1097421D02*
X1548609Y1097640D01*
X1548756Y1098375D01*
X1549176Y1098436D01*
X1549372Y1098397D01*
X1549169Y1097382D01*
X1548973Y1097421D01*
G37*
G36*
G01X1550259Y1101814D02*
X1550624Y1101596D01*
X1550477Y1100861D01*
X1550056Y1100799D01*
X1549860Y1100839D01*
X1550063Y1101854D01*
X1550259Y1101814D01*
G37*
G36*
G01X1550082Y1108512D02*
X1549682Y1108655D01*
Y1109405D01*
X1550082Y1109547D01*
X1550282D01*
Y1108512D01*
X1550082D01*
G37*
G36*
G01X1550482Y1106023D02*
X1550882Y1105880D01*
Y1105130D01*
X1550482Y1104987D01*
X1550282D01*
Y1106023D01*
X1550482D01*
G37*
G36*
G01Y1110723D02*
X1550882Y1110580D01*
Y1109830D01*
X1550482Y1109687D01*
X1550282D01*
Y1110723D01*
X1550482D01*
G37*
G36*
G01X1550082Y1110862D02*
X1549682Y1111005D01*
Y1111755D01*
X1550082Y1111897D01*
X1550282D01*
Y1110862D01*
X1550082D01*
G37*
G36*
G01X1550482Y1108373D02*
X1550882Y1108230D01*
Y1107480D01*
X1550482Y1107337D01*
X1550282D01*
Y1108373D01*
X1550482D01*
G37*
G36*
G01X1550082Y1106162D02*
X1549682Y1106305D01*
Y1107055D01*
X1550082Y1107197D01*
X1550282D01*
Y1106162D01*
X1550082D01*
G37*
G36*
G01X1551330Y1096950D02*
X1550965Y1097168D01*
X1551113Y1097904D01*
X1551533Y1097965D01*
X1551729Y1097926D01*
X1551526Y1096911D01*
X1551330Y1096950D01*
G37*
G36*
G01X1551791Y1099254D02*
X1551426Y1099473D01*
X1551573Y1100208D01*
X1551994Y1100269D01*
X1552190Y1100230D01*
X1551987Y1099215D01*
X1551791Y1099254D01*
G37*
G36*
G01X1552616Y1101343D02*
X1552981Y1101125D01*
X1552834Y1100389D01*
X1552413Y1100328D01*
X1552217Y1100367D01*
X1552420Y1101382D01*
X1552616Y1101343D01*
G37*
G36*
G01X1552155Y1099039D02*
X1552520Y1098820D01*
X1552373Y1098085D01*
X1551952Y1098024D01*
X1551756Y1098063D01*
X1551959Y1099078D01*
X1552155Y1099039D01*
G37*
G36*
G01X1552882Y1106023D02*
X1553282Y1105880D01*
Y1105130D01*
X1552882Y1104987D01*
X1552682D01*
Y1106023D01*
X1552882D01*
G37*
G36*
G01X1552482Y1106162D02*
X1552082Y1106305D01*
Y1107055D01*
X1552482Y1107197D01*
X1552682D01*
Y1106162D01*
X1552482D01*
G37*
G36*
G01Y1110862D02*
X1552082Y1111005D01*
Y1111755D01*
X1552482Y1111897D01*
X1552682D01*
Y1110862D01*
X1552482D01*
G37*
G36*
G01Y1108512D02*
X1552082Y1108655D01*
Y1109405D01*
X1552482Y1109547D01*
X1552682D01*
Y1108512D01*
X1552482D01*
G37*
G36*
G01X1552882Y1110723D02*
X1553282Y1110580D01*
Y1109830D01*
X1552882Y1109687D01*
X1552682D01*
Y1110723D01*
X1552882D01*
G37*
G36*
G01Y1108373D02*
X1553282Y1108230D01*
Y1107480D01*
X1552882Y1107337D01*
X1552682D01*
Y1108373D01*
X1552882D01*
G37*
G36*
G01X1552482Y1103812D02*
X1552082Y1103955D01*
Y1104705D01*
X1552482Y1104847D01*
X1552682D01*
Y1103812D01*
X1552482D01*
G37*
G36*
G01X1554411Y1100996D02*
X1554046Y1101214D01*
X1554193Y1101949D01*
X1554614Y1102011D01*
X1554810Y1101971D01*
X1554607Y1100957D01*
X1554411Y1100996D01*
G37*
G36*
G01X1554775Y1100780D02*
X1555140Y1100562D01*
X1554993Y1099826D01*
X1554572Y1099765D01*
X1554376Y1099804D01*
X1554579Y1100819D01*
X1554775Y1100780D01*
G37*
G36*
G01X1553950Y1098691D02*
X1553585Y1098910D01*
X1553732Y1099645D01*
X1554153Y1099706D01*
X1554349Y1099667D01*
X1554146Y1098652D01*
X1553950Y1098691D01*
G37*
G36*
G01X1554314Y1098476D02*
X1554679Y1098257D01*
X1554532Y1097522D01*
X1554111Y1097461D01*
X1553915Y1097500D01*
X1554118Y1098515D01*
X1554314Y1098476D01*
G37*
G36*
G01X1553489Y1096387D02*
X1553124Y1096605D01*
X1553272Y1097341D01*
X1553692Y1097402D01*
X1553888Y1097363D01*
X1553685Y1096348D01*
X1553489Y1096387D01*
G37*
G36*
G01X1555697Y1105389D02*
X1556061Y1105171D01*
X1555914Y1104435D01*
X1555494Y1104374D01*
X1555298Y1104413D01*
X1555501Y1105428D01*
X1555697Y1105389D01*
G37*
G36*
G01X1555332Y1105604D02*
X1554968Y1105823D01*
X1555115Y1106558D01*
X1555535Y1106619D01*
X1555732Y1106580D01*
X1555529Y1105565D01*
X1555332Y1105604D01*
G37*
G36*
G01X1556158Y1107693D02*
X1556522Y1107475D01*
X1556375Y1106739D01*
X1555955Y1106678D01*
X1555759Y1106717D01*
X1555962Y1107732D01*
X1556158Y1107693D01*
G37*
G36*
G01X1554871Y1103300D02*
X1554507Y1103518D01*
X1554654Y1104254D01*
X1555075Y1104315D01*
X1555271Y1104276D01*
X1555068Y1103261D01*
X1554871Y1103300D01*
G37*
G36*
G01X1555236Y1103084D02*
X1555601Y1102866D01*
X1555453Y1102131D01*
X1555033Y1102069D01*
X1554837Y1102109D01*
X1555040Y1103124D01*
X1555236Y1103084D01*
G37*
G36*
G01X1555845Y1095916D02*
X1555481Y1096134D01*
X1555628Y1096869D01*
X1556048Y1096931D01*
X1556244Y1096891D01*
X1556041Y1095876D01*
X1555845Y1095916D01*
G37*
G36*
G01X1556671Y1098004D02*
X1557035Y1097786D01*
X1556888Y1097051D01*
X1556468Y1096989D01*
X1556272Y1097029D01*
X1556475Y1098044D01*
X1556671Y1098004D01*
G37*
G36*
G01X1556767Y1100524D02*
X1556403Y1100743D01*
X1556550Y1101478D01*
X1556971Y1101539D01*
X1557167Y1101500D01*
X1556964Y1100485D01*
X1556767Y1100524D01*
G37*
G36*
G01X1556306Y1098220D02*
X1555942Y1098438D01*
X1556089Y1099174D01*
X1556509Y1099235D01*
X1556705Y1099196D01*
X1556502Y1098181D01*
X1556306Y1098220D01*
G37*
G36*
G01X1557132Y1100309D02*
X1557496Y1100090D01*
X1557349Y1099355D01*
X1556929Y1099294D01*
X1556733Y1099333D01*
X1556936Y1100348D01*
X1557132Y1100309D01*
G37*
G36*
G01X1557593Y1102613D02*
X1557958Y1102395D01*
X1557810Y1101659D01*
X1557390Y1101598D01*
X1557194Y1101637D01*
X1557397Y1102652D01*
X1557593Y1102613D01*
G37*
G36*
G01X1557229Y1102829D02*
X1556864Y1103047D01*
X1557011Y1103782D01*
X1557432Y1103844D01*
X1557628Y1103804D01*
X1557425Y1102789D01*
X1557229Y1102829D01*
G37*
G36*
G01X1555588Y1100760D02*
X1555224Y1100978D01*
X1555371Y1101714D01*
X1555791Y1101775D01*
X1555987Y1101736D01*
X1555784Y1100721D01*
X1555588Y1100760D01*
G37*
G36*
G01X1555127Y1098456D02*
X1554763Y1098674D01*
X1554910Y1099410D01*
X1555330Y1099471D01*
X1555526Y1099432D01*
X1555323Y1098417D01*
X1555127Y1098456D01*
G37*
G36*
G01X1555953Y1100544D02*
X1556317Y1100326D01*
X1556170Y1099591D01*
X1555750Y1099530D01*
X1555554Y1099569D01*
X1555757Y1100584D01*
X1555953Y1100544D01*
G37*
G36*
G01X1554666Y1096152D02*
X1554302Y1096370D01*
X1554449Y1097105D01*
X1554869Y1097166D01*
X1555065Y1097127D01*
X1554862Y1096112D01*
X1554666Y1096152D01*
G37*
G36*
G01X1555492Y1098240D02*
X1555856Y1098022D01*
X1555709Y1097286D01*
X1555289Y1097225D01*
X1555093Y1097264D01*
X1555296Y1098279D01*
X1555492Y1098240D01*
G37*
G36*
G01X1556875Y1105153D02*
X1557239Y1104935D01*
X1557092Y1104200D01*
X1556672Y1104138D01*
X1556475Y1104178D01*
X1556679Y1105192D01*
X1556875Y1105153D01*
G37*
G36*
G01X1556049Y1103065D02*
X1555685Y1103283D01*
X1555832Y1104018D01*
X1556252Y1104079D01*
X1556448Y1104040D01*
X1556245Y1103025D01*
X1556049Y1103065D01*
G37*
G36*
G01X1556414Y1102849D02*
X1556778Y1102631D01*
X1556631Y1101895D01*
X1556211Y1101834D01*
X1556015Y1101873D01*
X1556218Y1102888D01*
X1556414Y1102849D01*
G37*
G36*
G01X1557945Y1100289D02*
X1557581Y1100507D01*
X1557728Y1101242D01*
X1558148Y1101304D01*
X1558344Y1101264D01*
X1558141Y1100250D01*
X1557945Y1100289D01*
G37*
G36*
G01X1557484Y1097984D02*
X1557120Y1098203D01*
X1557267Y1098938D01*
X1557687Y1098999D01*
X1557883Y1098960D01*
X1557680Y1097945D01*
X1557484Y1097984D01*
G37*
G36*
G01X1558310Y1100073D02*
X1558674Y1099855D01*
X1558527Y1099119D01*
X1558107Y1099058D01*
X1557911Y1099097D01*
X1558114Y1100112D01*
X1558310Y1100073D01*
G37*
G36*
G01X1557849Y1097769D02*
X1558213Y1097551D01*
X1558066Y1096815D01*
X1557646Y1096754D01*
X1557450Y1096793D01*
X1557653Y1097808D01*
X1557849Y1097769D01*
G37*
G36*
G01X1542067Y1117480D02*
X1542467Y1117337D01*
Y1116587D01*
X1542067Y1116445D01*
X1541867D01*
Y1117480D01*
X1542067D01*
G37*
G36*
G01Y1115130D02*
X1542467Y1114987D01*
Y1114237D01*
X1542067Y1114095D01*
X1541867D01*
Y1115130D01*
X1542067D01*
G37*
G36*
G01Y1129230D02*
X1542467Y1129087D01*
Y1128337D01*
X1542067Y1128195D01*
X1541867D01*
Y1129230D01*
X1542067D01*
G37*
G36*
G01Y1126880D02*
X1542467Y1126737D01*
Y1125987D01*
X1542067Y1125845D01*
X1541867D01*
Y1126880D01*
X1542067D01*
G37*
G36*
G01Y1119830D02*
X1542467Y1119687D01*
Y1118937D01*
X1542067Y1118795D01*
X1541867D01*
Y1119830D01*
X1542067D01*
G37*
G36*
G01Y1122180D02*
X1542467Y1122037D01*
Y1121287D01*
X1542067Y1121145D01*
X1541867D01*
Y1122180D01*
X1542067D01*
G37*
G36*
G01Y1124530D02*
X1542467Y1124387D01*
Y1123637D01*
X1542067Y1123495D01*
X1541867D01*
Y1124530D01*
X1542067D01*
G37*
G36*
G01X1542867Y1112919D02*
X1542467Y1113062D01*
Y1113812D01*
X1542867Y1113955D01*
X1543067D01*
Y1112919D01*
X1542867D01*
G37*
G36*
G01Y1115269D02*
X1542467Y1115412D01*
Y1116162D01*
X1542867Y1116305D01*
X1543067D01*
Y1115269D01*
X1542867D01*
G37*
G36*
G01Y1117619D02*
X1542467Y1117762D01*
Y1118512D01*
X1542867Y1118655D01*
X1543067D01*
Y1117619D01*
X1542867D01*
G37*
G36*
G01X1543267Y1117480D02*
X1543667Y1117337D01*
Y1116587D01*
X1543267Y1116445D01*
X1543067D01*
Y1117480D01*
X1543267D01*
G37*
G36*
G01Y1115130D02*
X1543667Y1114987D01*
Y1114237D01*
X1543267Y1114095D01*
X1543067D01*
Y1115130D01*
X1543267D01*
G37*
G36*
G01X1542867Y1119969D02*
X1542467Y1120112D01*
Y1120862D01*
X1542867Y1121005D01*
X1543067D01*
Y1119969D01*
X1542867D01*
G37*
G36*
G01Y1122319D02*
X1542467Y1122462D01*
Y1123212D01*
X1542867Y1123355D01*
X1543067D01*
Y1122319D01*
X1542867D01*
G37*
G36*
G01Y1124669D02*
X1542467Y1124812D01*
Y1125562D01*
X1542867Y1125705D01*
X1543067D01*
Y1124669D01*
X1542867D01*
G37*
G36*
G01Y1127019D02*
X1542467Y1127162D01*
Y1127912D01*
X1542867Y1128055D01*
X1543067D01*
Y1127019D01*
X1542867D01*
G37*
G36*
G01X1543267Y1122180D02*
X1543667Y1122037D01*
Y1121287D01*
X1543267Y1121145D01*
X1543067D01*
Y1122180D01*
X1543267D01*
G37*
G36*
G01Y1119830D02*
X1543667Y1119687D01*
Y1118937D01*
X1543267Y1118795D01*
X1543067D01*
Y1119830D01*
X1543267D01*
G37*
G36*
G01Y1124530D02*
X1543667Y1124387D01*
Y1123637D01*
X1543267Y1123495D01*
X1543067D01*
Y1124530D01*
X1543267D01*
G37*
G36*
G01Y1126880D02*
X1543667Y1126737D01*
Y1125987D01*
X1543267Y1125845D01*
X1543067D01*
Y1126880D01*
X1543267D01*
G37*
G36*
G01Y1129230D02*
X1543667Y1129087D01*
Y1128337D01*
X1543267Y1128195D01*
X1543067D01*
Y1129230D01*
X1543267D01*
G37*
G36*
G01X1548882Y1117912D02*
X1548482Y1118055D01*
Y1118805D01*
X1548882Y1118947D01*
X1549082D01*
Y1117912D01*
X1548882D01*
G37*
G36*
G01X1549282Y1117773D02*
X1549682Y1117630D01*
Y1116880D01*
X1549282Y1116737D01*
X1549082D01*
Y1117773D01*
X1549282D01*
G37*
G36*
G01Y1113073D02*
X1549682Y1112930D01*
Y1112180D01*
X1549282Y1112037D01*
X1549082D01*
Y1113073D01*
X1549282D01*
G37*
G36*
G01Y1115423D02*
X1549682Y1115280D01*
Y1114530D01*
X1549282Y1114387D01*
X1549082D01*
Y1115423D01*
X1549282D01*
G37*
G36*
G01X1548882Y1115562D02*
X1548482Y1115705D01*
Y1116455D01*
X1548882Y1116597D01*
X1549082D01*
Y1115562D01*
X1548882D01*
G37*
G36*
G01Y1113212D02*
X1548482Y1113355D01*
Y1114105D01*
X1548882Y1114247D01*
X1549082D01*
Y1113212D01*
X1548882D01*
G37*
G36*
G01X1549282Y1122473D02*
X1549682Y1122330D01*
Y1121580D01*
X1549282Y1121437D01*
X1549082D01*
Y1122473D01*
X1549282D01*
G37*
G36*
G01Y1120123D02*
X1549682Y1119980D01*
Y1119230D01*
X1549282Y1119087D01*
X1549082D01*
Y1120123D01*
X1549282D01*
G37*
G36*
G01X1548882Y1122612D02*
X1548482Y1122755D01*
Y1123505D01*
X1548882Y1123647D01*
X1549082D01*
Y1122612D01*
X1548882D01*
G37*
G36*
G01Y1120262D02*
X1548482Y1120405D01*
Y1121155D01*
X1548882Y1121297D01*
X1549082D01*
Y1120262D01*
X1548882D01*
G37*
G36*
G01X1551282Y1117912D02*
X1550882Y1118055D01*
Y1118805D01*
X1551282Y1118947D01*
X1551482D01*
Y1117912D01*
X1551282D01*
G37*
G36*
G01Y1115562D02*
X1550882Y1115705D01*
Y1116455D01*
X1551282Y1116597D01*
X1551482D01*
Y1115562D01*
X1551282D01*
G37*
G36*
G01Y1113212D02*
X1550882Y1113355D01*
Y1114105D01*
X1551282Y1114247D01*
X1551482D01*
Y1113212D01*
X1551282D01*
G37*
G36*
G01X1551682Y1113073D02*
X1552082Y1112930D01*
Y1112180D01*
X1551682Y1112037D01*
X1551482D01*
Y1113073D01*
X1551682D01*
G37*
G36*
G01Y1117773D02*
X1552082Y1117630D01*
Y1116880D01*
X1551682Y1116737D01*
X1551482D01*
Y1117773D01*
X1551682D01*
G37*
G36*
G01Y1115423D02*
X1552082Y1115280D01*
Y1114530D01*
X1551682Y1114387D01*
X1551482D01*
Y1115423D01*
X1551682D01*
G37*
G36*
G01Y1120123D02*
X1552082Y1119980D01*
Y1119230D01*
X1551682Y1119087D01*
X1551482D01*
Y1120123D01*
X1551682D01*
G37*
G36*
G01X1550082Y1117912D02*
X1549682Y1118055D01*
Y1118805D01*
X1550082Y1118947D01*
X1550282D01*
Y1117912D01*
X1550082D01*
G37*
G36*
G01X1550482Y1117773D02*
X1550882Y1117630D01*
Y1116880D01*
X1550482Y1116737D01*
X1550282D01*
Y1117773D01*
X1550482D01*
G37*
G36*
G01Y1115423D02*
X1550882Y1115280D01*
Y1114530D01*
X1550482Y1114387D01*
X1550282D01*
Y1115423D01*
X1550482D01*
G37*
G36*
G01Y1113073D02*
X1550882Y1112930D01*
Y1112180D01*
X1550482Y1112037D01*
X1550282D01*
Y1113073D01*
X1550482D01*
G37*
G36*
G01X1550082Y1115562D02*
X1549682Y1115705D01*
Y1116455D01*
X1550082Y1116597D01*
X1550282D01*
Y1115562D01*
X1550082D01*
G37*
G36*
G01Y1113212D02*
X1549682Y1113355D01*
Y1114105D01*
X1550082Y1114247D01*
X1550282D01*
Y1113212D01*
X1550082D01*
G37*
G36*
G01X1550482Y1120123D02*
X1550882Y1119980D01*
Y1119230D01*
X1550482Y1119087D01*
X1550282D01*
Y1120123D01*
X1550482D01*
G37*
G36*
G01X1550082Y1122612D02*
X1549682Y1122755D01*
Y1123505D01*
X1550082Y1123647D01*
X1550282D01*
Y1122612D01*
X1550082D01*
G37*
G36*
G01Y1120262D02*
X1549682Y1120405D01*
Y1121155D01*
X1550082Y1121297D01*
X1550282D01*
Y1120262D01*
X1550082D01*
G37*
G36*
G01X1550482Y1122473D02*
X1550882Y1122330D01*
Y1121580D01*
X1550482Y1121437D01*
X1550282D01*
Y1122473D01*
X1550482D01*
G37*
G36*
G01X1552482Y1117912D02*
X1552082Y1118055D01*
Y1118805D01*
X1552482Y1118947D01*
X1552682D01*
Y1117912D01*
X1552482D01*
G37*
G36*
G01Y1115562D02*
X1552082Y1115705D01*
Y1116455D01*
X1552482Y1116597D01*
X1552682D01*
Y1115562D01*
X1552482D01*
G37*
G36*
G01Y1113212D02*
X1552082Y1113355D01*
Y1114105D01*
X1552482Y1114247D01*
X1552682D01*
Y1113212D01*
X1552482D01*
G37*
G36*
G01X1552882Y1117773D02*
X1553282Y1117630D01*
Y1116880D01*
X1552882Y1116737D01*
X1552682D01*
Y1117773D01*
X1552882D01*
G37*
G36*
G01Y1115423D02*
X1553282Y1115280D01*
Y1114530D01*
X1552882Y1114387D01*
X1552682D01*
Y1115423D01*
X1552882D01*
G37*
G36*
G01Y1113073D02*
X1553282Y1112930D01*
Y1112180D01*
X1552882Y1112037D01*
X1552682D01*
Y1113073D01*
X1552882D01*
G37*
G36*
G01X1542067Y1133930D02*
X1542467Y1133787D01*
Y1133037D01*
X1542067Y1132895D01*
X1541867D01*
Y1133930D01*
X1542067D01*
G37*
G36*
G01Y1131580D02*
X1542467Y1131437D01*
Y1130687D01*
X1542067Y1130545D01*
X1541867D01*
Y1131580D01*
X1542067D01*
G37*
G36*
G01Y1138630D02*
X1542467Y1138487D01*
Y1137737D01*
X1542067Y1137595D01*
X1541867D01*
Y1138630D01*
X1542067D01*
G37*
G36*
G01Y1136280D02*
X1542467Y1136137D01*
Y1135387D01*
X1542067Y1135245D01*
X1541867D01*
Y1136280D01*
X1542067D01*
G37*
G36*
G01X1542867Y1129369D02*
X1542467Y1129512D01*
Y1130262D01*
X1542867Y1130405D01*
X1543067D01*
Y1129369D01*
X1542867D01*
G37*
G36*
G01Y1131719D02*
X1542467Y1131862D01*
Y1132612D01*
X1542867Y1132755D01*
X1543067D01*
Y1131719D01*
X1542867D01*
G37*
G36*
G01Y1134069D02*
X1542467Y1134212D01*
Y1134962D01*
X1542867Y1135105D01*
X1543067D01*
Y1134069D01*
X1542867D01*
G37*
G36*
G01X1543267Y1131580D02*
X1543667Y1131437D01*
Y1130687D01*
X1543267Y1130545D01*
X1543067D01*
Y1131580D01*
X1543267D01*
G37*
G36*
G01Y1133930D02*
X1543667Y1133787D01*
Y1133037D01*
X1543267Y1132895D01*
X1543067D01*
Y1133930D01*
X1543267D01*
G37*
G36*
G01X1542867Y1136419D02*
X1542467Y1136562D01*
Y1137312D01*
X1542867Y1137455D01*
X1543067D01*
Y1136419D01*
X1542867D01*
G37*
G36*
G01X1543267Y1136280D02*
X1543667Y1136137D01*
Y1135387D01*
X1543267Y1135245D01*
X1543067D01*
Y1136280D01*
X1543267D01*
G37*
G36*
G01Y1138630D02*
X1543667Y1138487D01*
Y1137737D01*
X1543267Y1137595D01*
X1543067D01*
Y1138630D01*
X1543267D01*
G37*
G36*
G01X1558717Y1575686D02*
G03I-720J0D01*
G37*
G36*
G01Y1580678D02*
G03I-720J0D01*
G37*
G36*
G01X1551613D02*
G03I-720J0D01*
G37*
G36*
G01X1546657D02*
G03I-720J0D01*
G37*
G36*
G01X1551613Y1575686D02*
G03I-720J0D01*
G37*
G36*
G01X1546657D02*
G03I-720J0D01*
G37*
G36*
G01X1556913Y1599884D02*
G03I-720J0D01*
G37*
G36*
G01X1551957D02*
G03I-720J0D01*
G37*
G36*
G01X1544853Y1599790D02*
G03I-720J0D01*
G37*
G36*
G01X1558717Y1587598D02*
G03I-720J0D01*
G37*
G36*
G01Y1592590D02*
G03I-720J0D01*
G37*
G36*
G01X1546657D02*
G03I-720J0D01*
G37*
G36*
G01X1551613D02*
G03I-720J0D01*
G37*
G36*
G01Y1587598D02*
G03I-720J0D01*
G37*
G36*
G01X1546657D02*
G03I-720J0D01*
G37*
G36*
G01X1551957Y1616788D02*
G03I-720J0D01*
G37*
G36*
G01X1556913D02*
G03I-720J0D01*
G37*
G36*
G01Y1604876D02*
G03I-720J0D01*
G37*
G36*
G01X1551957D02*
G03I-720J0D01*
G37*
G36*
G01X1556913Y1611796D02*
G03I-720J0D01*
G37*
G36*
G01X1551957D02*
G03I-720J0D01*
G37*
G36*
G01X1544853Y1604876D02*
G03I-720J0D01*
G37*
G36*
G01Y1611796D02*
G03I-720J0D01*
G37*
G36*
G01Y1616788D02*
G03I-720J0D01*
G37*
G36*
G01X1561311Y16999D02*
G03I-720J0D01*
G37*
G36*
G01Y21991D02*
G03I-720J0D01*
G37*
G36*
G01X1570528Y16999D02*
G03I-720J0D01*
G37*
G36*
G01Y21991D02*
G03I-720J0D01*
G37*
G36*
G01X1575484Y16999D02*
G03I-720J0D01*
G37*
G36*
G01Y21991D02*
G03I-720J0D01*
G37*
G36*
G01X1563311Y19495D02*
G03I-720J0D01*
G37*
G36*
G01X1568528D02*
G03I-720J0D01*
G37*
G36*
G01X1568379Y23935D02*
G03I-720J0D01*
G37*
G36*
G01X1563423D02*
G03I-720J0D01*
G37*
G36*
G01X1561423Y25931D02*
G03I-720J0D01*
G37*
G36*
G01X1570379D02*
G03I-720J0D01*
G37*
G36*
G01X1575596D02*
G03I-720J0D01*
G37*
G36*
G01X1564494Y69297D02*
G03I-720J0D01*
G37*
G36*
G01X1562494Y66801D02*
G03I-720J0D01*
G37*
G36*
G01Y71793D02*
G03I-720J0D01*
G37*
G36*
G01X1566538Y75297D02*
G03I-720J0D01*
G37*
G36*
G01X1575494D02*
G03I-720J0D01*
G37*
G36*
G01X1573494Y77793D02*
G03I-720J0D01*
G37*
G36*
G01Y72801D02*
G03I-720J0D01*
G37*
G36*
G01X1568538Y77793D02*
G03I-720J0D01*
G37*
G36*
G01Y72801D02*
G03I-720J0D01*
G37*
G36*
G01X1582735Y616232D02*
X1611330D01*
X1612078Y615484D01*
Y584820D01*
X1610970Y583712D01*
X1566940D01*
X1566270Y584382D01*
Y613395D01*
X1569107Y616232D01*
X1573397D01*
X1573414Y616051D01*
G03X1577000Y612786I3586J337D01*
G03X1578994Y613389I-1J3602D01*
G01X1579045Y613422D01*
X1579925D01*
X1582735Y616232D01*
G37*
G36*
G01X1565540Y656892D02*
X1568802D01*
X1571103Y654592D01*
X1602660D01*
X1603560Y655492D01*
X1605110D01*
X1605258Y655343D01*
Y620110D01*
X1605270Y620081D01*
Y619302D01*
X1604200Y618232D01*
X1590540D01*
X1588067Y620705D01*
X1580899D01*
G02X1580500Y621133I0J400D01*
G03X1580502Y621162I-399J42D01*
G01Y627362D01*
G03X1580100Y627764I-402J0D01*
G01X1573900D01*
G03X1573498Y627362I0J-402D01*
G01Y621162D01*
G03X1573500Y621133I401J13D01*
G02X1573101Y620705I-399J-28D01*
G01X1565659D01*
X1562710Y623654D01*
Y651772D01*
X1564110Y653172D01*
X1564138Y653187D01*
G03X1565506Y655416I-1133J2230D01*
G03X1565282Y656450I-2502J-1D01*
G01X1565224Y656576D01*
X1565540Y656892D01*
G37*
G36*
G01X1603420Y657630D02*
X1602170Y656380D01*
X1572552D01*
X1568716Y660216D01*
Y663254D01*
X1567150Y664820D01*
Y722502D01*
X1573021Y728373D01*
Y733361D01*
X1571820Y734562D01*
X1568920D01*
X1568620Y734862D01*
Y738062D01*
X1569720Y739162D01*
X1576720D01*
X1576760Y739122D01*
X1581840D01*
X1582700Y738262D01*
Y731062D01*
X1585375Y728387D01*
X1602270D01*
X1603420Y727237D01*
Y657630D01*
G37*
G36*
G01X1567100Y765032D02*
X1594142D01*
X1596182Y762992D01*
X1751130D01*
X1758171Y755951D01*
Y748156D01*
X1755512D01*
G03Y740952I0J-3602D01*
G01X1758171D01*
Y727431D01*
X1758320Y727282D01*
Y689642D01*
X1757280Y688602D01*
X1736290D01*
X1734830Y690062D01*
Y722409D01*
X1726290Y730949D01*
X1707482D01*
G03X1702588I-2447J-1739D01*
G01X1603119D01*
X1601346Y732722D01*
Y746234D01*
X1597992Y749588D01*
X1590741D01*
X1589367Y750962D01*
X1582800D01*
X1581110Y749272D01*
Y742812D01*
X1579410Y741112D01*
X1566920D01*
X1565740Y742292D01*
Y763672D01*
X1567100Y765032D01*
G37*
G36*
G01X1560370Y898312D02*
X1559970Y898455D01*
Y899205D01*
X1560370Y899347D01*
X1560570D01*
Y898312D01*
X1560370D01*
G37*
G36*
G01X1560770Y900522D02*
X1561170Y900379D01*
Y899629D01*
X1560770Y899487D01*
X1560570D01*
Y900522D01*
X1560770D01*
G37*
G36*
G01X1560370Y893612D02*
X1559970Y893755D01*
Y894505D01*
X1560370Y894647D01*
X1560570D01*
Y893612D01*
X1560370D01*
G37*
G36*
G01Y895962D02*
X1559970Y896105D01*
Y896855D01*
X1560370Y896997D01*
X1560570D01*
Y895962D01*
X1560370D01*
G37*
G36*
G01X1560770Y895822D02*
X1561170Y895679D01*
Y894929D01*
X1560770Y894787D01*
X1560570D01*
Y895822D01*
X1560770D01*
G37*
G36*
G01Y898172D02*
X1561170Y898029D01*
Y897279D01*
X1560770Y897137D01*
X1560570D01*
Y898172D01*
X1560770D01*
G37*
G36*
G01X1558370Y895822D02*
X1558770Y895679D01*
Y894929D01*
X1558370Y894787D01*
X1558170D01*
Y895822D01*
X1558370D01*
G37*
G36*
G01Y898172D02*
X1558770Y898029D01*
Y897279D01*
X1558370Y897137D01*
X1558170D01*
Y898172D01*
X1558370D01*
G37*
G36*
G01Y893472D02*
X1558770Y893329D01*
Y892579D01*
X1558370Y892437D01*
X1558170D01*
Y893472D01*
X1558370D01*
G37*
G36*
G01Y900522D02*
X1558770Y900379D01*
Y899629D01*
X1558370Y899487D01*
X1558170D01*
Y900522D01*
X1558370D01*
G37*
G36*
G01X1559170Y898312D02*
X1558770Y898455D01*
Y899205D01*
X1559170Y899347D01*
X1559370D01*
Y898312D01*
X1559170D01*
G37*
G36*
G01X1559570Y900522D02*
X1559970Y900379D01*
Y899629D01*
X1559570Y899487D01*
X1559370D01*
Y900522D01*
X1559570D01*
G37*
G36*
G01Y898172D02*
X1559970Y898029D01*
Y897279D01*
X1559570Y897137D01*
X1559370D01*
Y898172D01*
X1559570D01*
G37*
G36*
G01Y895822D02*
X1559970Y895679D01*
Y894929D01*
X1559570Y894787D01*
X1559370D01*
Y895822D01*
X1559570D01*
G37*
G36*
G01X1559170Y895962D02*
X1558770Y896105D01*
Y896855D01*
X1559170Y896997D01*
X1559370D01*
Y895962D01*
X1559170D01*
G37*
G36*
G01X1561171Y915222D02*
X1560787Y915040D01*
X1560257Y915571D01*
X1560439Y915954D01*
X1560580Y916096D01*
X1561312Y915364D01*
X1561171Y915222D01*
G37*
G36*
G01X1559891Y917068D02*
X1560274Y917250D01*
X1560805Y916720D01*
X1560623Y916336D01*
X1560481Y916195D01*
X1559749Y916927D01*
X1559891Y917068D01*
G37*
G36*
G01X1559509Y916884D02*
X1559125Y916702D01*
X1558595Y917232D01*
X1558777Y917616D01*
X1558919Y917757D01*
X1559650Y917026D01*
X1559509Y916884D01*
G37*
G36*
G01X1564494Y911899D02*
X1564110Y911717D01*
X1563580Y912247D01*
X1563762Y912631D01*
X1563904Y912772D01*
X1564635Y912041D01*
X1564494Y911899D01*
G37*
G36*
G01X1562832Y913561D02*
X1562449Y913379D01*
X1561918Y913909D01*
X1562101Y914293D01*
X1562242Y914434D01*
X1562974Y913702D01*
X1562832Y913561D01*
G37*
G36*
G01X1561552Y915406D02*
X1561936Y915588D01*
X1562466Y915058D01*
X1562284Y914674D01*
X1562143Y914533D01*
X1561411Y915265D01*
X1561552Y915406D01*
G37*
G36*
G01X1563214Y913745D02*
X1563598Y913927D01*
X1564128Y913396D01*
X1563946Y913013D01*
X1563805Y912871D01*
X1563073Y913603D01*
X1563214Y913745D01*
G37*
G36*
G01X1566156Y910237D02*
X1565772Y910055D01*
X1565242Y910586D01*
X1565424Y910969D01*
X1565565Y911111D01*
X1566297Y910379D01*
X1566156Y910237D01*
G37*
G36*
G01X1559851Y913705D02*
X1560235Y913887D01*
X1560765Y913357D01*
X1560583Y912974D01*
X1560442Y912832D01*
X1559710Y913564D01*
X1559851Y913705D01*
G37*
G36*
G01X1561131Y911860D02*
X1560748Y911678D01*
X1560217Y912208D01*
X1560399Y912592D01*
X1560541Y912733D01*
X1561273Y912001D01*
X1561131Y911860D01*
G37*
G36*
G01X1558190Y915367D02*
X1558573Y915549D01*
X1559104Y915019D01*
X1558922Y914635D01*
X1558780Y914494D01*
X1558048Y915226D01*
X1558190Y915367D01*
G37*
G36*
G01X1559470Y913522D02*
X1559086Y913339D01*
X1558556Y913870D01*
X1558738Y914253D01*
X1558879Y914395D01*
X1559611Y913663D01*
X1559470Y913522D01*
G37*
G36*
G01X1561513Y912044D02*
X1561897Y912226D01*
X1562427Y911695D01*
X1562245Y911312D01*
X1562104Y911170D01*
X1561372Y911902D01*
X1561513Y912044D01*
G37*
G36*
G01X1564837Y908720D02*
X1565220Y908902D01*
X1565751Y908372D01*
X1565568Y907988D01*
X1565427Y907847D01*
X1564695Y908579D01*
X1564837Y908720D01*
G37*
G36*
G01X1563175Y910382D02*
X1563558Y910564D01*
X1564089Y910034D01*
X1563907Y909650D01*
X1563765Y909509D01*
X1563033Y910240D01*
X1563175Y910382D01*
G37*
G36*
G01X1564455Y908536D02*
X1564071Y908354D01*
X1563541Y908885D01*
X1563723Y909268D01*
X1563864Y909410D01*
X1564596Y908678D01*
X1564455Y908536D01*
G37*
G36*
G01X1562793Y910198D02*
X1562410Y910016D01*
X1561879Y910546D01*
X1562061Y910930D01*
X1562203Y911071D01*
X1562935Y910340D01*
X1562793Y910198D01*
G37*
G36*
G01X1560370Y900662D02*
X1559970Y900805D01*
Y901555D01*
X1560370Y901697D01*
X1560570D01*
Y900662D01*
X1560370D01*
G37*
G36*
G01X1560770Y902872D02*
X1561170Y902729D01*
Y901979D01*
X1560770Y901837D01*
X1560570D01*
Y902872D01*
X1560770D01*
G37*
G36*
G01X1558941Y906126D02*
X1559325Y906308D01*
X1559855Y905778D01*
X1559673Y905394D01*
X1559531Y905253D01*
X1558799Y905985D01*
X1558941Y906126D01*
G37*
G36*
G01X1559170Y900662D02*
X1558770Y900805D01*
Y901555D01*
X1559170Y901697D01*
X1559370D01*
Y900662D01*
X1559170D01*
G37*
G36*
G01X1559570Y902872D02*
X1559970Y902729D01*
Y901979D01*
X1559570Y901837D01*
X1559370D01*
Y902872D01*
X1559570D01*
G37*
G36*
G01X1562020Y916072D02*
X1561637Y915890D01*
X1561106Y916420D01*
X1561288Y916804D01*
X1561430Y916945D01*
X1562162Y916213D01*
X1562020Y916072D01*
G37*
G36*
G01X1562402Y916256D02*
X1562786Y916438D01*
X1563316Y915908D01*
X1563134Y915524D01*
X1562992Y915383D01*
X1562261Y916114D01*
X1562402Y916256D01*
G37*
G36*
G01X1563682Y914410D02*
X1563298Y914228D01*
X1562768Y914759D01*
X1562950Y915142D01*
X1563091Y915284D01*
X1563823Y914552D01*
X1563682Y914410D01*
G37*
G36*
G01X1564064Y914594D02*
X1564447Y914776D01*
X1564978Y914246D01*
X1564796Y913862D01*
X1564654Y913721D01*
X1563922Y914453D01*
X1564064Y914594D01*
G37*
G36*
G01X1560321Y914372D02*
X1559937Y914190D01*
X1559407Y914721D01*
X1559589Y915104D01*
X1559730Y915246D01*
X1560462Y914514D01*
X1560321Y914372D01*
G37*
G36*
G01X1559041Y916218D02*
X1559424Y916400D01*
X1559955Y915870D01*
X1559772Y915486D01*
X1559631Y915345D01*
X1558899Y916076D01*
X1559041Y916218D01*
G37*
G36*
G01X1560702Y914556D02*
X1561086Y914738D01*
X1561616Y914208D01*
X1561434Y913824D01*
X1561293Y913683D01*
X1560561Y914415D01*
X1560702Y914556D01*
G37*
G36*
G01X1561982Y912711D02*
X1561599Y912529D01*
X1561068Y913059D01*
X1561250Y913443D01*
X1561392Y913584D01*
X1562124Y912852D01*
X1561982Y912711D01*
G37*
G36*
G01X1563644Y911049D02*
X1563261Y910867D01*
X1562730Y911397D01*
X1562912Y911781D01*
X1563054Y911922D01*
X1563786Y911191D01*
X1563644Y911049D01*
G37*
G36*
G01X1562364Y912895D02*
X1562748Y913077D01*
X1563278Y912546D01*
X1563096Y912163D01*
X1562955Y912021D01*
X1562223Y912753D01*
X1562364Y912895D01*
G37*
G36*
G01X1564026Y911233D02*
X1564410Y911415D01*
X1564940Y910885D01*
X1564758Y910501D01*
X1564617Y910360D01*
X1563885Y911092D01*
X1564026Y911233D01*
G37*
G36*
G01X1565306Y909388D02*
X1564922Y909206D01*
X1564392Y909736D01*
X1564574Y910119D01*
X1564716Y910261D01*
X1565447Y909529D01*
X1565306Y909388D01*
G37*
G36*
G01X1565688Y909572D02*
X1566072Y909754D01*
X1566602Y909223D01*
X1566420Y908840D01*
X1566278Y908698D01*
X1565547Y909430D01*
X1565688Y909572D01*
G37*
G36*
G01X1566968Y907726D02*
X1566584Y907544D01*
X1566054Y908074D01*
X1566236Y908458D01*
X1566377Y908599D01*
X1567109Y907868D01*
X1566968Y907726D01*
G37*
G36*
G01X1558229Y918730D02*
X1558613Y918912D01*
X1559143Y918381D01*
X1558961Y917998D01*
X1558820Y917856D01*
X1558088Y918588D01*
X1558229Y918730D01*
G37*
G36*
G01X1560358Y917734D02*
X1559975Y917552D01*
X1559445Y918082D01*
X1559627Y918466D01*
X1559768Y918607D01*
X1560500Y917875D01*
X1560358Y917734D01*
G37*
G36*
G01X1560740Y917918D02*
X1561124Y918100D01*
X1561654Y917569D01*
X1561472Y917186D01*
X1561331Y917044D01*
X1560599Y917776D01*
X1560740Y917918D01*
G37*
G36*
G01X1559079Y919579D02*
X1559462Y919761D01*
X1559993Y919231D01*
X1559810Y918847D01*
X1559669Y918706D01*
X1558937Y919438D01*
X1559079Y919579D01*
G37*
G36*
G01X1559286Y1046940D02*
X1559468Y1046556D01*
X1558938Y1046026D01*
X1558554Y1046208D01*
X1558412Y1046349D01*
X1559144Y1047081D01*
X1559286Y1046940D01*
G37*
G36*
G01X1559873Y1062812D02*
X1560055Y1062428D01*
X1559525Y1061898D01*
X1559141Y1062080D01*
X1559000Y1062222D01*
X1559731Y1062953D01*
X1559873Y1062812D01*
G37*
G36*
G01X1559689Y1063194D02*
X1559507Y1063578D01*
X1560037Y1064108D01*
X1560421Y1063926D01*
X1560562Y1063784D01*
X1559830Y1063052D01*
X1559689Y1063194D01*
G37*
G36*
G01X1559024Y1063661D02*
X1559206Y1063277D01*
X1558676Y1062747D01*
X1558292Y1062929D01*
X1558151Y1063071D01*
X1558882Y1063802D01*
X1559024Y1063661D01*
G37*
G36*
G01X1558876Y1060683D02*
X1558694Y1061067D01*
X1559225Y1061597D01*
X1559608Y1061415D01*
X1559750Y1061274D01*
X1559018Y1060542D01*
X1558876Y1060683D01*
G37*
G36*
G01X1559060Y1060301D02*
X1559242Y1059918D01*
X1558712Y1059387D01*
X1558328Y1059570D01*
X1558187Y1059711D01*
X1558919Y1060443D01*
X1559060Y1060301D01*
G37*
G36*
G01X1560538Y1062345D02*
X1560356Y1062729D01*
X1560886Y1063259D01*
X1561270Y1063077D01*
X1561411Y1062935D01*
X1560679Y1062203D01*
X1560538Y1062345D01*
G37*
G36*
G01X1560722Y1061963D02*
X1560904Y1061579D01*
X1560374Y1061049D01*
X1559990Y1061231D01*
X1559849Y1061373D01*
X1560580Y1062104D01*
X1560722Y1061963D01*
G37*
G36*
G01X1562384Y1063625D02*
X1562566Y1063241D01*
X1562035Y1062711D01*
X1561652Y1062893D01*
X1561510Y1063034D01*
X1562242Y1063766D01*
X1562384Y1063625D01*
G37*
G36*
G01X1558217Y1051530D02*
X1558035Y1051914D01*
X1558565Y1052444D01*
X1558948Y1052262D01*
X1559090Y1052121D01*
X1558358Y1051389D01*
X1558217Y1051530D01*
G37*
G36*
G01X1560062Y1052810D02*
X1560244Y1052427D01*
X1559714Y1051896D01*
X1559330Y1052078D01*
X1559189Y1052220D01*
X1559921Y1052952D01*
X1560062Y1052810D01*
G37*
G36*
G01X1561724Y1054472D02*
X1561906Y1054088D01*
X1561376Y1053558D01*
X1560992Y1053740D01*
X1560851Y1053882D01*
X1561582Y1054613D01*
X1561724Y1054472D01*
G37*
G36*
G01X1559878Y1053192D02*
X1559696Y1053576D01*
X1560227Y1054106D01*
X1560610Y1053924D01*
X1560752Y1053783D01*
X1560020Y1053051D01*
X1559878Y1053192D01*
G37*
G36*
G01X1561540Y1054854D02*
X1561358Y1055237D01*
X1561888Y1055768D01*
X1562272Y1055586D01*
X1562413Y1055444D01*
X1561681Y1054712D01*
X1561540Y1054854D01*
G37*
G36*
G01X1563386Y1056134D02*
X1563568Y1055750D01*
X1563037Y1055220D01*
X1562654Y1055402D01*
X1562512Y1055543D01*
X1563244Y1056275D01*
X1563386Y1056134D01*
G37*
G36*
G01X1563202Y1056516D02*
X1563020Y1056899D01*
X1563550Y1057429D01*
X1563934Y1057247D01*
X1564075Y1057106D01*
X1563343Y1056374D01*
X1563202Y1056516D01*
G37*
G36*
G01X1560098Y1049451D02*
X1560281Y1049067D01*
X1559750Y1048537D01*
X1559367Y1048719D01*
X1559225Y1048860D01*
X1559957Y1049592D01*
X1560098Y1049451D01*
G37*
G36*
G01X1559915Y1049832D02*
X1559733Y1050216D01*
X1560263Y1050746D01*
X1560646Y1050564D01*
X1560788Y1050423D01*
X1560056Y1049691D01*
X1559915Y1049832D01*
G37*
G36*
G01X1558253Y1048171D02*
X1558071Y1048554D01*
X1558601Y1049085D01*
X1558985Y1048903D01*
X1559126Y1048761D01*
X1558394Y1048029D01*
X1558253Y1048171D01*
G37*
G36*
G01X1561760Y1051112D02*
X1561942Y1050729D01*
X1561412Y1050198D01*
X1561028Y1050380D01*
X1560887Y1050522D01*
X1561619Y1051254D01*
X1561760Y1051112D01*
G37*
G36*
G01X1561576Y1051494D02*
X1561394Y1051878D01*
X1561925Y1052408D01*
X1562308Y1052226D01*
X1562450Y1052085D01*
X1561718Y1051353D01*
X1561576Y1051494D01*
G37*
G36*
G01X1563422Y1052774D02*
X1563604Y1052390D01*
X1563074Y1051860D01*
X1562690Y1052042D01*
X1562549Y1052184D01*
X1563280Y1052915D01*
X1563422Y1052774D01*
G37*
G36*
G01X1565084Y1054436D02*
X1565266Y1054052D01*
X1564735Y1053522D01*
X1564352Y1053704D01*
X1564210Y1053845D01*
X1564942Y1054577D01*
X1565084Y1054436D01*
G37*
G36*
G01X1564900Y1054818D02*
X1564718Y1055201D01*
X1565248Y1055731D01*
X1565632Y1055549D01*
X1565773Y1055408D01*
X1565041Y1054676D01*
X1564900Y1054818D01*
G37*
G36*
G01X1563238Y1053156D02*
X1563056Y1053539D01*
X1563586Y1054070D01*
X1563970Y1053888D01*
X1564111Y1053746D01*
X1563379Y1053014D01*
X1563238Y1053156D01*
G37*
G36*
G01X1559249Y1050300D02*
X1559432Y1049916D01*
X1558901Y1049386D01*
X1558518Y1049568D01*
X1558376Y1049709D01*
X1559108Y1050441D01*
X1559249Y1050300D01*
G37*
G36*
G01X1560911Y1051961D02*
X1561093Y1051578D01*
X1560563Y1051047D01*
X1560179Y1051229D01*
X1560038Y1051371D01*
X1560770Y1052103D01*
X1560911Y1051961D01*
G37*
G36*
G01X1559066Y1050681D02*
X1558884Y1051065D01*
X1559414Y1051595D01*
X1559797Y1051413D01*
X1559939Y1051272D01*
X1559207Y1050540D01*
X1559066Y1050681D01*
G37*
G36*
G01X1560727Y1052343D02*
X1560545Y1052727D01*
X1561076Y1053257D01*
X1561459Y1053075D01*
X1561601Y1052934D01*
X1560869Y1052202D01*
X1560727Y1052343D01*
G37*
G36*
G01X1564235Y1055285D02*
X1564417Y1054901D01*
X1563886Y1054371D01*
X1563503Y1054553D01*
X1563361Y1054694D01*
X1564093Y1055426D01*
X1564235Y1055285D01*
G37*
G36*
G01X1562573Y1053623D02*
X1562755Y1053239D01*
X1562225Y1052709D01*
X1561841Y1052891D01*
X1561700Y1053033D01*
X1562431Y1053764D01*
X1562573Y1053623D01*
G37*
G36*
G01X1564051Y1055667D02*
X1563869Y1056050D01*
X1564399Y1056580D01*
X1564783Y1056398D01*
X1564924Y1056257D01*
X1564192Y1055525D01*
X1564051Y1055667D01*
G37*
G36*
G01X1562389Y1054005D02*
X1562207Y1054388D01*
X1562737Y1054919D01*
X1563121Y1054737D01*
X1563262Y1054595D01*
X1562530Y1053863D01*
X1562389Y1054005D01*
G37*
G36*
G01X1560947Y1048602D02*
X1561130Y1048218D01*
X1560599Y1047688D01*
X1560216Y1047870D01*
X1560074Y1048011D01*
X1560806Y1048743D01*
X1560947Y1048602D01*
G37*
G36*
G01X1559102Y1047322D02*
X1558920Y1047705D01*
X1559450Y1048236D01*
X1559834Y1048054D01*
X1559975Y1047912D01*
X1559243Y1047180D01*
X1559102Y1047322D01*
G37*
G36*
G01X1560764Y1048983D02*
X1560582Y1049367D01*
X1561112Y1049897D01*
X1561495Y1049715D01*
X1561637Y1049574D01*
X1560905Y1048842D01*
X1560764Y1048983D01*
G37*
G36*
G01X1564271Y1051925D02*
X1564453Y1051541D01*
X1563923Y1051011D01*
X1563539Y1051193D01*
X1563398Y1051335D01*
X1564129Y1052066D01*
X1564271Y1051925D01*
G37*
G36*
G01X1562609Y1050263D02*
X1562791Y1049880D01*
X1562261Y1049349D01*
X1561877Y1049531D01*
X1561736Y1049673D01*
X1562468Y1050405D01*
X1562609Y1050263D01*
G37*
G36*
G01X1562425Y1050645D02*
X1562243Y1051029D01*
X1562774Y1051559D01*
X1563157Y1051377D01*
X1563299Y1051236D01*
X1562567Y1050504D01*
X1562425Y1050645D01*
G37*
G36*
G01X1564087Y1052307D02*
X1563905Y1052690D01*
X1564435Y1053221D01*
X1564819Y1053039D01*
X1564960Y1052897D01*
X1564228Y1052165D01*
X1564087Y1052307D01*
G37*
G36*
G01X1559653Y1066554D02*
X1559471Y1066937D01*
X1560001Y1067468D01*
X1560385Y1067285D01*
X1560526Y1067144D01*
X1559794Y1066412D01*
X1559653Y1066554D01*
G37*
G36*
G01X1561498Y1067833D02*
X1561680Y1067450D01*
X1561150Y1066920D01*
X1560766Y1067102D01*
X1560625Y1067243D01*
X1561357Y1067975D01*
X1561498Y1067833D01*
G37*
G36*
G01X1559837Y1066172D02*
X1560019Y1065788D01*
X1559488Y1065258D01*
X1559105Y1065440D01*
X1558963Y1065581D01*
X1559695Y1066313D01*
X1559837Y1066172D01*
G37*
G36*
G01X1561314Y1068215D02*
X1561132Y1068599D01*
X1561663Y1069129D01*
X1562046Y1068947D01*
X1562188Y1068806D01*
X1561456Y1068074D01*
X1561314Y1068215D01*
G37*
G36*
G01X1561535Y1064474D02*
X1561717Y1064090D01*
X1561186Y1063560D01*
X1560803Y1063742D01*
X1560661Y1063883D01*
X1561393Y1064615D01*
X1561535Y1064474D01*
G37*
G36*
G01X1561351Y1064856D02*
X1561169Y1065239D01*
X1561699Y1065770D01*
X1562083Y1065587D01*
X1562224Y1065446D01*
X1561492Y1064714D01*
X1561351Y1064856D01*
G37*
G36*
G01X1560502Y1065705D02*
X1560320Y1066088D01*
X1560850Y1066619D01*
X1561234Y1066436D01*
X1561375Y1066295D01*
X1560643Y1065563D01*
X1560502Y1065705D01*
G37*
G36*
G01X1560686Y1065323D02*
X1560868Y1064939D01*
X1560337Y1064409D01*
X1559954Y1064591D01*
X1559812Y1064732D01*
X1560544Y1065464D01*
X1560686Y1065323D01*
G37*
G36*
G01X1558840Y1064043D02*
X1558658Y1064427D01*
X1559188Y1064957D01*
X1559572Y1064775D01*
X1559713Y1064633D01*
X1558981Y1063901D01*
X1558840Y1064043D01*
G37*
G36*
G01X1562200Y1064007D02*
X1562018Y1064390D01*
X1562548Y1064921D01*
X1562932Y1064738D01*
X1563073Y1064597D01*
X1562341Y1063865D01*
X1562200Y1064007D01*
G37*
G36*
G01X1560412Y1079703D02*
X1560776Y1079485D01*
X1560629Y1078749D01*
X1560209Y1078688D01*
X1560012Y1078727D01*
X1560215Y1079742D01*
X1560412Y1079703D01*
G37*
G36*
G01X1559586Y1077614D02*
X1559221Y1077832D01*
X1559369Y1078568D01*
X1559789Y1078629D01*
X1559985Y1078590D01*
X1559782Y1077575D01*
X1559586Y1077614D01*
G37*
G36*
G01X1559125Y1075310D02*
X1558760Y1075528D01*
X1558907Y1076264D01*
X1559328Y1076325D01*
X1559524Y1076286D01*
X1559321Y1075271D01*
X1559125Y1075310D01*
G37*
G36*
G01X1559950Y1077398D02*
X1560315Y1077180D01*
X1560168Y1076445D01*
X1559747Y1076384D01*
X1559551Y1076423D01*
X1559754Y1077438D01*
X1559950Y1077398D01*
G37*
G36*
G01X1558972Y1070558D02*
X1558790Y1070941D01*
X1559320Y1071472D01*
X1559704Y1071290D01*
X1559845Y1071148D01*
X1559113Y1070416D01*
X1558972Y1070558D01*
G37*
G36*
G01X1559156Y1070176D02*
X1559338Y1069792D01*
X1558808Y1069262D01*
X1558424Y1069444D01*
X1558283Y1069586D01*
X1559014Y1070317D01*
X1559156Y1070176D01*
G37*
G36*
G01X1560818Y1071838D02*
X1561000Y1071454D01*
X1560469Y1070924D01*
X1560086Y1071106D01*
X1559944Y1071247D01*
X1560676Y1071979D01*
X1560818Y1071838D01*
G37*
G36*
G01X1562402Y1079447D02*
X1562038Y1079665D01*
X1562185Y1080401D01*
X1562605Y1080462D01*
X1562801Y1080423D01*
X1562598Y1079408D01*
X1562402Y1079447D01*
G37*
G36*
G01X1562767Y1079232D02*
X1563131Y1079013D01*
X1562984Y1078278D01*
X1562564Y1078217D01*
X1562368Y1078256D01*
X1562571Y1079271D01*
X1562767Y1079232D01*
G37*
G36*
G01X1561480Y1074839D02*
X1561116Y1075057D01*
X1561263Y1075792D01*
X1561683Y1075853D01*
X1561879Y1075814D01*
X1561676Y1074799D01*
X1561480Y1074839D01*
G37*
G36*
G01X1561845Y1074623D02*
X1562209Y1074405D01*
X1562062Y1073669D01*
X1561642Y1073608D01*
X1561446Y1073647D01*
X1561649Y1074662D01*
X1561845Y1074623D01*
G37*
G36*
G01X1562306Y1076927D02*
X1562670Y1076709D01*
X1562523Y1075974D01*
X1562103Y1075912D01*
X1561907Y1075951D01*
X1562110Y1076966D01*
X1562306Y1076927D01*
G37*
G36*
G01X1561941Y1077143D02*
X1561577Y1077361D01*
X1561724Y1078097D01*
X1562144Y1078158D01*
X1562340Y1078119D01*
X1562137Y1077104D01*
X1561941Y1077143D01*
G37*
G36*
G01X1561589Y1079467D02*
X1561954Y1079249D01*
X1561807Y1078513D01*
X1561386Y1078452D01*
X1561190Y1078491D01*
X1561393Y1079506D01*
X1561589Y1079467D01*
G37*
G36*
G01X1560764Y1077379D02*
X1560399Y1077597D01*
X1560547Y1078332D01*
X1560967Y1078393D01*
X1561163Y1078354D01*
X1560960Y1077339D01*
X1560764Y1077379D01*
G37*
G36*
G01X1561128Y1077163D02*
X1561493Y1076945D01*
X1561346Y1076209D01*
X1560925Y1076148D01*
X1560729Y1076187D01*
X1560932Y1077202D01*
X1561128Y1077163D01*
G37*
G36*
G01X1560303Y1075074D02*
X1559938Y1075292D01*
X1560086Y1076028D01*
X1560506Y1076089D01*
X1560702Y1076050D01*
X1560499Y1075035D01*
X1560303Y1075074D01*
G37*
G36*
G01X1560667Y1074858D02*
X1561032Y1074640D01*
X1560885Y1073905D01*
X1560464Y1073844D01*
X1560268Y1073883D01*
X1560471Y1074898D01*
X1560667Y1074858D01*
G37*
G36*
G01X1563580Y1079212D02*
X1563216Y1079430D01*
X1563363Y1080165D01*
X1563783Y1080226D01*
X1563979Y1080187D01*
X1563776Y1079172D01*
X1563580Y1079212D01*
G37*
G36*
G01X1562658Y1074603D02*
X1562294Y1074821D01*
X1562441Y1075556D01*
X1562861Y1075618D01*
X1563057Y1075578D01*
X1562854Y1074564D01*
X1562658Y1074603D01*
G37*
G36*
G01X1563023Y1074387D02*
X1563387Y1074169D01*
X1563240Y1073433D01*
X1562820Y1073372D01*
X1562624Y1073411D01*
X1562827Y1074426D01*
X1563023Y1074387D01*
G37*
G36*
G01X1563484Y1076691D02*
X1563848Y1076473D01*
X1563701Y1075738D01*
X1563281Y1075677D01*
X1563085Y1075716D01*
X1563288Y1076731D01*
X1563484Y1076691D01*
G37*
G36*
G01X1563119Y1076907D02*
X1562755Y1077125D01*
X1562902Y1077861D01*
X1563322Y1077922D01*
X1563518Y1077883D01*
X1563315Y1076868D01*
X1563119Y1076907D01*
G37*
G36*
G01X1563945Y1078996D02*
X1564309Y1078778D01*
X1564162Y1078042D01*
X1563742Y1077981D01*
X1563545Y1078020D01*
X1563749Y1079035D01*
X1563945Y1078996D01*
G37*
G36*
G01X1560005Y1069326D02*
X1560187Y1068943D01*
X1559657Y1068413D01*
X1559273Y1068595D01*
X1559132Y1068736D01*
X1559864Y1069468D01*
X1560005Y1069326D01*
G37*
G36*
G01X1559821Y1069708D02*
X1559639Y1070092D01*
X1560170Y1070622D01*
X1560553Y1070440D01*
X1560695Y1070299D01*
X1559963Y1069567D01*
X1559821Y1069708D01*
G37*
G36*
G01X1561667Y1070988D02*
X1561849Y1070605D01*
X1561319Y1070074D01*
X1560935Y1070256D01*
X1560794Y1070398D01*
X1561526Y1071130D01*
X1561667Y1070988D01*
G37*
G36*
G01X1560047Y1079919D02*
X1559683Y1080137D01*
X1559830Y1080872D01*
X1560250Y1080933D01*
X1560446Y1080894D01*
X1560243Y1079879D01*
X1560047Y1079919D01*
G37*
G36*
G01X1560508Y1082223D02*
X1560144Y1082441D01*
X1560291Y1083176D01*
X1560711Y1083238D01*
X1560907Y1083198D01*
X1560704Y1082184D01*
X1560508Y1082223D01*
G37*
G36*
G01X1560969Y1084527D02*
X1560605Y1084745D01*
X1560752Y1085481D01*
X1561172Y1085542D01*
X1561368Y1085503D01*
X1561165Y1084488D01*
X1560969Y1084527D01*
G37*
G36*
G01X1561334Y1084311D02*
X1561698Y1084093D01*
X1561551Y1083358D01*
X1561131Y1083297D01*
X1560935Y1083336D01*
X1561138Y1084351D01*
X1561334Y1084311D01*
G37*
G36*
G01X1560873Y1082007D02*
X1561237Y1081789D01*
X1561090Y1081053D01*
X1560670Y1080992D01*
X1560474Y1081031D01*
X1560677Y1082046D01*
X1560873Y1082007D01*
G37*
G36*
G01X1561430Y1086831D02*
X1561066Y1087050D01*
X1561213Y1087785D01*
X1561633Y1087846D01*
X1561829Y1087807D01*
X1561626Y1086792D01*
X1561430Y1086831D01*
G37*
G36*
G01X1561795Y1086616D02*
X1562159Y1086398D01*
X1562012Y1085662D01*
X1561592Y1085601D01*
X1561396Y1085640D01*
X1561599Y1086655D01*
X1561795Y1086616D01*
G37*
G36*
G01X1561891Y1089136D02*
X1561527Y1089354D01*
X1561674Y1090089D01*
X1562094Y1090151D01*
X1562291Y1090111D01*
X1562088Y1089097D01*
X1561891Y1089136D01*
G37*
G36*
G01X1562717Y1091224D02*
X1563082Y1091006D01*
X1562934Y1090271D01*
X1562514Y1090209D01*
X1562318Y1090249D01*
X1562521Y1091264D01*
X1562717Y1091224D01*
G37*
G36*
G01X1562256Y1088920D02*
X1562620Y1088702D01*
X1562473Y1087966D01*
X1562053Y1087905D01*
X1561857Y1087944D01*
X1562060Y1088959D01*
X1562256Y1088920D01*
G37*
G36*
G01X1562353Y1091440D02*
X1561988Y1091658D01*
X1562135Y1092394D01*
X1562556Y1092455D01*
X1562752Y1092416D01*
X1562549Y1091401D01*
X1562353Y1091440D01*
G37*
G36*
G01X1563324Y1084056D02*
X1562960Y1084274D01*
X1563107Y1085010D01*
X1563527Y1085071D01*
X1563723Y1085032D01*
X1563520Y1084017D01*
X1563324Y1084056D01*
G37*
G36*
G01X1563689Y1083840D02*
X1564053Y1083622D01*
X1563906Y1082887D01*
X1563486Y1082825D01*
X1563290Y1082865D01*
X1563493Y1083879D01*
X1563689Y1083840D01*
G37*
G36*
G01X1562863Y1081752D02*
X1562499Y1081970D01*
X1562646Y1082705D01*
X1563066Y1082766D01*
X1563262Y1082727D01*
X1563059Y1081712D01*
X1562863Y1081752D01*
G37*
G36*
G01X1563228Y1081536D02*
X1563592Y1081318D01*
X1563445Y1080582D01*
X1563025Y1080521D01*
X1562829Y1080560D01*
X1563032Y1081575D01*
X1563228Y1081536D01*
G37*
G36*
G01X1564246Y1088665D02*
X1563882Y1088883D01*
X1564029Y1089618D01*
X1564449Y1089679D01*
X1564645Y1089640D01*
X1564442Y1088625D01*
X1564246Y1088665D01*
G37*
G36*
G01X1563785Y1086360D02*
X1563421Y1086578D01*
X1563568Y1087314D01*
X1563988Y1087375D01*
X1564184Y1087336D01*
X1563981Y1086321D01*
X1563785Y1086360D01*
G37*
G36*
G01X1564611Y1088449D02*
X1564975Y1088231D01*
X1564828Y1087495D01*
X1564408Y1087434D01*
X1564212Y1087473D01*
X1564415Y1088488D01*
X1564611Y1088449D01*
G37*
G36*
G01X1564150Y1086145D02*
X1564514Y1085926D01*
X1564367Y1085191D01*
X1563947Y1085130D01*
X1563751Y1085169D01*
X1563954Y1086184D01*
X1564150Y1086145D01*
G37*
G36*
G01X1561225Y1079683D02*
X1560860Y1079901D01*
X1561008Y1080636D01*
X1561428Y1080698D01*
X1561624Y1080658D01*
X1561421Y1079644D01*
X1561225Y1079683D01*
G37*
G36*
G01X1561686Y1081987D02*
X1561322Y1082205D01*
X1561469Y1082941D01*
X1561889Y1083002D01*
X1562085Y1082963D01*
X1561882Y1081948D01*
X1561686Y1081987D01*
G37*
G36*
G01X1562147Y1084291D02*
X1561783Y1084510D01*
X1561930Y1085245D01*
X1562350Y1085306D01*
X1562546Y1085267D01*
X1562343Y1084252D01*
X1562147Y1084291D01*
G37*
G36*
G01X1562512Y1084076D02*
X1562876Y1083858D01*
X1562729Y1083122D01*
X1562309Y1083061D01*
X1562112Y1083100D01*
X1562315Y1084115D01*
X1562512Y1084076D01*
G37*
G36*
G01X1562051Y1081771D02*
X1562415Y1081553D01*
X1562268Y1080818D01*
X1561847Y1080757D01*
X1561651Y1080796D01*
X1561854Y1081811D01*
X1562051Y1081771D01*
G37*
G36*
G01X1563069Y1088900D02*
X1562705Y1089118D01*
X1562852Y1089854D01*
X1563272Y1089915D01*
X1563468Y1089876D01*
X1563265Y1088861D01*
X1563069Y1088900D01*
G37*
G36*
G01X1562608Y1086596D02*
X1562244Y1086814D01*
X1562391Y1087549D01*
X1562811Y1087611D01*
X1563007Y1087571D01*
X1562804Y1086557D01*
X1562608Y1086596D01*
G37*
G36*
G01X1562973Y1086380D02*
X1563337Y1086162D01*
X1563190Y1085426D01*
X1562770Y1085365D01*
X1562573Y1085404D01*
X1562777Y1086419D01*
X1562973Y1086380D01*
G37*
G36*
G01X1563895Y1090989D02*
X1564259Y1090771D01*
X1564112Y1090035D01*
X1563692Y1089974D01*
X1563496Y1090013D01*
X1563699Y1091028D01*
X1563895Y1090989D01*
G37*
G36*
G01X1563434Y1088684D02*
X1563798Y1088466D01*
X1563651Y1087731D01*
X1563231Y1087670D01*
X1563035Y1087709D01*
X1563238Y1088724D01*
X1563434Y1088684D01*
G37*
G36*
G01X1564501Y1083820D02*
X1564137Y1084038D01*
X1564284Y1084774D01*
X1564704Y1084835D01*
X1564901Y1084796D01*
X1564698Y1083781D01*
X1564501Y1083820D01*
G37*
G36*
G01X1564041Y1081516D02*
X1563676Y1081734D01*
X1563823Y1082470D01*
X1564244Y1082531D01*
X1564440Y1082492D01*
X1564237Y1081477D01*
X1564041Y1081516D01*
G37*
G36*
G01X1564405Y1081300D02*
X1564770Y1081082D01*
X1564623Y1080347D01*
X1564202Y1080285D01*
X1564006Y1080324D01*
X1564209Y1081339D01*
X1564405Y1081300D01*
G37*
G36*
G01X1564866Y1083605D02*
X1565231Y1083386D01*
X1565083Y1082651D01*
X1564663Y1082590D01*
X1564467Y1082629D01*
X1564670Y1083644D01*
X1564866Y1083605D01*
G37*
G36*
G01X1565423Y1088429D02*
X1565059Y1088647D01*
X1565206Y1089383D01*
X1565626Y1089444D01*
X1565822Y1089405D01*
X1565619Y1088390D01*
X1565423Y1088429D01*
G37*
G36*
G01X1564962Y1086125D02*
X1564598Y1086343D01*
X1564745Y1087078D01*
X1565165Y1087140D01*
X1565361Y1087100D01*
X1565158Y1086085D01*
X1564962Y1086125D01*
G37*
G36*
G01X1565788Y1088213D02*
X1566152Y1087995D01*
X1566005Y1087260D01*
X1565585Y1087198D01*
X1565389Y1087238D01*
X1565592Y1088252D01*
X1565788Y1088213D01*
G37*
G36*
G01X1565327Y1085909D02*
X1565691Y1085691D01*
X1565544Y1084955D01*
X1565124Y1084894D01*
X1564928Y1084933D01*
X1565131Y1085948D01*
X1565327Y1085909D01*
G37*
G36*
G01X1558771Y1102377D02*
X1559135Y1102159D01*
X1558988Y1101424D01*
X1558568Y1101362D01*
X1558372Y1101402D01*
X1558575Y1102417D01*
X1558771Y1102377D01*
G37*
G36*
G01X1558406Y1102593D02*
X1558042Y1102811D01*
X1558189Y1103547D01*
X1558609Y1103608D01*
X1558805Y1103569D01*
X1558602Y1102554D01*
X1558406Y1102593D01*
G37*
G36*
G01X1559232Y1104682D02*
X1559596Y1104464D01*
X1559449Y1103728D01*
X1559029Y1103667D01*
X1558833Y1103706D01*
X1559036Y1104721D01*
X1559232Y1104682D01*
G37*
G36*
G01X1570777Y1580678D02*
G03I-720J0D01*
G37*
G36*
G01Y1575686D02*
G03I-720J0D01*
G37*
G36*
G01X1563673D02*
G03I-720J0D01*
G37*
G36*
G01Y1580678D02*
G03I-720J0D01*
G37*
G36*
G01X1564017Y1599884D02*
G03I-720J0D01*
G37*
G36*
G01X1568973D02*
G03I-720J0D01*
G37*
G36*
G01X1570777Y1592590D02*
G03I-720J0D01*
G37*
G36*
G01Y1587598D02*
G03I-720J0D01*
G37*
G36*
G01X1563673D02*
G03I-720J0D01*
G37*
G36*
G01Y1592590D02*
G03I-720J0D01*
G37*
G36*
G01X1564017Y1604876D02*
G03I-720J0D01*
G37*
G36*
G01Y1611796D02*
G03I-720J0D01*
G37*
G36*
G01X1568973Y1604876D02*
G03I-720J0D01*
G37*
G36*
G01Y1611796D02*
G03I-720J0D01*
G37*
G36*
G01X1564017Y1616788D02*
G03I-720J0D01*
G37*
G36*
G01X1568973D02*
G03I-720J0D01*
G37*
G36*
G01X1584701Y16999D02*
G03I-720J0D01*
G37*
G36*
G01Y21991D02*
G03I-720J0D01*
G37*
G36*
G01X1589657Y16999D02*
G03I-720J0D01*
G37*
G36*
G01Y21991D02*
G03I-720J0D01*
G37*
G36*
G01X1577484Y19495D02*
G03I-720J0D01*
G37*
G36*
G01X1582701D02*
G03I-720J0D01*
G37*
G36*
G01X1591657D02*
G03I-720J0D01*
G37*
G36*
G01X1577596Y23935D02*
G03I-720J0D01*
G37*
G36*
G01X1582552D02*
G03I-720J0D01*
G37*
G36*
G01X1591770D02*
G03I-720J0D01*
G37*
G36*
G01X1584552Y25931D02*
G03I-720J0D01*
G37*
G36*
G01X1589770D02*
G03I-720J0D01*
G37*
G36*
G01X1577538Y69297D02*
G03I-720J0D01*
G37*
G36*
G01X1586494D02*
G03I-720J0D01*
G37*
G36*
G01X1579538Y66801D02*
G03I-720J0D01*
G37*
G36*
G01X1584494D02*
G03I-720J0D01*
G37*
G36*
G01X1579538Y71793D02*
G03I-720J0D01*
G37*
G36*
G01X1584494D02*
G03I-720J0D01*
G37*
G36*
G01X1588538Y75297D02*
G03I-720J0D01*
G37*
G36*
G01X1590538Y77793D02*
G03I-720J0D01*
G37*
G36*
G01Y72801D02*
G03I-720J0D01*
G37*
G36*
G01X1575889Y303929D02*
G03I-720J0D01*
G37*
G36*
G01X1584740Y746832D02*
X1585500Y747592D01*
X1597000D01*
X1600140Y744452D01*
Y734322D01*
X1597040Y731222D01*
X1585590D01*
X1584740Y732072D01*
Y746832D01*
G37*
G36*
G01X1584840Y1339472D02*
X1712800D01*
X1721497Y1330775D01*
X1726947D01*
X1730217Y1327505D01*
Y1315365D01*
X1738487Y1307095D01*
X1749557D01*
X1755377Y1312915D01*
X1759437D01*
X1760597Y1314075D01*
Y1315955D01*
X1761657Y1317015D01*
X1767596D01*
Y1310081D01*
G03X1767796Y1309332I1501J0D01*
G01Y1307881D01*
G03X1768297Y1307380I501J0D01*
G01X1769897D01*
G03X1770398Y1307881I0J501D01*
G01Y1309332D01*
G03X1770598Y1310081I-1301J749D01*
G01Y1317015D01*
X1814104D01*
X1834988Y1296131D01*
Y1262664D01*
X1833388Y1261064D01*
X1831196D01*
Y1263039D01*
X1831215Y1263078D01*
G03X1831342Y1263662I-1275J583D01*
G03X1828538I-1402J0D01*
G03X1828665Y1263078I1402J-1D01*
G01X1828684Y1263039D01*
Y1261752D01*
X1827995Y1261064D01*
X1814888D01*
X1812728Y1263224D01*
X1812713Y1263266D01*
G03X1812409Y1263570I-472J-168D01*
G01X1812367Y1263585D01*
X1811588Y1264364D01*
X1803888D01*
X1802998Y1263474D01*
X1802930Y1263466D01*
G03X1801708Y1262244I170J-1392D01*
G01X1801700Y1262176D01*
X1800588Y1261064D01*
X1791205D01*
X1789616Y1262652D01*
Y1263899D01*
X1789635Y1263938D01*
G03X1789762Y1264522I-1275J583D01*
G03X1786958I-1402J0D01*
G03X1787085Y1263938I1402J-1D01*
G01X1787104Y1263899D01*
Y1262132D01*
G03X1787210Y1261625I1256J-2D01*
G02X1786844Y1261064I-366J-161D01*
G01X1786488D01*
X1783188Y1264364D01*
X1773488D01*
X1770188Y1261064D01*
X1757188D01*
X1753888Y1264364D01*
X1743688D01*
X1740388Y1261064D01*
X1726988D01*
X1723688Y1264364D01*
X1717088D01*
X1716488Y1263764D01*
X1714488D01*
X1714181Y1263457D01*
X1714085Y1263467D01*
G03X1713930Y1263476I-159J-1393D01*
G03X1712528Y1262074I0J-1402D01*
G03X1712537Y1261919I1402J4D01*
G01X1712547Y1261823D01*
X1711788Y1261064D01*
X1701723D01*
X1700286Y1262500D01*
Y1263289D01*
X1700305Y1263328D01*
G03X1700432Y1263912I-1275J583D01*
G03X1697628I-1402J0D01*
G03X1697755Y1263328I1402J-1D01*
G01X1697774Y1263289D01*
Y1261980D01*
G03X1697936Y1261362I1256J-1D01*
G01X1697962Y1261317D01*
Y1261064D01*
X1697488D01*
X1694188Y1264364D01*
X1687588D01*
X1686788Y1263564D01*
X1686025D01*
X1684829Y1264760D01*
X1684814Y1264801D01*
G03X1683500Y1265714I-1314J-489D01*
G03X1682098Y1264312I0J-1402D01*
G03X1683011Y1262998I1402J0D01*
G01X1683052Y1262983D01*
X1683480Y1262556D01*
X1681988Y1261064D01*
X1674088D01*
X1673388Y1260364D01*
X1668588D01*
X1664588Y1264364D01*
X1655488D01*
X1655158Y1264034D01*
X1655041Y1264073D01*
G03X1654600Y1264144I-441J-1331D01*
G03X1653198Y1262742I0J-1402D01*
G03X1653269Y1262301I1402J0D01*
G01X1653308Y1262184D01*
X1652188Y1261064D01*
X1642588D01*
X1639188Y1264464D01*
X1626688D01*
X1625554Y1263330D01*
X1625223D01*
X1625184Y1263349D01*
G03X1624600Y1263476I-583J-1275D01*
G03X1623198Y1262074I0J-1402D01*
G03X1623469Y1261245I1402J0D01*
G01X1623088Y1260864D01*
X1610917D01*
X1610754Y1261026D01*
G03X1609591Y1261538I-1239J-1238D01*
G02X1609400Y1261729I9J200D01*
G03X1608447Y1262991I-1400J-67D01*
G03X1607588Y1263330I-858J-917D01*
G01X1606980D01*
G03X1605946Y1264062I-1240J-655D01*
G01X1605880Y1264072D01*
X1605588Y1264364D01*
X1584498D01*
X1583307Y1265555D01*
Y1337939D01*
X1584840Y1339472D01*
G37*
G36*
G01X1622046Y1420028D02*
G03X1623448Y1418626I1402J0D01*
G03X1623581Y1418632I3J1402D01*
G02X1623800Y1418433I19J-199D01*
G01Y1392352D01*
X1624010Y1392142D01*
X1622630Y1390762D01*
X1621330D01*
X1619570Y1389002D01*
Y1358282D01*
X1620840Y1357012D01*
X1631063D01*
G02X1631390Y1356383I-1J-400D01*
G03X1630757Y1354375I2869J-2008D01*
G01Y1354374D01*
G03X1637761I3502J0D01*
G01Y1354375D01*
G03X1637128Y1356383I-3502J0D01*
G02X1637455Y1357012I328J229D01*
G01X1655419D01*
G02X1655748Y1356385I-1J-400D01*
G03X1655130Y1354399I2884J-1987D01*
G03X1662134I3502J0D01*
G03X1661516Y1356385I-3502J-1D01*
G02X1661845Y1357012I330J227D01*
G01X1679819D01*
G02X1680148Y1356385I-1J-400D01*
G03X1679530Y1354399I2884J-1987D01*
G03X1686534I3502J0D01*
G03X1685916Y1356385I-3502J-1D01*
G02X1686245Y1357012I330J227D01*
G01X1709050D01*
X1710530Y1358492D01*
Y1388332D01*
X1705250Y1393612D01*
Y1432232D01*
X1723100Y1450082D01*
X1727710Y1445472D01*
Y1343912D01*
X1726441Y1342643D01*
X1586437D01*
X1584810Y1344270D01*
Y1405550D01*
X1586942Y1407682D01*
X1616510D01*
X1618690Y1409862D01*
Y1418742D01*
X1621370Y1421422D01*
X1622175Y1420617D01*
G03X1622046Y1420031I1273J-588D01*
G01Y1420028D01*
G37*
G36*
G01X1575733Y1580678D02*
G03I-720J0D01*
G37*
G36*
G01Y1575686D02*
G03I-720J0D01*
G37*
G36*
G01X1582837D02*
G03I-720J0D01*
G37*
G36*
G01X1587793D02*
G03I-720J0D01*
G37*
G36*
G01X1582837Y1580678D02*
G03I-720J0D01*
G37*
G36*
G01X1587793D02*
G03I-720J0D01*
G37*
G36*
G01X1576077Y1599884D02*
G03I-720J0D01*
G37*
G36*
G01X1575733Y1592590D02*
G03I-720J0D01*
G37*
G36*
G01Y1587598D02*
G03I-720J0D01*
G37*
G36*
G01X1588137Y1599884D02*
G03I-720J0D01*
G37*
G36*
G01X1581033D02*
G03I-720J0D01*
G37*
G36*
G01X1582837Y1587598D02*
G03I-720J0D01*
G37*
G36*
G01X1587793D02*
G03I-720J0D01*
G37*
G36*
G01X1582837Y1592590D02*
G03I-720J0D01*
G37*
G36*
G01X1587793D02*
G03I-720J0D01*
G37*
G36*
G01X1576077Y1616788D02*
G03I-720J0D01*
G37*
G36*
G01Y1604876D02*
G03I-720J0D01*
G37*
G36*
G01Y1611796D02*
G03I-720J0D01*
G37*
G36*
G01X1588137Y1604876D02*
G03I-720J0D01*
G37*
G36*
G01Y1611796D02*
G03I-720J0D01*
G37*
G36*
G01Y1616788D02*
G03I-720J0D01*
G37*
G36*
G01X1581033D02*
G03I-720J0D01*
G37*
G36*
G01Y1604876D02*
G03I-720J0D01*
G37*
G36*
G01Y1611796D02*
G03I-720J0D01*
G37*
G36*
G01X1598875Y16999D02*
G03I-720J0D01*
G37*
G36*
G01Y21991D02*
G03I-720J0D01*
G37*
G36*
G01X1603831Y16999D02*
G03I-720J0D01*
G37*
G36*
G01Y21991D02*
G03I-720J0D01*
G37*
G36*
G01X1596875Y19495D02*
G03I-720J0D01*
G37*
G36*
G01X1605831D02*
G03I-720J0D01*
G37*
G36*
G01X1596726Y23935D02*
G03I-720J0D01*
G37*
G36*
G01X1598726Y25931D02*
G03I-720J0D01*
G37*
G36*
G01X1599538Y69297D02*
G03I-720J0D01*
G37*
G36*
G01X1601538Y66801D02*
G03I-720J0D01*
G37*
G36*
G01X1606494D02*
G03I-720J0D01*
G37*
G36*
G01X1601538Y71793D02*
G03I-720J0D01*
G37*
G36*
G01X1606494D02*
G03I-720J0D01*
G37*
G36*
G01X1597494Y75297D02*
G03I-720J0D01*
G37*
G36*
G01X1595494Y77793D02*
G03I-720J0D01*
G37*
G36*
G01Y72801D02*
G03I-720J0D01*
G37*
G36*
G01X1604498Y189943D02*
G03I-720J0D01*
G37*
G36*
G01X1604446Y198061D02*
G03I-720J0D01*
G37*
G36*
G01X1640130Y715976D02*
Y713845D01*
G03X1640189Y713703I200J0D01*
G01X1640411Y713481D01*
G03X1640553Y713422I142J141D01*
G01X1644367D01*
G03X1644509Y713481I0J200D01*
G01X1644511Y713483D01*
G03X1644570Y713625I-141J142D01*
G01Y716922D01*
G02X1644770Y717122I200J0D01*
G01X1645250D01*
G02X1645450Y716922I0J-200D01*
G01Y713645D01*
G03X1645509Y713503I200J0D01*
G01X1645551Y713461D01*
G03X1645693Y713402I142J141D01*
G01X1646287D01*
G02X1646429Y713343I0J-200D01*
G01X1646551Y713221D01*
G02X1646610Y713079I-141J-142D01*
G01Y706945D01*
G02X1646551Y706803I-200J0D01*
G01X1646369Y706621D01*
X1646341Y706592D01*
X1646267Y706562D01*
X1638413D01*
G03X1638271Y706503I0J-200D01*
G01X1637469Y705701D01*
G03X1637410Y705559I141J-142D01*
G01Y688685D01*
G02X1637351Y688543I-200J0D01*
G01X1636689Y687881D01*
G03X1636630Y687739I141J-142D01*
G01Y685512D01*
X1636830Y685312D01*
Y684452D01*
X1636520Y684142D01*
X1635540D01*
X1634719Y683321D01*
G03X1634660Y683179I141J-142D01*
G01Y676245D01*
G03X1634719Y676103I200J0D01*
G01X1634861Y675961D01*
G03X1635003Y675902I142J141D01*
G01X1638807D01*
G03X1638949Y675961I0J200D01*
G01X1639061Y676073D01*
G03X1639120Y676215I-141J142D01*
G01Y679119D01*
G02X1639179Y679261I200J0D01*
G01X1639251Y679333D01*
G03X1639310Y679475I-141J142D01*
G01Y682032D01*
X1640140D01*
Y679565D01*
G03X1640199Y679423I200J0D01*
G01X1640321Y679301D01*
G03X1640463Y679242I142J141D01*
G01X1644267D01*
G03X1644409Y679301I0J200D01*
G01X1644531Y679423D01*
G03X1644590Y679565I-141J142D01*
G01Y682902D01*
G02X1644790Y683102I200J0D01*
G01X1645197D01*
G02X1645339Y683043I0J-200D01*
G01X1645381Y683001D01*
G02X1645440Y682859I-141J-142D01*
G01Y679505D01*
G03X1645499Y679363I200J0D01*
G01X1645561Y679301D01*
G03X1645703Y679242I142J141D01*
G01X1646197D01*
G02X1646339Y679183I0J-200D01*
G01X1646551Y678971D01*
G02X1646610Y678829I-141J-142D01*
G01Y673075D01*
G02X1646551Y672933I-200J0D01*
G01X1646219Y672601D01*
X1646191Y672572D01*
X1646117Y672542D01*
X1638613D01*
G03X1638471Y672483I0J-200D01*
G01X1637399Y671411D01*
G03X1637340Y671269I141J-142D01*
G01Y670952D01*
X1637360Y670932D01*
Y655475D01*
G02X1637301Y655333I-200J0D01*
G01X1636709Y654741D01*
G03X1636650Y654599I141J-142D01*
G01Y651662D01*
X1636780Y651532D01*
Y650212D01*
X1636300Y649732D01*
X1635940D01*
X1635310D01*
X1634679Y649101D01*
G03X1634620Y648959I141J-142D01*
G01Y642185D01*
G03X1634679Y642043I200J0D01*
G01X1634700Y642022D01*
X1634736Y642007D01*
G03X1634812Y641992I76J185D01*
G01X1637987D01*
G03X1638129Y642051I0J200D01*
G01X1639021Y642943D01*
G03X1639080Y643085I-141J142D01*
G01Y645429D01*
G02X1639139Y645571I200J0D01*
G01X1639191Y645623D01*
G03X1639250Y645765I-141J142D01*
G01Y648072D01*
X1640150D01*
Y645825D01*
G03X1640209Y645683I200J0D01*
G01X1640521Y645371D01*
G03X1640663Y645312I142J141D01*
G01X1644347D01*
G03X1644489Y645371I0J200D01*
G01X1644591Y645473D01*
G03X1644650Y645615I-141J142D01*
G01Y648892D01*
G02X1644850Y649092I200J0D01*
G01X1645197D01*
G02X1645339Y649033I0J-200D01*
G01X1645381Y648991D01*
G02X1645440Y648849I-141J-142D01*
G01Y645615D01*
G03X1645499Y645473I200J0D01*
G01X1645621Y645351D01*
G03X1645763Y645292I142J141D01*
G01X1646187D01*
G02X1646329Y645233I0J-200D01*
G01X1646521Y645041D01*
G02X1646580Y644899I-141J-142D01*
G01Y639135D01*
G02X1646521Y638993I-200J0D01*
G01X1646229Y638701D01*
X1646201Y638672D01*
X1646127Y638642D01*
X1639053D01*
G03X1638911Y638583I0J-200D01*
G01X1637409Y637081D01*
G03X1637350Y636939I141J-142D01*
G01Y622315D01*
G03X1637409Y622173I200J0D01*
G01X1638511Y621071D01*
G03X1638653Y621012I142J141D01*
G01X1642717D01*
G02X1642859Y620953I0J-200D01*
G01X1643741Y620071D01*
X1643770Y620043D01*
X1643800Y619969D01*
Y605125D01*
G03X1643859Y604983I200J0D01*
G01X1644361Y604481D01*
G03X1644503Y604422I142J141D01*
G01X1647217D01*
G03X1647359Y604481I0J200D01*
G01X1648111Y605233D01*
G03X1648170Y605375I-141J142D01*
G01Y607449D01*
G02X1648229Y607591I200J0D01*
G01X1648581Y607943D01*
G02X1648723Y608002I142J-141D01*
G01X1654017D01*
G02X1654159Y607943I0J-200D01*
G01X1654841Y607261D01*
X1654870Y607233D01*
X1654900Y607159D01*
Y601545D01*
G02X1654841Y601403I-200J0D01*
G01X1654639Y601201D01*
X1654611Y601172D01*
X1654537Y601142D01*
X1647633D01*
G03X1647491Y601083I0J-200D01*
G01X1646679Y600271D01*
G03X1646620Y600129I141J-142D01*
G01Y587685D01*
G03X1646679Y587543I200J0D01*
G01X1647331Y586891D01*
G03X1647473Y586832I142J141D01*
G01X1672387D01*
G02X1672529Y586773I0J-200D01*
G01X1674161Y585141D01*
G02X1674220Y584999I-141J-142D01*
G01Y579395D01*
G02X1674161Y579253I-200J0D01*
G01X1673669Y578761D01*
X1673641Y578732D01*
X1673567Y578702D01*
X1614853D01*
G02X1614711Y578761I0J200D01*
G01X1613139Y580333D01*
X1613110Y580361D01*
X1613080Y580435D01*
Y616329D01*
G03X1613021Y616471I-200J0D01*
G01X1611649Y617843D01*
G03X1611507Y617902I-142J-141D01*
G01X1610192D01*
G03X1610066Y617857I0J-200D01*
G02X1609940Y617812I-126J155D01*
G01X1608793D01*
G02X1608651Y617871I0J200D01*
G01X1606319Y620203D01*
X1606290Y620231D01*
X1606260Y620305D01*
Y719309D01*
G03X1606201Y719451I-200J0D01*
G01X1604569Y721083D01*
X1604540Y721111D01*
X1604510Y721185D01*
Y727699D01*
G02X1604569Y727841I200J0D01*
G01X1605191Y728463D01*
G02X1605333Y728522I142J-141D01*
G01X1635037D01*
G02X1635179Y728463I0J-200D01*
G01X1636411Y727231D01*
G02X1636470Y727089I-141J-142D01*
G01Y718555D01*
G02X1636411Y718413I-200J0D01*
G01X1634709Y716711D01*
G03X1634650Y716569I141J-142D01*
G01Y710175D01*
G03X1634709Y710033I200J0D01*
G01X1634711Y710031D01*
G03X1634853Y709972I142J141D01*
G01X1638777D01*
G03X1638919Y710031I0J200D01*
G01X1638961Y710073D01*
G03X1639020Y710215I-141J142D01*
G01Y713559D01*
G02X1639079Y713701I200J0D01*
G01X1639181Y713803D01*
G03X1639240Y713945I-141J142D01*
G01Y715976D01*
X1640130D01*
G37*
G36*
G01X1606957Y1575686D02*
G03I-720J0D01*
G37*
G36*
G01Y1580678D02*
G03I-720J0D01*
G37*
G36*
G01X1594897D02*
G03I-720J0D01*
G37*
G36*
G01X1599853D02*
G03I-720J0D01*
G37*
G36*
G01X1594897Y1575686D02*
G03I-720J0D01*
G37*
G36*
G01X1599853D02*
G03I-720J0D01*
G37*
G36*
G01X1600197Y1599884D02*
G03I-720J0D01*
G37*
G36*
G01X1605153D02*
G03I-720J0D01*
G37*
G36*
G01X1593093D02*
G03I-720J0D01*
G37*
G36*
G01X1606957Y1587598D02*
G03I-720J0D01*
G37*
G36*
G01Y1592590D02*
G03I-720J0D01*
G37*
G36*
G01X1594897D02*
G03I-720J0D01*
G37*
G36*
G01X1599853D02*
G03I-720J0D01*
G37*
G36*
G01X1594897Y1587598D02*
G03I-720J0D01*
G37*
G36*
G01X1599853D02*
G03I-720J0D01*
G37*
G36*
G01X1600197Y1616788D02*
G03I-720J0D01*
G37*
G36*
G01X1605153D02*
G03I-720J0D01*
G37*
G36*
G01X1600197Y1604876D02*
G03I-720J0D01*
G37*
G36*
G01Y1611796D02*
G03I-720J0D01*
G37*
G36*
G01X1605153Y1604876D02*
G03I-720J0D01*
G37*
G36*
G01Y1611796D02*
G03I-720J0D01*
G37*
G36*
G01X1593093Y1604876D02*
G03I-720J0D01*
G37*
G36*
G01Y1611796D02*
G03I-720J0D01*
G37*
G36*
G01Y1616788D02*
G03I-720J0D01*
G37*
G36*
G01X1608494Y69297D02*
G03I-720J0D01*
G37*
G36*
G01X1621538D02*
G03I-720J0D01*
G37*
G36*
G01X1623538Y66801D02*
G03I-720J0D01*
G37*
G36*
G01Y71793D02*
G03I-720J0D01*
G37*
G36*
G01X1610538Y75297D02*
G03I-720J0D01*
G37*
G36*
G01X1619494D02*
G03I-720J0D01*
G37*
G36*
G01X1617494Y77793D02*
G03I-720J0D01*
G37*
G36*
G01Y72801D02*
G03I-720J0D01*
G37*
G36*
G01X1612538Y77793D02*
G03I-720J0D01*
G37*
G36*
G01Y72801D02*
G03I-720J0D01*
G37*
G36*
G01X1708337Y1387895D02*
Y1359539D01*
X1707010Y1358212D01*
X1622407D01*
X1620877Y1359742D01*
Y1388585D01*
X1621845Y1389553D01*
X1706679D01*
X1708337Y1387895D01*
G37*
G36*
G01X1700777Y1469535D02*
X1714852D01*
X1717347Y1468395D01*
X1724050Y1461692D01*
Y1394104D01*
X1720720Y1390774D01*
X1621604D01*
X1620672Y1391706D01*
Y1423472D01*
X1621482Y1424282D01*
X1626752D01*
X1628444Y1422590D01*
X1634528D01*
X1634683Y1422745D01*
X1634710Y1422772D01*
Y1426310D01*
X1634703Y1426317D01*
Y1426428D01*
X1634478Y1426653D01*
X1630664D01*
X1630602Y1426715D01*
X1630345Y1426972D01*
X1629050D01*
X1628930Y1427092D01*
Y1427732D01*
X1629080Y1427882D01*
X1630736D01*
X1631008Y1428154D01*
X1631284Y1428431D01*
X1631343Y1428573D01*
Y1431891D01*
X1631284Y1432033D01*
X1631202Y1432115D01*
X1631060Y1432174D01*
X1628026D01*
X1627884Y1432233D01*
X1627873Y1432244D01*
X1627843Y1432317D01*
Y1433107D01*
X1627902Y1433249D01*
X1627913Y1433260D01*
X1627986Y1433290D01*
X1631060D01*
X1631202Y1433349D01*
X1631284Y1433431D01*
X1631343Y1433573D01*
Y1434307D01*
X1631402Y1434449D01*
X1631484Y1434531D01*
X1631626Y1434590D01*
X1638260D01*
X1638402Y1434531D01*
X1638584Y1434349D01*
G02X1638626Y1434288I-141J-142D01*
G01Y1425785D01*
X1639075Y1425336D01*
X1657928D01*
X1658697Y1426105D01*
Y1435247D01*
X1656603Y1437341D01*
Y1446109D01*
X1659020Y1448526D01*
X1661254D01*
X1661491Y1448289D01*
Y1438920D01*
X1660887Y1438316D01*
Y1424955D01*
X1661497Y1424345D01*
X1664797D01*
X1666552Y1422590D01*
X1672728D01*
X1672870Y1422732D01*
Y1426293D01*
X1672826Y1426337D01*
X1672696Y1426467D01*
X1672591Y1426572D01*
X1668888D01*
X1668745Y1426715D01*
X1668488Y1426972D01*
X1667170D01*
X1667060Y1427082D01*
Y1427772D01*
X1667150Y1427862D01*
X1668858D01*
X1669145Y1428149D01*
X1669427Y1428431D01*
X1669486Y1428573D01*
Y1431891D01*
X1669427Y1432033D01*
X1669345Y1432115D01*
X1669203Y1432174D01*
X1666169D01*
X1666027Y1432233D01*
X1666016Y1432244D01*
X1665986Y1432317D01*
Y1433107D01*
X1666045Y1433249D01*
X1666056Y1433260D01*
X1666129Y1433290D01*
X1669203D01*
X1669345Y1433349D01*
X1669427Y1433431D01*
X1669486Y1433573D01*
Y1434307D01*
X1669545Y1434449D01*
X1669627Y1434531D01*
X1669769Y1434590D01*
X1676403D01*
X1676545Y1434531D01*
X1676727Y1434349D01*
G02X1676769Y1434288I-141J-142D01*
G01Y1425785D01*
X1677167Y1425387D01*
X1677170D01*
X1677245Y1425312D01*
X1686470D01*
X1686545Y1425387D01*
X1691083D01*
X1691094Y1425377D01*
X1691101Y1425384D01*
X1697746D01*
X1698397Y1426035D01*
Y1450475D01*
X1698407Y1450485D01*
Y1467165D01*
X1700777Y1469535D01*
G37*
G36*
G01X1619017Y1580678D02*
G03I-720J0D01*
G37*
G36*
G01X1623973D02*
G03I-720J0D01*
G37*
G36*
G01X1619017Y1575686D02*
G03I-720J0D01*
G37*
G36*
G01X1623973D02*
G03I-720J0D01*
G37*
G36*
G01X1611913D02*
G03I-720J0D01*
G37*
G36*
G01Y1580678D02*
G03I-720J0D01*
G37*
G36*
G01X1624317Y1599884D02*
G03I-720J0D01*
G37*
G36*
G01X1612257D02*
G03I-720J0D01*
G37*
G36*
G01X1617213D02*
G03I-720J0D01*
G37*
G36*
G01X1619017Y1592590D02*
G03I-720J0D01*
G37*
G36*
G01X1623973D02*
G03I-720J0D01*
G37*
G36*
G01X1619017Y1587598D02*
G03I-720J0D01*
G37*
G36*
G01X1623973D02*
G03I-720J0D01*
G37*
G36*
G01X1611913D02*
G03I-720J0D01*
G37*
G36*
G01Y1592590D02*
G03I-720J0D01*
G37*
G36*
G01X1624317Y1616788D02*
G03I-720J0D01*
G37*
G36*
G01Y1604876D02*
G03I-720J0D01*
G37*
G36*
G01Y1611796D02*
G03I-720J0D01*
G37*
G36*
G01X1612257Y1604876D02*
G03I-720J0D01*
G37*
G36*
G01Y1611796D02*
G03I-720J0D01*
G37*
G36*
G01X1617213Y1604876D02*
G03I-720J0D01*
G37*
G36*
G01Y1611796D02*
G03I-720J0D01*
G37*
G36*
G01X1612257Y1616788D02*
G03I-720J0D01*
G37*
G36*
G01X1617213D02*
G03I-720J0D01*
G37*
G36*
G01X1634741Y16999D02*
G03I-720J0D01*
G37*
G36*
G01Y21991D02*
G03I-720J0D01*
G37*
G36*
G01X1639697Y16999D02*
G03I-720J0D01*
G37*
G36*
G01Y21991D02*
G03I-720J0D01*
G37*
G36*
G01X1632741Y19495D02*
G03I-720J0D01*
G37*
G36*
G01X1632592Y23935D02*
G03I-720J0D01*
G37*
G36*
G01X1627636D02*
G03I-720J0D01*
G37*
G36*
G01X1625636Y25931D02*
G03I-720J0D01*
G37*
G36*
G01X1634592D02*
G03I-720J0D01*
G37*
G36*
G01X1639809D02*
G03I-720J0D01*
G37*
G36*
G01X1630494Y69297D02*
G03I-720J0D01*
G37*
G36*
G01X1628494Y66801D02*
G03I-720J0D01*
G37*
G36*
G01Y71793D02*
G03I-720J0D01*
G37*
G36*
G01X1633742Y75297D02*
G03I-720J0D01*
G37*
G36*
G01X1635742Y77793D02*
G03I-720J0D01*
G37*
G36*
G01X1640698D02*
G03I-720J0D01*
G37*
G36*
G01Y72801D02*
G03I-720J0D01*
G37*
G36*
G01X1635742D02*
G03I-720J0D01*
G37*
G36*
G01X1672660Y714172D02*
X1689930D01*
X1689970Y714132D01*
X1697880D01*
X1699020Y712992D01*
X1704270D01*
X1704390Y712872D01*
Y712642D01*
X1704380Y712632D01*
Y712302D01*
X1704210Y712132D01*
X1696197D01*
X1692917Y708852D01*
X1690860D01*
X1690825Y708887D01*
X1685305D01*
X1681796Y705378D01*
Y697823D01*
X1687120Y692498D01*
Y685562D01*
X1690950Y681732D01*
Y635072D01*
X1696660Y629362D01*
Y589502D01*
X1694814Y587656D01*
X1649020D01*
X1648800Y587876D01*
Y599252D01*
X1649180Y599632D01*
X1654360D01*
X1654840Y599152D01*
Y593972D01*
X1655471Y593341D01*
X1667489D01*
X1672580Y598432D01*
Y619392D01*
X1669310Y622662D01*
X1639194D01*
X1638689Y623167D01*
Y636995D01*
G02X1638711Y637087I200J1D01*
G01X1646895D01*
X1647081Y636901D01*
Y631852D01*
G03X1647140Y631710I200J0D01*
G01X1647924Y630926D01*
G03X1648066Y630867I142J141D01*
G01X1651671D01*
X1652656Y629882D01*
G03X1652798Y629823I142J141D01*
G01X1659040D01*
X1663640Y634423D01*
Y652012D01*
X1659790Y655862D01*
X1639994D01*
X1638689Y657167D01*
Y670995D01*
G02X1638748Y671137I200J0D01*
G01X1646845D01*
X1647081Y670901D01*
Y665852D01*
G03X1647140Y665710I200J0D01*
G01X1647924Y664926D01*
G03X1648066Y664867I142J141D01*
G01X1651671D01*
X1652656Y663882D01*
G03X1652798Y663823I142J141D01*
G01X1658861D01*
X1663520Y668482D01*
Y686342D01*
X1660000Y689862D01*
X1639994D01*
X1638689Y691167D01*
Y705156D01*
X1646826D01*
X1647081Y704901D01*
Y699852D01*
G03X1647140Y699710I200J0D01*
G01X1647924Y698926D01*
G03X1648066Y698867I142J141D01*
G01X1651671D01*
X1652656Y697882D01*
G03X1652798Y697823I142J141D01*
G01X1667121D01*
X1668757Y699459D01*
Y710269D01*
X1672660Y714172D01*
G37*
G36*
G01X1631077Y1575592D02*
G03I-720J0D01*
G37*
G36*
G01X1636033D02*
G03I-720J0D01*
G37*
G36*
G01X1631077Y1580678D02*
G03I-720J0D01*
G37*
G36*
G01X1636033D02*
G03I-720J0D01*
G37*
G36*
G01X1636377Y1599790D02*
G03I-720J0D01*
G37*
G36*
G01X1629273Y1599884D02*
G03I-720J0D01*
G37*
G36*
G01X1631077Y1587598D02*
G03I-720J0D01*
G37*
G36*
G01X1636033D02*
G03I-720J0D01*
G37*
G36*
G01X1631077Y1592590D02*
G03I-720J0D01*
G37*
G36*
G01X1636033D02*
G03I-720J0D01*
G37*
G36*
G01X1636377Y1604876D02*
G03I-720J0D01*
G37*
G36*
G01Y1611796D02*
G03I-720J0D01*
G37*
G36*
G01Y1616788D02*
G03I-720J0D01*
G37*
G36*
G01X1629273D02*
G03I-720J0D01*
G37*
G36*
G01Y1604876D02*
G03I-720J0D01*
G37*
G36*
G01Y1611796D02*
G03I-720J0D01*
G37*
G36*
G01X1648914Y16999D02*
G03I-720J0D01*
G37*
G36*
G01Y21991D02*
G03I-720J0D01*
G37*
G36*
G01X1653870Y16999D02*
G03I-720J0D01*
G37*
G36*
G01Y21991D02*
G03I-720J0D01*
G37*
G36*
G01X1641697Y19495D02*
G03I-720J0D01*
G37*
G36*
G01X1646914D02*
G03I-720J0D01*
G37*
G36*
G01X1655870D02*
G03I-720J0D01*
G37*
G36*
G01X1641809Y23935D02*
G03I-720J0D01*
G37*
G36*
G01X1646765D02*
G03I-720J0D01*
G37*
G36*
G01X1648765Y25931D02*
G03I-720J0D01*
G37*
G36*
G01X1644742Y69297D02*
G03I-720J0D01*
G37*
G36*
G01X1653698D02*
G03I-720J0D01*
G37*
G36*
G01X1646742Y66801D02*
G03I-720J0D01*
G37*
G36*
G01X1651698D02*
G03I-720J0D01*
G37*
G36*
G01X1646742Y71793D02*
G03I-720J0D01*
G37*
G36*
G01X1651698D02*
G03I-720J0D01*
G37*
G36*
G01X1655742Y75297D02*
G03I-720J0D01*
G37*
G36*
G01X1642698D02*
G03I-720J0D01*
G37*
G36*
G01X1645320Y397052D02*
X1646420Y398152D01*
X1663520D01*
X1664720Y396952D01*
Y394352D01*
X1660820Y390452D01*
Y381452D01*
X1659720Y380352D01*
X1648320D01*
X1645320Y383352D01*
Y397052D01*
G37*
G36*
G01X1655720Y415652D02*
Y412852D01*
X1655420Y412552D01*
X1652820D01*
X1651440Y411172D01*
Y408592D01*
X1650650Y407802D01*
X1646840D01*
X1646190Y408452D01*
Y414922D01*
X1647420Y416152D01*
X1655220D01*
X1655720Y415652D01*
G37*
G36*
G01X1651988Y1475306D02*
X1693236D01*
X1697060Y1471482D01*
Y1426911D01*
X1696547Y1426398D01*
X1678191D01*
X1677953Y1426636D01*
Y1434478D01*
X1678272Y1434797D01*
X1683362D01*
X1683393Y1434829D01*
X1683394D01*
X1684022Y1435457D01*
Y1438068D01*
X1685467Y1439513D01*
Y1446706D01*
X1682477Y1449696D01*
X1658661D01*
X1655647Y1446682D01*
Y1436761D01*
X1657616Y1434792D01*
Y1426598D01*
X1657416Y1426398D01*
X1639830D01*
X1639790Y1426438D01*
Y1434529D01*
X1640053Y1434790D01*
X1645399D01*
X1645437Y1434829D01*
X1645438D01*
X1645916Y1435307D01*
Y1435751D01*
G03X1645917Y1435777I-797J44D01*
G01Y1438140D01*
G03X1645909Y1438249I-799J-4D01*
G01X1645895Y1438347D01*
X1647430Y1439883D01*
Y1451698D01*
X1650822Y1455090D01*
Y1474140D01*
X1651988Y1475306D01*
G37*
G36*
G01X1648093Y1580678D02*
G03I-720J0D01*
G37*
G36*
G01X1643137D02*
G03I-720J0D01*
G37*
G36*
G01X1648093Y1575686D02*
G03I-720J0D01*
G37*
G36*
G01X1643137D02*
G03I-720J0D01*
G37*
G36*
G01X1641333Y1599790D02*
G03I-720J0D01*
G37*
G36*
G01X1648437Y1599884D02*
G03I-720J0D01*
G37*
G36*
G01X1653393D02*
G03I-720J0D01*
G37*
G36*
G01X1648093Y1592590D02*
G03I-720J0D01*
G37*
G36*
G01X1643137D02*
G03I-720J0D01*
G37*
G36*
G01X1648093Y1587598D02*
G03I-720J0D01*
G37*
G36*
G01X1643137D02*
G03I-720J0D01*
G37*
G36*
G01X1641333Y1604876D02*
G03I-720J0D01*
G37*
G36*
G01Y1611796D02*
G03I-720J0D01*
G37*
G36*
G01Y1616788D02*
G03I-720J0D01*
G37*
G36*
G01X1648437D02*
G03I-720J0D01*
G37*
G36*
G01X1653393D02*
G03I-720J0D01*
G37*
G36*
G01X1648437Y1604876D02*
G03I-720J0D01*
G37*
G36*
G01Y1611796D02*
G03I-720J0D01*
G37*
G36*
G01X1653393Y1604876D02*
G03I-720J0D01*
G37*
G36*
G01Y1611796D02*
G03I-720J0D01*
G37*
G36*
G01X1671770Y23935D02*
G03I-720J0D01*
G37*
G36*
G01X1669770Y25931D02*
G03I-720J0D01*
G37*
G36*
G01X1666742Y69297D02*
G03I-720J0D01*
G37*
G36*
G01X1668742Y66801D02*
G03I-720J0D01*
G37*
G36*
G01Y71793D02*
G03I-720J0D01*
G37*
G36*
G01X1657742Y77793D02*
G03I-720J0D01*
G37*
G36*
G01Y72801D02*
G03I-720J0D01*
G37*
G36*
G01X1664698Y75297D02*
G03I-720J0D01*
G37*
G36*
G01X1662698Y77793D02*
G03I-720J0D01*
G37*
G36*
G01Y72801D02*
G03I-720J0D01*
G37*
G36*
G01X1686722Y227603D02*
X1712139D01*
X1713370Y226372D01*
Y213742D01*
X1712827Y213199D01*
X1707187D01*
X1705250Y211262D01*
Y184812D01*
X1703161Y182723D01*
X1665440D01*
X1662676Y185487D01*
Y188887D01*
X1663276Y189487D01*
X1665688D01*
X1667795Y191594D01*
Y192273D01*
G03X1668192Y193290I-1104J1017D01*
G03X1667842Y194254I-1503J0D01*
G01X1667795Y194310D01*
Y194555D01*
X1667540Y194810D01*
X1666530D01*
X1666510Y194790D01*
X1662860D01*
X1662390Y195260D01*
Y197386D01*
X1663021Y198017D01*
X1668828D01*
G03X1669073Y198367I-1508J1316D01*
G01X1672368D01*
X1673500Y199499D01*
Y210529D01*
X1674557Y211586D01*
X1682217D01*
X1683552Y212921D01*
Y224433D01*
X1686722Y227603D01*
G37*
G36*
G01X1666794Y229710D02*
G03I-720J0D01*
G37*
G36*
G01X1660896Y231100D02*
G03I-720J0D01*
G37*
G36*
G01X1671120Y229462D02*
G03I-720J0D01*
G37*
G36*
G01X1673002Y429039D02*
X1682509D01*
X1684244Y427304D01*
Y421245D01*
X1690314Y415175D01*
X1693732D01*
X1693751Y415171D01*
G03X1694050Y415141I299J1472D01*
G03X1694349Y415171I0J1502D01*
G01X1694368Y415175D01*
X1703304D01*
X1703544Y414935D01*
Y414465D01*
X1703294Y414215D01*
X1695994D01*
X1695274Y413495D01*
Y411925D01*
X1695974Y411225D01*
X1701344D01*
X1701564Y411005D01*
Y410435D01*
X1701374Y410245D01*
X1696634D01*
X1695534Y409145D01*
X1685160D01*
X1681970Y405955D01*
Y395002D01*
X1682970Y394002D01*
X1691910D01*
X1694480Y391432D01*
Y380132D01*
X1698350Y376262D01*
Y372032D01*
X1699310Y371072D01*
X1702120D01*
X1702680Y370512D01*
Y368992D01*
X1702180Y368492D01*
X1673980D01*
X1664550Y377922D01*
Y391172D01*
X1667060Y393682D01*
Y407412D01*
X1661830Y412642D01*
X1656860D01*
X1656722Y412781D01*
Y415632D01*
X1659690D01*
X1660370Y416312D01*
X1671472D01*
X1672362Y417202D01*
Y428399D01*
X1673002Y429039D01*
G37*
G36*
G01X1666720Y440952D02*
X1714820D01*
X1715870Y439902D01*
Y436002D01*
X1715920Y435952D01*
Y422952D01*
X1715513Y422545D01*
X1709344D01*
X1709144Y422745D01*
Y431945D01*
X1709009Y432080D01*
X1708995Y432132D01*
G03X1707544Y433246I-1451J-388D01*
G03X1706134Y432261I0J-1502D01*
G01X1706119Y432220D01*
X1706044Y432145D01*
Y431808D01*
G03X1706042Y431745I1499J-79D01*
G01Y430183D01*
X1705614Y429755D01*
X1700114D01*
X1700044Y429684D01*
X1699874D01*
Y429516D01*
X1699604Y429245D01*
Y419505D01*
X1700034Y419075D01*
X1701294D01*
X1701584Y418785D01*
Y418455D01*
X1701284Y418155D01*
X1698844D01*
X1698684Y418315D01*
Y421155D01*
X1696673Y423166D01*
G03X1696346Y423496I-1218J-879D01*
G01X1696334Y423505D01*
X1696014Y423825D01*
Y429913D01*
X1695472Y430455D01*
X1693014D01*
X1692814Y430655D01*
Y436215D01*
X1692777Y436252D01*
X1687920D01*
X1687620Y435952D01*
Y431952D01*
X1686820Y431152D01*
X1675920D01*
X1675120Y430352D01*
X1672220D01*
X1670620Y428752D01*
Y420452D01*
X1669720Y419552D01*
X1665720D01*
X1665220Y420052D01*
Y439452D01*
X1666720Y440952D01*
G37*
G36*
G01X1667712Y520017D02*
X1662481D01*
X1662243Y520255D01*
Y521963D01*
X1662512Y522232D01*
Y523972D01*
X1664502Y525962D01*
Y529445D01*
X1665393Y530336D01*
X1667490D01*
X1667712Y530114D01*
Y523142D01*
X1668450Y522404D01*
Y520262D01*
X1668205Y520017D01*
X1667712D01*
G37*
G36*
G01X1668904Y529765D02*
X1683104D01*
X1683304Y529965D01*
Y544165D01*
X1683104Y544365D01*
X1668904D01*
X1668784Y544245D01*
Y529886D01*
X1668904Y529765D01*
G37*
G36*
G01X1678875Y16999D02*
G03I-720J0D01*
G37*
G36*
G01Y21991D02*
G03I-720J0D01*
G37*
G36*
G01X1683831Y16999D02*
G03I-720J0D01*
G37*
G36*
G01Y21991D02*
G03I-720J0D01*
G37*
G36*
G01X1676875Y19495D02*
G03I-720J0D01*
G37*
G36*
G01X1685831D02*
G03I-720J0D01*
G37*
G36*
G01X1676726Y23935D02*
G03I-720J0D01*
G37*
G36*
G01X1685943D02*
G03I-720J0D01*
G37*
G36*
G01X1678726Y25931D02*
G03I-720J0D01*
G37*
G36*
G01X1683943D02*
G03I-720J0D01*
G37*
G36*
G01X1673698Y66801D02*
G03I-720J0D01*
G37*
G36*
G01X1688876Y69297D02*
G03I-720J0D01*
G37*
G36*
G01X1675698D02*
G03I-720J0D01*
G37*
G36*
G01X1673698Y71793D02*
G03I-720J0D01*
G37*
G36*
G01X1677876Y75297D02*
G03I-720J0D01*
G37*
G36*
G01X1686832D02*
G03I-720J0D01*
G37*
G36*
G01X1684832Y77793D02*
G03I-720J0D01*
G37*
G36*
G01Y72801D02*
G03I-720J0D01*
G37*
G36*
G01X1679876Y77793D02*
G03I-720J0D01*
G37*
G36*
G01Y72801D02*
G03I-720J0D01*
G37*
G36*
G01X1677020Y219762D02*
G03I-720J0D01*
G37*
G36*
G01X1682620Y227962D02*
G03I-720J0D01*
G37*
G36*
G01X1698167Y715985D02*
X1697532Y715350D01*
X1679467D01*
X1678948Y715869D01*
Y729366D01*
X1679437Y729855D01*
X1696300D01*
X1697580Y728575D01*
Y726442D01*
X1699100Y724922D01*
X1702457D01*
X1703037Y724342D01*
Y720635D01*
X1703847Y719825D01*
Y716855D01*
X1702977Y715985D01*
X1698167D01*
G37*
G36*
G01X1693048Y16999D02*
G03I-720J0D01*
G37*
G36*
G01Y21991D02*
G03I-720J0D01*
G37*
G36*
G01X1698004Y16999D02*
G03I-720J0D01*
G37*
G36*
G01Y21991D02*
G03I-720J0D01*
G37*
G36*
G01X1691048Y19495D02*
G03I-720J0D01*
G37*
G36*
G01X1700004D02*
G03I-720J0D01*
G37*
G36*
G01X1690899Y23935D02*
G03I-720J0D01*
G37*
G36*
G01X1692899Y25931D02*
G03I-720J0D01*
G37*
G36*
G01X1697832Y69297D02*
G03I-720J0D01*
G37*
G36*
G01X1690876Y66801D02*
G03I-720J0D01*
G37*
G36*
G01X1695832D02*
G03I-720J0D01*
G37*
G36*
G01X1690876Y71793D02*
G03I-720J0D01*
G37*
G36*
G01X1695832D02*
G03I-720J0D01*
G37*
G36*
G01X1699876Y75297D02*
G03I-720J0D01*
G37*
G36*
G01X1701876Y77793D02*
G03I-720J0D01*
G37*
G36*
G01Y72801D02*
G03I-720J0D01*
G37*
G36*
G01X1692200Y234462D02*
X1693000Y235262D01*
X1705400D01*
X1706200Y234462D01*
Y229262D01*
X1705700Y228762D01*
X1693100D01*
X1692200Y229662D01*
Y234462D01*
G37*
G36*
G01X1697910Y394082D02*
X1719520D01*
X1720960Y392642D01*
Y377712D01*
X1719310Y376062D01*
X1710506D01*
G03X1708674I-916J-1779D01*
G01X1704100D01*
X1702760Y374722D01*
Y372702D01*
X1700550D01*
X1699650Y373602D01*
Y377282D01*
X1696550Y380382D01*
Y392722D01*
X1697910Y394082D01*
G37*
G36*
G01X1700594Y408505D02*
Y409005D01*
X1700824Y409235D01*
X1704014D01*
X1707754D01*
X1708444Y408545D01*
X1711444D01*
X1711944Y408045D01*
Y406545D01*
X1711444Y406045D01*
X1707204D01*
X1703054D01*
X1700594Y408505D01*
G37*
G36*
G01X1717520Y425852D02*
X1720320D01*
X1720820Y425352D01*
Y422652D01*
X1720869Y422603D01*
Y412185D01*
X1708184D01*
X1708159Y412191D01*
G03X1707780Y412240I-380J-1453D01*
G03X1707401Y412191I1J-1502D01*
G01X1707376Y412185D01*
X1701800D01*
X1701759Y412226D01*
X1696942D01*
X1696704Y412465D01*
Y412915D01*
X1696914Y413125D01*
X1703424D01*
X1703512Y413214D01*
X1703709D01*
X1704546Y414050D01*
Y415350D01*
X1704484Y415411D01*
Y415425D01*
X1703734Y416175D01*
X1703720D01*
X1703719Y416176D01*
X1698872D01*
X1698684Y416365D01*
Y416985D01*
X1698814Y417115D01*
X1708154D01*
X1709506Y418466D01*
X1716034D01*
X1716920Y419352D01*
Y422536D01*
X1716922Y422537D01*
Y425253D01*
X1717520Y425852D01*
G37*
G36*
G01X1710123Y490944D02*
X1713359D01*
X1713409Y490994D01*
Y491586D01*
X1713351Y491644D01*
X1692203D01*
X1692111Y491552D01*
Y489473D01*
X1692215Y489369D01*
X1695334D01*
X1695353Y489350D01*
X1695560Y489143D01*
Y477138D01*
X1695691Y477007D01*
X1709913D01*
X1709960Y477054D01*
Y490781D01*
X1710123Y490944D01*
G37*
G36*
G01X1691998Y477206D02*
Y469021D01*
X1692816Y468203D01*
X1698741D01*
X1699067Y468529D01*
Y471657D01*
X1698383Y472341D01*
X1694930D01*
X1694539Y472732D01*
Y477423D01*
X1694430Y477532D01*
X1692324D01*
X1691998Y477206D01*
G37*
G36*
G01X1704517Y656481D02*
Y638201D01*
X1703938Y637621D01*
X1698300D01*
X1695590D01*
X1695098Y638113D01*
Y657083D01*
X1695510Y657495D01*
X1696695Y658680D01*
X1703430D01*
X1704517Y657593D01*
Y656481D01*
G37*
G36*
G01X1705022Y708142D02*
X1705792D01*
X1705932Y708002D01*
Y705505D01*
X1706152Y705285D01*
X1707627D01*
X1707808Y705104D01*
Y704566D01*
G03X1708175Y703681I1252J1D01*
G01X1708320Y703536D01*
Y700462D01*
X1707920Y700062D01*
X1706453D01*
X1705620Y700895D01*
X1703187D01*
X1702822Y701260D01*
Y703264D01*
X1704832Y705274D01*
Y707952D01*
X1705022Y708142D01*
G37*
G36*
G01X1704947Y717247D02*
Y720375D01*
X1704072Y721250D01*
Y723950D01*
X1704102Y723980D01*
Y727382D01*
X1704522Y727802D01*
X1705827D01*
X1705967Y727662D01*
Y724205D01*
X1706097Y724075D01*
Y719705D01*
Y717267D01*
X1705980Y717150D01*
X1705044D01*
X1704947Y717247D01*
G37*
G36*
G01X1725780Y701622D02*
X1717955D01*
X1716425Y703152D01*
Y710442D01*
Y712557D01*
X1715220Y713762D01*
X1710976D01*
X1710848Y713890D01*
X1710708Y714030D01*
X1699462D01*
X1699268Y714224D01*
Y714439D01*
Y714780D01*
X1699420Y714932D01*
X1709683D01*
X1710020Y715269D01*
X1715438Y720687D01*
X1724995D01*
X1727645D01*
X1727850Y720482D01*
Y701902D01*
X1727570Y701622D01*
X1725780D01*
G37*
G36*
G01X1708832Y75297D02*
G03I-720J0D01*
G37*
G36*
G01X1706832Y77793D02*
G03I-720J0D01*
G37*
G36*
G01Y72801D02*
G03I-720J0D01*
G37*
G36*
G01X1719663Y118267D02*
X1722918D01*
X1723318Y117867D01*
Y111567D01*
X1723218Y111467D01*
X1719218D01*
X1718518Y112167D01*
Y113047D01*
X1718526Y113074D01*
G03X1718602Y113622I-1926J546D01*
G03X1718526Y114170I-2002J2D01*
G01X1718518Y114197D01*
Y117321D01*
G03X1719663Y118267I-1607J3111D01*
G37*
G36*
G01X1760093Y198350D02*
X1756081Y202362D01*
X1719270D01*
X1717270Y204362D01*
Y226783D01*
X1718918Y228432D01*
X1804130D01*
X1805700Y226862D01*
Y199850D01*
X1804200Y198350D01*
X1760093D01*
G37*
G36*
G01X1766388Y194789D02*
G03X1773192I3402J0D01*
G03X1772799Y196376I-3401J0D01*
G02X1773153Y196962I354J186D01*
G01X1795987D01*
G02X1796341Y196376I0J-400D01*
G03X1795948Y194789I3008J-1587D01*
G03X1802752I3402J0D01*
G03X1802359Y196376I-3401J0D01*
G02X1802713Y196962I354J186D01*
G01X1804900D01*
X1807500Y199562D01*
Y226928D01*
X1804400Y230028D01*
X1719134D01*
X1716800Y232362D01*
Y336462D01*
X1721300Y340962D01*
X1814200D01*
X1815500Y339662D01*
Y304262D01*
X1814000Y302762D01*
X1787843D01*
X1776446Y314159D01*
X1773985D01*
X1746286D01*
X1741286Y309159D01*
Y277965D01*
X1743286Y275965D01*
X1746800D01*
X1749084Y278249D01*
Y281579D01*
X1749404Y281899D01*
X1754494D01*
X1754964Y282369D01*
Y285119D01*
X1754984Y285139D01*
X1761394D01*
X1761404Y285149D01*
Y288689D01*
X1761394Y288699D01*
X1758454D01*
X1758444Y288709D01*
Y296439D01*
X1758464Y296459D01*
X1772404D01*
X1772414Y296449D01*
Y289879D01*
X1767894D01*
X1767884Y289869D01*
Y279379D01*
X1767894Y279369D01*
X1773544D01*
X1773674Y279239D01*
X1794000D01*
X1797477Y275762D01*
X1815586D01*
X1816286Y275062D01*
Y232908D01*
X1816220Y232842D01*
Y186482D01*
X1815600Y185862D01*
X1761800D01*
X1754900Y192762D01*
X1735700D01*
X1735000Y193462D01*
Y200188D01*
X1736172Y201360D01*
X1755302D01*
X1759700Y196962D01*
X1766427D01*
G02X1766781Y196376I0J-400D01*
G03X1766388Y194789I3008J-1587D01*
G37*
G36*
G01X1712212Y468379D02*
G03I-735J0D01*
G37*
G36*
G01Y465229D02*
G03I-735J0D01*
G37*
G36*
G01X1706760Y708960D02*
X1706860Y709060D01*
X1709540D01*
X1709640Y708960D01*
Y706390D01*
X1709560Y706310D01*
X1707150D01*
X1706934Y706526D01*
Y708417D01*
X1706760Y708590D01*
Y708960D01*
G37*
G36*
G01X1713368Y1557099D02*
X1831068D01*
X1836601D01*
X1839054Y1554646D01*
Y1549113D01*
Y1520131D01*
X1838838Y1519915D01*
X1797545D01*
X1797450Y1520009D01*
Y1533011D01*
X1787510Y1542951D01*
X1723468D01*
X1721649Y1541132D01*
Y1493261D01*
X1721133Y1492745D01*
X1719565Y1491176D01*
X1710486D01*
X1708986D01*
X1707300Y1492862D01*
Y1551032D01*
X1708280Y1552012D01*
X1713368Y1557099D01*
G37*
G36*
G01X1732964Y35562D02*
X1736120D01*
X1737020Y34662D01*
Y27462D01*
X1735820Y26262D01*
X1722420D01*
X1721220Y27462D01*
Y35362D01*
X1721420Y35562D01*
X1722670D01*
Y29989D01*
X1722751Y29908D01*
X1723423D01*
X1723514Y29999D01*
Y35562D01*
X1725032D01*
Y29989D01*
X1725113Y29908D01*
X1725785D01*
X1725876Y29999D01*
Y35562D01*
X1727394D01*
Y29989D01*
X1727475Y29908D01*
X1728147D01*
X1728238Y29999D01*
Y35562D01*
X1729756D01*
Y29989D01*
X1729838Y29908D01*
X1730510D01*
X1730602Y29999D01*
Y35562D01*
X1732118D01*
Y29989D01*
X1732200Y29908D01*
X1732872D01*
X1732964Y29999D01*
Y35562D01*
G37*
G36*
G01X1735128Y107007D02*
X1735158Y107037D01*
X1749928D01*
X1749968Y106997D01*
Y99057D01*
X1752398Y96627D01*
X1752710D01*
X1754745Y94592D01*
X1755000D01*
X1755350Y94242D01*
Y67522D01*
X1756145Y66727D01*
X1774400D01*
Y66752D01*
X1777110Y69462D01*
Y85762D01*
X1777330Y85982D01*
X1777790D01*
X1777980Y85792D01*
Y78742D01*
X1778430Y78292D01*
X1780500D01*
X1781050Y78842D01*
Y83802D01*
X1781270Y84022D01*
X1781700D01*
X1781986Y83736D01*
Y82892D01*
X1782000Y82879D01*
Y73192D01*
X1788465Y66727D01*
X1792373D01*
X1793078Y66022D01*
Y55660D01*
X1792260Y54842D01*
X1783234D01*
X1783186Y54974D01*
G03X1780362I-1412J-512D01*
G01X1780314Y54842D01*
X1779425D01*
G03X1776710Y56564I-2715J-1279D01*
G03X1774582Y55680I0J-3003D01*
G02X1774002Y55694I-283J282D01*
G03X1771774Y56684I-2228J-2012D01*
G03X1769005Y54842I0J-3002D01*
G01X1768135D01*
X1768089Y54868D01*
G03X1767220Y55098I-869J-1527D01*
G03X1766306Y54842I-1J-1756D01*
G01X1763507D01*
X1763467Y54860D01*
G03X1762738Y55018I-728J-1598D01*
G03X1762009Y54860I-1J-1756D01*
G01X1761969Y54842D01*
X1755420D01*
X1748670Y48092D01*
Y39782D01*
X1747741Y38853D01*
X1747706Y38838D01*
G03X1747006Y38272I695J-1575D01*
G01X1722300D01*
X1721230Y39342D01*
Y48295D01*
X1726767Y53832D01*
X1733200D01*
X1734220Y54852D01*
Y86399D01*
X1735128Y87307D01*
Y107007D01*
G37*
G36*
G01X1722420Y83762D02*
X1729020D01*
X1731620Y81162D01*
Y68462D01*
X1733218Y66864D01*
Y56961D01*
X1732420Y56162D01*
X1729620D01*
X1728603Y57179D01*
X1728602Y57260D01*
G03X1728220Y58408I-2002J-29D01*
G01Y66062D01*
X1726976Y67306D01*
Y67762D01*
G03X1726616Y68721I-1457J0D01*
G03X1725320Y69464I-1296J-759D01*
G03X1724987Y69427I-2J-1502D01*
G01X1724880Y69402D01*
X1721220Y73062D01*
Y82562D01*
X1722420Y83762D01*
G37*
G36*
G01X1734100Y87752D02*
X1733865Y87517D01*
X1729465D01*
X1728930Y86982D01*
X1727540D01*
X1727000Y87522D01*
Y89422D01*
X1727540Y89962D01*
X1729100D01*
X1730678Y91540D01*
Y100684D01*
X1732478Y102484D01*
Y106717D01*
X1732778Y107017D01*
X1734100D01*
Y87752D01*
G37*
G36*
G01X1728618Y106167D02*
Y97467D01*
X1728118Y96967D01*
X1725218D01*
X1724918Y97267D01*
Y106167D01*
X1725518Y106767D01*
X1728018D01*
X1728618Y106167D01*
G37*
G36*
G01X1721418Y106767D02*
X1723916D01*
Y96852D01*
X1724018Y96751D01*
Y96067D01*
X1724818Y95267D01*
X1728218D01*
X1728518Y94967D01*
Y91967D01*
X1728018Y91467D01*
X1723118D01*
X1721218Y93367D01*
Y106567D01*
X1721418Y106767D01*
G37*
G36*
G01X1757104Y118167D02*
X1784708D01*
X1790038Y112837D01*
Y104322D01*
X1789698Y103982D01*
X1781230D01*
X1779830Y102582D01*
Y99472D01*
X1779950Y99352D01*
Y79382D01*
X1779862Y79294D01*
X1779238D01*
X1779040Y79492D01*
Y86162D01*
X1778460Y86742D01*
X1778446D01*
X1778205Y86984D01*
X1776915D01*
X1776674Y86742D01*
X1776380D01*
X1775980Y86342D01*
Y81322D01*
X1775830Y81172D01*
X1775340D01*
X1775070Y81442D01*
Y87935D01*
X1775075Y87958D01*
G03X1775113Y88293I-1464J336D01*
G03X1775075Y88628I-1502J-1D01*
G01X1775070Y88651D01*
Y97592D01*
X1773300Y99362D01*
X1767420D01*
X1764120Y102662D01*
X1757123D01*
X1751613Y108172D01*
X1734913D01*
X1734618Y108467D01*
Y113367D01*
X1734918Y113667D01*
X1752604D01*
X1757104Y118167D01*
G37*
G36*
G01X1725810Y119652D02*
X1732330D01*
X1734120Y117862D01*
Y115062D01*
X1733920Y114862D01*
X1724820D01*
X1724420Y115262D01*
Y118262D01*
X1725810Y119652D01*
G37*
G36*
G01X1724618Y136367D02*
X1755318D01*
X1756318Y135367D01*
Y129698D01*
X1750918D01*
G03X1750546Y129650I0J-1465D01*
G01X1750521Y129644D01*
X1750329D01*
G03X1749432Y128754I-7J-890D01*
G01Y127700D01*
X1749560D01*
X1749616Y127590D01*
G03X1749644Y127537I1301J654D01*
G01X1749668Y127492D01*
Y126867D01*
X1745918D01*
X1745418Y127367D01*
Y129567D01*
X1744318Y130667D01*
X1738418D01*
X1737818Y130067D01*
Y127567D01*
X1737518Y127267D01*
X1724398D01*
X1724058Y127607D01*
Y135807D01*
X1724618Y136367D01*
G37*
G36*
G01X1728320Y1469462D02*
X1741620D01*
X1742220Y1468862D01*
Y1449862D01*
X1741220Y1448862D01*
X1728720D01*
X1727720Y1449862D01*
Y1468862D01*
X1728320Y1469462D01*
G37*
G36*
G01X1724733Y1541246D02*
X1755639D01*
X1757723Y1539161D01*
Y1495935D01*
X1756549Y1494761D01*
Y1494691D01*
X1755220Y1493362D01*
Y1478862D01*
Y1474342D01*
X1754440Y1473562D01*
X1752420D01*
X1751020D01*
X1726720D01*
X1722906Y1477376D01*
Y1494761D01*
X1722649Y1495018D01*
Y1539161D01*
X1724733Y1541246D01*
G37*
G36*
G01X1749120Y37262D02*
G03I-720J0D01*
G37*
G36*
G01X1750970Y101362D02*
X1754930D01*
X1758130Y98162D01*
X1769320D01*
X1769678Y97804D01*
Y91827D01*
X1769478Y91627D01*
X1760278D01*
X1760143Y91492D01*
X1760091Y91478D01*
G03X1758976Y90027I387J-1451D01*
G03X1759962Y88616I1503J0D01*
G01X1760004Y88601D01*
X1760078Y88527D01*
X1760405D01*
G03X1760478Y88525I78J1500D01*
G03X1760551Y88527I-5J1502D01*
G01X1762038D01*
X1762468Y88097D01*
Y82597D01*
X1762538Y82526D01*
Y82358D01*
X1762708D01*
X1762978Y82087D01*
X1772718D01*
X1773148Y82517D01*
Y83777D01*
X1773438Y84067D01*
X1773768D01*
X1774068Y83767D01*
Y81327D01*
X1773908Y81167D01*
X1771068D01*
X1768398Y78497D01*
X1762310D01*
X1761768Y77955D01*
Y75497D01*
X1761568Y75297D01*
X1756352D01*
Y94657D01*
X1755415Y95594D01*
X1755160D01*
X1753125Y97628D01*
X1752813D01*
X1750970Y99472D01*
Y101362D01*
G37*
G36*
G01X1738424Y183139D02*
G03I-720J0D01*
G37*
G36*
G01X1747945Y295199D02*
Y299797D01*
X1748930Y300782D01*
X1751780D01*
X1752086Y301088D01*
Y304276D01*
X1751500Y304862D01*
X1743500D01*
X1742274Y303636D01*
Y300023D01*
Y299091D01*
Y295638D01*
X1742971Y294941D01*
X1747687D01*
X1747945Y295199D01*
G37*
G36*
G01X1749709Y380206D02*
G03I-720J0D01*
G37*
G36*
G01X1741557Y1324415D02*
X1749707D01*
X1750247Y1323875D01*
Y1309425D01*
X1749407Y1308585D01*
X1746037D01*
X1745487Y1309135D01*
Y1314510D01*
G03X1745736Y1315043I-449J535D01*
G01Y1317013D01*
G03X1745039Y1317710I-698J-1D01*
G01X1741099D01*
G03X1740971Y1317698I1J-698D01*
G02X1740497Y1318091I-74J393D01*
G01Y1323355D01*
X1741557Y1324415D01*
G37*
G36*
G01X1745220Y1460362D02*
X1743520Y1458662D01*
Y1449862D01*
X1744520Y1448862D01*
X1764420D01*
X1769020Y1453462D01*
Y1491062D01*
X1767420Y1492662D01*
X1758720D01*
X1758690Y1492632D01*
X1757400D01*
X1756790Y1492022D01*
Y1469232D01*
X1747820Y1460262D01*
X1745320D01*
X1745220Y1460362D01*
G37*
G36*
G01X1754810Y16302D02*
G03I-720J0D01*
G37*
G36*
G01X1764978Y135227D02*
X1796465D01*
X1798380Y133312D01*
Y73272D01*
X1806040Y65612D01*
X1809530D01*
X1811890Y63252D01*
Y55272D01*
X1811273Y54655D01*
X1795358D01*
X1794978Y55035D01*
Y63727D01*
X1795956Y64706D01*
Y69499D01*
X1795971Y69536D01*
G03X1796122Y70297I-1851J763D01*
G01Y94273D01*
G03X1795971Y95034I-2002J-2D01*
G01X1795956Y95071D01*
Y100196D01*
X1791278Y104874D01*
Y113427D01*
X1785478Y119227D01*
X1763078D01*
X1762978Y119327D01*
Y133227D01*
X1764978Y135227D01*
G37*
G36*
G01X1766590Y179392D02*
G03I-720J0D01*
G37*
G36*
G01X1817577Y304462D02*
X1844900D01*
X1849200Y300162D01*
Y252762D01*
X1844600Y248162D01*
X1820500D01*
X1818259Y250403D01*
Y258903D01*
X1818200Y258962D01*
Y275579D01*
G03X1818141Y275721I-200J0D01*
G01X1816959Y276903D01*
G03X1816817Y276962I-142J-141D01*
G01X1797600D01*
X1794572Y279990D01*
G03X1794430Y280049I-142J-141D01*
G01X1782063D01*
X1781918Y280194D01*
X1769652D01*
X1769084Y280762D01*
Y288674D01*
X1769208Y288809D01*
X1771849D01*
X1771894Y288798D01*
X1773370D01*
X1773644Y289072D01*
X1780157D01*
X1780186Y289085D01*
X1784134D01*
G03X1784276Y289144I0J200D01*
G01X1786662Y291530D01*
Y299914D01*
X1788300Y301552D01*
X1814667D01*
X1817577Y304462D01*
G37*
G36*
G01X1769477Y380498D02*
G03I-720J0D01*
G37*
G36*
G01X1760213Y728648D02*
X1767112D01*
X1769112Y726648D01*
Y692060D01*
X1768369Y691317D01*
X1760103D01*
X1759322Y692098D01*
Y727756D01*
X1760213Y728648D01*
G37*
G36*
G01X1757660Y1356552D02*
X1781672D01*
X1785922Y1352302D01*
Y1322320D01*
X1785402Y1321800D01*
X1770598D01*
Y1331341D01*
G03X1770398Y1332090I-1501J0D01*
G01Y1333541D01*
G03X1769897Y1334042I-501J0D01*
G01X1768297D01*
G03X1767796Y1333541I0J-501D01*
G01Y1332090D01*
G03X1767596Y1331341I1301J-749D01*
G01Y1322020D01*
X1760762D01*
X1760347Y1322435D01*
Y1323035D01*
X1759677Y1323705D01*
X1756992D01*
X1756162Y1324535D01*
Y1355054D01*
X1757660Y1356552D01*
G37*
G36*
G01X1776779Y1714960D02*
G02I-9850J0D01*
G37*
G36*
G01X1783718Y83077D02*
X1783218D01*
X1782988Y83307D01*
Y86497D01*
Y90237D01*
X1783678Y90927D01*
Y90932D01*
X1784170Y91424D01*
Y93937D01*
X1784660Y94427D01*
X1785678D01*
X1786178Y93927D01*
Y89687D01*
Y85537D01*
X1783718Y83077D01*
G37*
G36*
G01X1781040Y177602D02*
G03I-720J0D01*
G37*
G36*
G01X1776880Y592792D02*
G03I-720J0D01*
G37*
G36*
G01X1801343Y1518080D02*
X1801506Y1517917D01*
Y1516712D01*
X1801374Y1516580D01*
X1797550D01*
X1787958D01*
X1786923Y1515545D01*
Y1511345D01*
Y1508845D01*
X1787523Y1508245D01*
X1789523D01*
X1789890Y1507878D01*
Y1505692D01*
X1788930Y1504732D01*
X1774736D01*
X1773123Y1506345D01*
Y1524045D01*
X1773508Y1524430D01*
X1774423Y1525345D01*
X1785670D01*
X1792935Y1518080D01*
X1801343D01*
G37*
G36*
G01X1788823Y1512345D02*
Y1510445D01*
X1789023Y1510245D01*
X1793423D01*
X1793723Y1510545D01*
Y1512245D01*
X1793423Y1512545D01*
X1789023D01*
X1788823Y1512345D01*
G37*
G36*
G01X1791113Y1508345D02*
X1794023D01*
X1795023Y1509345D01*
Y1512145D01*
X1795423Y1512545D01*
X1796323D01*
X1796523Y1512345D01*
Y1508245D01*
X1793523Y1505245D01*
X1791223D01*
X1790890Y1505578D01*
Y1508122D01*
X1791113Y1508345D01*
G37*
G36*
G01X1798550Y1515580D02*
X1802633D01*
X1804774Y1517721D01*
X1804783D01*
X1805499Y1518437D01*
X1838515D01*
X1839160Y1517792D01*
Y1510512D01*
X1836840Y1508192D01*
X1829450D01*
X1828030Y1509612D01*
X1819960D01*
X1816944Y1512628D01*
X1813806D01*
X1812523Y1513912D01*
X1811620D01*
X1791852D01*
X1791385Y1513445D01*
X1789123D01*
X1788823Y1513745D01*
Y1515345D01*
X1789058Y1515580D01*
X1798550D01*
G37*
G36*
G01X1820000Y236694D02*
Y239122D01*
X1820600Y239722D01*
X1840729D01*
X1848440D01*
X1849200Y238962D01*
Y238462D01*
Y220362D01*
X1848700Y219862D01*
X1822600D01*
X1820600D01*
X1820000Y220462D01*
Y236694D01*
G37*
G36*
G01X1833098Y1494480D02*
X1824440D01*
X1823720Y1495200D01*
Y1504293D01*
X1825019Y1505592D01*
X1832690D01*
X1834130Y1504152D01*
Y1495512D01*
X1833098Y1494480D01*
G37*
G36*
G01X1839974Y1598129D02*
G02X1841691Y1593983I-4147J-4146D01*
G01Y1389300D01*
G02X1841559Y1389112I-200J0D01*
G01X1841146Y1388962D01*
X1841024Y1388995D01*
X1840984Y1389044D01*
G03X1839748Y1390443I-24213J-20147D01*
G02X1839694Y1390580I146J137D01*
G01Y1413131D01*
G02X1839705Y1413196I200J0D01*
G03X1840910Y1420330I-20498J7131D01*
G03X1839705Y1427464I-21703J3D01*
G02X1839694Y1427529I189J65D01*
G01Y1593984D01*
G03X1838562Y1596717I-3867J-1D01*
G01X1831363Y1603916D01*
G02X1827883Y1612316I8400J8401D01*
G01X1827882D01*
Y1691933D01*
G02X1827945Y1692079I200J0D01*
G03X1829189Y1693323I-21642J22886D01*
G01X1829232Y1693368D01*
X1829351Y1693395D01*
X1829754Y1693234D01*
G02X1829880Y1693049I-74J-186D01*
G01Y1612316D01*
G03X1832775Y1605328I9883J1D01*
G01X1839974Y1598129D01*
G37*
G36*
G01X1853753Y309940D02*
G02X1855470Y305794I-4147J-4146D01*
G01Y107417D01*
G02X1855335Y107228I-200J0D01*
G01X1854916Y107084D01*
X1854794Y107120D01*
X1854755Y107171D01*
G03X1853523Y108654I-24833J-19377D01*
G02X1853472Y108787I149J133D01*
G01Y124078D01*
G02X1853481Y124137I200J0D01*
G03X1853940Y127165I-9780J3031D01*
G01Y133464D01*
G03X1853481Y136492I-10239J-3D01*
G02X1853472Y136551I191J59D01*
G01Y305795D01*
G03X1852341Y308528I-3867J0D01*
G01X1843174Y317695D01*
G02X1839694Y326095I8401J8401D01*
G01Y333362D01*
G02X1839894Y333562I200J0D01*
G01X1841491D01*
G02X1841691Y333362I0J-200D01*
G01Y326095D01*
G03X1844586Y319107I9884J1D01*
G01X1853753Y309940D01*
G37*
G36*
G01X1841024Y611792D02*
X1841146Y611825D01*
X1841559Y611675D01*
G02X1841691Y611487I-68J-188D01*
G01Y341968D01*
G02X1841491Y341768I-200J0D01*
G01X1839893D01*
G02X1839694Y341967I1J200D01*
G01Y453169D01*
X1839704Y453214D01*
X1839716Y453236D01*
G03X1839881Y453921I-1337J684D01*
G03X1839716Y454606I-1502J1D01*
G01X1839704Y454628D01*
X1839694Y454673D01*
Y610208D01*
G02X1839748Y610344I200J-1D01*
G03X1840984Y611743I-22977J21546D01*
G01X1841024Y611792D01*
G37*
G36*
G01X1839748Y1347351D02*
G03X1840984Y1348750I-22977J21546D01*
G01X1841024Y1348799D01*
X1841146Y1348832D01*
X1841559Y1348682D01*
G02X1841691Y1348494I-68J-188D01*
G01Y652293D01*
G02X1841559Y652105I-200J0D01*
G01X1841146Y651955D01*
X1841024Y651988D01*
X1840984Y652037D01*
G03X1839748Y653436I-24213J-20147D01*
G02X1839694Y653573I146J137D01*
G01Y1347214D01*
G02X1839748Y1347351I200J0D01*
G37*
%LPC*%
G75*
G36*
G01X245570Y1291266D02*
X250470D01*
G02Y1284062I0J-3602D01*
G01X245570D01*
G02Y1291266I0J3602D01*
G37*
G36*
G01X186170D02*
X191070D01*
G02Y1284062I0J-3602D01*
G01X186170D01*
G02Y1291266I0J3602D01*
G37*
G36*
G01X126770D02*
X131670D01*
G02Y1284062I0J-3602D01*
G01X126770D01*
G02Y1291266I0J3602D01*
G37*
G36*
G01X67370D02*
X72270D01*
G02Y1284062I0J-3602D01*
G01X67370D01*
G02Y1291266I0J3602D01*
G37*
G36*
G01X215870D02*
X220770D01*
G02Y1284062I0J-3602D01*
G01X215870D01*
G02Y1291266I0J3602D01*
G37*
G36*
G01X156470D02*
X161370D01*
G02Y1284062I0J-3602D01*
G01X156470D01*
G02Y1291266I0J3602D01*
G37*
G36*
G01X97070D02*
X101970D01*
G02Y1284062I0J-3602D01*
G01X97070D01*
G02Y1291266I0J3602D01*
G37*
G36*
G01X37670D02*
X42570D01*
G02Y1284062I0J-3602D01*
G01X37670D01*
G02Y1291266I0J3602D01*
G37*
G36*
G01X191586Y1269737D02*
G03X191584Y1270290I-290J275D01*
G02X191192Y1271262I1009J972D01*
G02X193996I1402J0D01*
G02X193613Y1270299I-1402J0D01*
G03X193615Y1269746I290J-275D01*
G02X194007Y1268774I-1009J-972D01*
G02X191203I-1402J0D01*
G02X191586Y1269737I1402J0D01*
G37*
G36*
G01X205351Y1269717D02*
G03X205336Y1270300I-281J284D01*
G02X204866Y1271348I933J1048D01*
G02X207670I1402J0D01*
G02X207254Y1270351I-1403J0D01*
G03X207269Y1269768I281J-284D01*
G02X207739Y1268720I-933J-1048D01*
G02X204935I-1402J0D01*
G02X205351Y1269717I1403J0D01*
G37*
G36*
G01X32457Y1272481D02*
G03X31835I-311J-252D01*
G02X30746Y1271962I-1089J883D01*
G02Y1274766I0J1402D01*
G02X31835Y1274247I0J-1402D01*
G03X32457I311J252D01*
G02X33546Y1274766I1089J-883D01*
G02Y1271962I0J-1402D01*
G02X32457Y1272481I0J1402D01*
G37*
G36*
G01X48457D02*
G03X47835I-311J-252D01*
G02X46746Y1271962I-1089J883D01*
G02Y1274766I0J1402D01*
G02X47835Y1274247I0J-1402D01*
G03X48457I311J252D01*
G02X49546Y1274766I1089J-883D01*
G02Y1271962I0J-1402D01*
G02X48457Y1272481I0J1402D01*
G37*
G36*
G01X62157D02*
G03X61535I-311J-252D01*
G02X60446Y1271962I-1089J883D01*
G02Y1274766I0J1402D01*
G02X61535Y1274247I0J-1402D01*
G03X62157I311J252D01*
G02X63246Y1274766I1089J-883D01*
G02Y1271962I0J-1402D01*
G02X62157Y1272481I0J1402D01*
G37*
G36*
G01X78157D02*
G03X77535I-311J-252D01*
G02X76446Y1271962I-1089J883D01*
G02Y1274766I0J1402D01*
G02X77535Y1274247I0J-1402D01*
G03X78157I311J252D01*
G02X79246Y1274766I1089J-883D01*
G02Y1271962I0J-1402D01*
G02X78157Y1272481I0J1402D01*
G37*
G36*
G01X91857D02*
G03X91235I-311J-252D01*
G02X90146Y1271962I-1089J883D01*
G02Y1274766I0J1402D01*
G02X91235Y1274247I0J-1402D01*
G03X91857I311J252D01*
G02X92946Y1274766I1089J-883D01*
G02Y1271962I0J-1402D01*
G02X91857Y1272481I0J1402D01*
G37*
G36*
G01X107857D02*
G03X107235I-311J-252D01*
G02X106146Y1271962I-1089J883D01*
G02Y1274766I0J1402D01*
G02X107235Y1274247I0J-1402D01*
G03X107857I311J252D01*
G02X108946Y1274766I1089J-883D01*
G02Y1271962I0J-1402D01*
G02X107857Y1272481I0J1402D01*
G37*
G36*
G01X121557D02*
G03X120935I-311J-252D01*
G02X119846Y1271962I-1089J883D01*
G02Y1274766I0J1402D01*
G02X120935Y1274247I0J-1402D01*
G03X121557I311J252D01*
G02X122646Y1274766I1089J-883D01*
G02Y1271962I0J-1402D01*
G02X121557Y1272481I0J1402D01*
G37*
G36*
G01X137557D02*
G03X136935I-311J-252D01*
G02X135846Y1271962I-1089J883D01*
G02Y1274766I0J1402D01*
G02X136935Y1274247I0J-1402D01*
G03X137557I311J252D01*
G02X138646Y1274766I1089J-883D01*
G02Y1271962I0J-1402D01*
G02X137557Y1272481I0J1402D01*
G37*
G36*
G01X151257D02*
G03X150635I-311J-252D01*
G02X149546Y1271962I-1089J883D01*
G02Y1274766I0J1402D01*
G02X150635Y1274247I0J-1402D01*
G03X151257I311J252D01*
G02X152346Y1274766I1089J-883D01*
G02Y1271962I0J-1402D01*
G02X151257Y1272481I0J1402D01*
G37*
G36*
G01X167257D02*
G03X166635I-311J-252D01*
G02X165546Y1271962I-1089J883D01*
G02Y1274766I0J1402D01*
G02X166635Y1274247I0J-1402D01*
G03X167257I311J252D01*
G02X168346Y1274766I1089J-883D01*
G02Y1271962I0J-1402D01*
G02X167257Y1272481I0J1402D01*
G37*
G36*
G01X180957D02*
G03X180335I-311J-252D01*
G02X179246Y1271962I-1089J883D01*
G02Y1274766I0J1402D01*
G02X180335Y1274247I0J-1402D01*
G03X180957I311J252D01*
G02X182046Y1274766I1089J-883D01*
G02Y1271962I0J-1402D01*
G02X180957Y1272481I0J1402D01*
G37*
G36*
G01X226617Y1272533D02*
G03X226005Y1272571I-322J-237D01*
G02X224987Y1272133I-1018J964D01*
G02Y1274937I0J1402D01*
G02X226116Y1274366I0J-1402D01*
G03X226728Y1274328I322J237D01*
G02X227746Y1274766I1018J-964D01*
G02Y1271962I0J-1402D01*
G02X226617Y1272533I0J1402D01*
G37*
G36*
G01X256119Y1272743D02*
G03X255609Y1272832I-307J-256D01*
G02X254897Y1272638I-712J1208D01*
G02Y1275442I0J1402D01*
G02X255975Y1274937I0J-1403D01*
G03X256485Y1274848I307J256D01*
G02X257197Y1275042I712J-1208D01*
G02Y1272238I0J-1402D01*
G02X256119Y1272743I0J1403D01*
G37*
G36*
G01X239636Y1272700D02*
G03X239193Y1272969I-380J-126D01*
G02X238971Y1272951I-224J1384D01*
G02Y1275755I0J1402D01*
G02X240301Y1274796I0J-1402D01*
G03X240744Y1274527I380J126D01*
G02X240966Y1274545I224J-1384D01*
G02Y1271741I0J-1402D01*
G02X239636Y1272700I0J1402D01*
G37*
G36*
G01X186170Y748156D02*
X191070D01*
G02Y740952I0J-3602D01*
G01X186170D01*
G02Y748156I0J3602D01*
G37*
G36*
G01X126770D02*
X131670D01*
G02Y740952I0J-3602D01*
G01X126770D01*
G02Y748156I0J3602D01*
G37*
G36*
G01X67370D02*
X72270D01*
G02Y740952I0J-3602D01*
G01X67370D01*
G02Y748156I0J3602D01*
G37*
G36*
G01X215870D02*
X220770D01*
G02Y740952I0J-3602D01*
G01X215870D01*
G02Y748156I0J3602D01*
G37*
G36*
G01X156470D02*
X161370D01*
G02Y740952I0J-3602D01*
G01X156470D01*
G02Y748156I0J3602D01*
G37*
G36*
G01X97070D02*
X101970D01*
G02Y740952I0J-3602D01*
G01X97070D01*
G02Y748156I0J3602D01*
G37*
G36*
G01X181905Y738785D02*
G03X182535I315J246D01*
G02X184905I1185J-923D01*
G03X185535I315J246D01*
G02X186720Y739364I1185J-923D01*
G02X188222Y737862I0J-1502D01*
G02X187643Y736677I-1502J0D01*
G03Y736047I246J-315D01*
G02X188222Y734862I-923J-1185D01*
G02X186720Y733360I-1502J0D01*
G02X185535Y733939I0J1502D01*
G03X184905I-315J-246D01*
G02X182535I-1185J923D01*
G03X181905I-315J-246D01*
G02X180720Y733360I-1185J923D01*
G02X179218Y734862I0J1502D01*
G02X179797Y736047I1502J0D01*
G03Y736677I-246J315D01*
G02X179218Y737862I923J1185D01*
G02X180720Y739364I1502J0D01*
G02X181905Y738785I0J-1502D01*
G37*
G36*
G01X205234Y738064D02*
G03X205638Y738463I4J400D01*
G02X207140Y739964I1502J-1D01*
G02Y736960I0J-1502D01*
G01X207126D01*
G03X206722Y736561I-4J-400D01*
G02X205220Y735060I-1502J1D01*
G02Y738064I0J1502D01*
G01X205234D01*
G37*
G36*
G01X119922Y739649D02*
G03X120552I315J246D01*
G02X122922I1185J-923D01*
G03X123552I315J246D01*
G02X124737Y740228I1185J-923D01*
G02X126239Y738726I0J-1502D01*
G02X125660Y737541I-1502J0D01*
G03Y736911I246J-315D01*
G02X126239Y735726I-923J-1185D01*
G02X124737Y734224I-1502J0D01*
G02X123552Y734803I0J1502D01*
G03X122922I-315J-246D01*
G02X120552I-1185J923D01*
G03X119922I-315J-246D01*
G02X118737Y734224I-1185J923D01*
G02X117235Y735726I0J1502D01*
G02X117814Y736911I1502J0D01*
G03Y737541I-246J315D01*
G02X117235Y738726I923J1185D01*
G02X118737Y740228I1502J0D01*
G02X119922Y739649I0J-1502D01*
G37*
G36*
G01X268418Y739529D02*
G03X268836Y739987I23J399D01*
G02X268820Y740207I1486J219D01*
G02X270322Y738705I1502J0D01*
G02X270235Y738707I-9J1502D01*
G03X269817Y738249I-23J-399D01*
G02X269833Y738029I-1486J-219D01*
G02X268331Y739531I-1502J0D01*
G02X268418Y739529I9J-1502D01*
G37*
G36*
G01X274965Y725846D02*
G02X274247Y725663I-718J1319D01*
G02Y728667I0J1502D01*
G02X275739Y727334I0J-1501D01*
G03X276328Y727028I398J45D01*
G02X277046Y727211I718J-1319D01*
G02Y724207I0J-1502D01*
G02X275554Y725540I0J1501D01*
G03X274965Y725846I-398J-45D01*
G37*
G36*
G01X207905Y732785D02*
G03X208535I315J246D01*
G02X209720Y733364I1185J-923D01*
G02Y730360I0J-1502D01*
G02X208535Y730939I0J1502D01*
G03X207905I-315J-246D01*
G02X206720Y730360I-1185J923D01*
G02X205529Y730947I0J1502D01*
G03X204886Y730934I-317J-244D01*
G02X203660Y730300I-1226J868D01*
G02Y733304I0J1502D01*
G02X204851Y732717I0J-1502D01*
G03X205494Y732730I317J244D01*
G02X206720Y733364I1226J-868D01*
G02X207905Y732785I0J-1502D01*
G37*
G36*
G01X358665Y734742D02*
G02X357400Y736225I237J1483D01*
G02X360404I1502J0D01*
G02X359951Y735150I-1502J0D01*
G03X360167Y734468I279J-287D01*
G02X361432Y732985I-237J-1483D01*
G02X358428I-1502J0D01*
G02X358881Y734060I1502J0D01*
G03X358665Y734742I-279J287D01*
G37*
G36*
G01X273777Y737652D02*
G02X273708Y738102I1433J450D01*
G02X275210Y739604I1502J0D01*
G02X276524Y738830I0J-1502D01*
G03X277220Y738824I350J194D01*
G02X278520Y739574I1300J-752D01*
G02X279577Y739139I0J-1502D01*
G03X280108Y739111I281J284D01*
G02X281046Y739440I938J-1173D01*
G02Y736436I0J-1502D01*
G02X279989Y736871I0J1502D01*
G03X279458Y736899I-281J-284D01*
G02X279119Y736695I-937J1174D01*
G03X278907Y736180I160J-367D01*
G02X279048Y735442I-1861J-738D01*
G02X275044I-2002J0D01*
G02X275160Y736114I2002J0D01*
G03X274873Y736638I-377J134D01*
G02X274577Y736740I339J1463D01*
G03X274323Y736453I-84J-181D01*
G02X274548Y735662I-1278J-791D01*
G02X273046Y737164I-1502J0D01*
G02X273322Y737138I-2J-1502D01*
G03X273777Y737652I74J393D01*
G37*
G36*
G01X199444Y737877D02*
G02X199220Y737860I-225J1485D01*
G02X200722Y739362I0J1502D01*
G02X200576Y738715I-1502J-1D01*
G03X200996Y738147I361J-173D01*
G02X201220Y738164I225J-1485D01*
G02X199718Y736662I0J-1502D01*
G02X199864Y737309I1502J1D01*
G03X199444Y737877I-361J173D01*
G37*
G36*
G01X171182Y637380D02*
X171184Y637457D01*
G02X178186I3501J-90D01*
G01X178188Y637380D01*
G02Y637367I-3503J-7D01*
G02X171182I-3503J0D01*
G02Y637380I3503J6D01*
G37*
G36*
G01X180346Y1325552D02*
Y1331752D01*
G02X180747Y1332154I401J1D01*
G01X186947D01*
G02X187348Y1331752I-1J-402D01*
G01Y1325552D01*
G02X186947Y1325150I-401J-1D01*
G01X180747D01*
G02X180346Y1325552I1J402D01*
G37*
G36*
G01X155972Y1325527D02*
Y1331727D01*
G02X156374Y1332128I402J-1D01*
G01X162574D01*
G02X162976Y1331727I1J-401D01*
G01Y1325527D01*
G02X162574Y1325126I-402J1D01*
G01X156374D01*
G02X155972Y1325527I-1J401D01*
G37*
G36*
G01X204746Y1325552D02*
Y1331752D01*
G02X205147Y1332154I401J1D01*
G01X211347D01*
G02X211748Y1331752I-1J-402D01*
G01Y1325552D01*
G02X211347Y1325150I-401J-1D01*
G01X205147D01*
G02X204746Y1325552I1J402D01*
G37*
G36*
G01X191784Y1383020D02*
X191786Y1383022D01*
X211786D01*
X211792Y1383016D01*
Y1363044D01*
X210547Y1361799D01*
X192755D01*
X191784Y1362770D01*
Y1383020D01*
G37*
G36*
G01X153641D02*
X153643Y1383022D01*
X173643D01*
X173649Y1383016D01*
Y1363044D01*
X172404Y1361799D01*
X154612D01*
X153641Y1362770D01*
Y1383020D01*
G37*
G36*
G01X219077Y1400656D02*
G02X218249Y1401999I675J1343D01*
G02X221255I1503J0D01*
G02X220427Y1400656I-1503J0D01*
G03X220426Y1399941I179J-358D01*
G02X221254Y1398599I-674J-1342D01*
G02X218250I-1502J0D01*
G02X219078Y1399941I1502J0D01*
G03X219077Y1400656I-180J357D01*
G37*
G36*
G01X225000Y591153D02*
X225770Y591923D01*
X241000D01*
X241631Y591292D01*
Y573102D01*
X240710Y572181D01*
X225840D01*
X225000Y573021D01*
Y591153D01*
G37*
G36*
G01Y625153D02*
X225770Y625923D01*
X241000D01*
X241631Y625292D01*
Y607102D01*
X240710Y606181D01*
X225840D01*
X225000Y607021D01*
Y625153D01*
G37*
G36*
G01X225001Y659153D02*
X225770Y659922D01*
X241000D01*
X241630Y659292D01*
Y641102D01*
X240710Y640182D01*
X225840D01*
X225001Y641021D01*
Y659153D01*
G37*
G36*
G01X216502Y692964D02*
X217780Y694242D01*
X235160D01*
X236520Y692882D01*
Y679142D01*
X234969Y677591D01*
X217751D01*
X216502Y678840D01*
Y692964D01*
G37*
G36*
G01X249040Y29910D02*
X248390D01*
X248250Y30050D01*
Y35590D01*
X248270Y35610D01*
X249050D01*
X249110Y35550D01*
Y29980D01*
X249040Y29910D01*
G37*
G36*
G01X251360Y29890D02*
X250710D01*
X250620Y29980D01*
Y35590D01*
X250640Y35610D01*
X251360D01*
X251460Y35510D01*
Y29990D01*
X251360Y29890D01*
G37*
G36*
G01X253760Y29860D02*
X253040D01*
X252980Y29920D01*
Y35560D01*
X253040Y35620D01*
X253770D01*
X253830Y35560D01*
Y29930D01*
X253760Y29860D01*
G37*
G36*
G01X257791Y29908D02*
X257710Y29989D01*
Y35561D01*
X257751Y35602D01*
X258443D01*
X258554Y35491D01*
Y29999D01*
X258463Y29908D01*
X257791D01*
G37*
G36*
G01X255429D02*
X255348Y29989D01*
Y35561D01*
X255389Y35602D01*
X256081D01*
X256192Y35491D01*
Y29999D01*
X256101Y29908D01*
X255429D01*
G37*
G36*
G01X257791Y41522D02*
X257710Y41603D01*
Y47175D01*
X257751Y47216D01*
X258443D01*
X258554Y47105D01*
Y41613D01*
X258463Y41522D01*
X257791D01*
G37*
G36*
G01X255429D02*
X255348Y41603D01*
Y47175D01*
X255389Y47216D01*
X256081D01*
X256192Y47105D01*
Y41613D01*
X256101Y41522D01*
X255429D01*
G37*
G36*
G01X248342D02*
X248260Y41603D01*
Y47175D01*
X248302Y47216D01*
X248994D01*
X249106Y47105D01*
Y41613D01*
X249014Y41522D01*
X248342D01*
G37*
G36*
G01X250704D02*
X250622Y41603D01*
Y47175D01*
X250664Y47216D01*
X251356D01*
X251468Y47105D01*
Y41613D01*
X251376Y41522D01*
X250704D01*
G37*
G36*
G01X253066D02*
X252984Y41603D01*
Y47175D01*
X253026Y47216D01*
X253718D01*
X253830Y47105D01*
Y41613D01*
X253738Y41522D01*
X253066D01*
G37*
G36*
G01X271788Y580476D02*
Y586676D01*
G02X272189Y587078I401J1D01*
G01X278389D01*
G02X278790Y586676I-1J-402D01*
G01Y580476D01*
G02X278389Y580074I-401J-1D01*
G01X272189D01*
G02X271788Y580476I1J402D01*
G37*
G36*
G01X278389Y611236D02*
G02X278790Y610835I0J-401D01*
G01Y604635D01*
G02X278389Y604234I-401J0D01*
G01X272189D01*
G02X271788Y604635I0J401D01*
G01Y610835D01*
G02X272189Y611236I401J0D01*
G01X278389D01*
G37*
G36*
G01Y635390D02*
G02X278790Y634989I0J-401D01*
G01Y628789D01*
G02X278389Y628388I-401J0D01*
G01X272189D01*
G02X271788Y628789I0J401D01*
G01Y634989D01*
G02X272189Y635390I401J0D01*
G01X278389D01*
G37*
G36*
G01X271788Y659143D02*
G02X272189Y659544I401J0D01*
G01X278389D01*
G02X278790Y659143I0J-401D01*
G01Y652943D01*
G02X278389Y652542I-401J0D01*
G01X272189D01*
G02X271788Y652943I0J401D01*
G01Y659143D01*
G37*
G36*
G01X266750Y697314D02*
Y703514D01*
G02X267152Y703916I402J0D01*
G01X273352D01*
G02X273754Y703514I0J-402D01*
G01Y697314D01*
G02X273352Y696912I-402J0D01*
G01X267152D01*
G02X266750Y697314I0J402D01*
G37*
G36*
G01X433118Y1239685D02*
Y1245885D01*
G02X433519Y1246286I401J0D01*
G01X439719D01*
G02X440120Y1245885I0J-401D01*
G01Y1239685D01*
G02X439719Y1239284I-401J0D01*
G01X433519D01*
G02X433118Y1239685I0J401D01*
G37*
G36*
G01X457518D02*
Y1245885D01*
G02X457919Y1246286I401J0D01*
G01X464119D01*
G02X464520Y1245885I0J-401D01*
G01Y1239685D01*
G02X464119Y1239284I-401J0D01*
G01X457919D01*
G02X457518Y1239685I0J401D01*
G37*
G36*
G01X481918D02*
Y1245885D01*
G02X482319Y1246286I401J0D01*
G01X488519D01*
G02X488920Y1245885I0J-401D01*
G01Y1239685D01*
G02X488519Y1239284I-401J0D01*
G01X482319D01*
G02X481918Y1239685I0J401D01*
G37*
G36*
G01X408796D02*
Y1245885D01*
G02X409197Y1246286I401J0D01*
G01X415397D01*
G02X415798Y1245885I0J-401D01*
G01Y1239685D01*
G02X415397Y1239284I-401J0D01*
G01X409197D01*
G02X408796Y1239685I0J401D01*
G37*
G36*
G01X384396D02*
Y1245885D01*
G02X384797Y1246286I401J0D01*
G01X390997D01*
G02X391398Y1245885I0J-401D01*
G01Y1239685D01*
G02X390997Y1239284I-401J0D01*
G01X384797D01*
G02X384396Y1239685I0J401D01*
G37*
G36*
G01X429612Y1138649D02*
G02X429667Y1138753I199J-39D01*
G02X429954I143J-144D01*
G02X430014Y1138603I-143J-144D01*
G02X429676Y1137748I-1152J-39D01*
G02X428046I-815J815D01*
G02X427709Y1138594I815J815D01*
G02X427768Y1138749I202J12D01*
G02X428055I143J-144D01*
G02X428110Y1138646I-143J-143D01*
G01Y1138559D01*
G03X428330Y1138032I752J5D01*
G03X429392I531J531D01*
G03X429612Y1138525I-531J532D01*
G01Y1138649D01*
G37*
G36*
G01X418512D02*
G02X418567Y1138753I199J-39D01*
G02X418854I143J-144D01*
G02X418914Y1138603I-143J-144D01*
G02X418576Y1137748I-1152J-39D01*
G02X416946I-815J815D01*
G02X416609Y1138594I815J815D01*
G02X416668Y1138749I202J12D01*
G02X416955I143J-144D01*
G02X417010Y1138646I-143J-143D01*
G01Y1138559D01*
G03X417230Y1138032I752J5D01*
G03X418292I531J531D01*
G03X418512Y1138525I-531J532D01*
G01Y1138649D01*
G37*
G36*
G01X466612D02*
G02X466667Y1138753I199J-39D01*
G02X466954I143J-144D01*
G02X467014Y1138603I-143J-144D01*
G02X466676Y1137748I-1152J-39D01*
G02X465046I-815J815D01*
G02X464709Y1138594I815J815D01*
G02X464768Y1138749I202J12D01*
G02X465055I143J-144D01*
G02X465110Y1138646I-143J-143D01*
G01Y1138559D01*
G03X465330Y1138032I752J5D01*
G03X466392I531J531D01*
G03X466612Y1138525I-531J532D01*
G01Y1138649D01*
G37*
G36*
G01X462912D02*
G02X462967Y1138753I199J-39D01*
G02X463254I143J-144D01*
G02X463314Y1138603I-143J-144D01*
G02X462976Y1137748I-1152J-39D01*
G02X461346I-815J815D01*
G02X461009Y1138594I815J815D01*
G02X461068Y1138749I202J12D01*
G02X461355I143J-144D01*
G02X461410Y1138646I-143J-143D01*
G01Y1138559D01*
G03X461630Y1138032I752J5D01*
G03X462692I531J531D01*
G03X462912Y1138525I-531J532D01*
G01Y1138649D01*
G37*
G36*
G01X459212D02*
G02X459267Y1138753I199J-39D01*
G02X459554I143J-144D01*
G02X459614Y1138603I-143J-144D01*
G02X459276Y1137748I-1152J-39D01*
G02X457646I-815J815D01*
G02X457309Y1138594I815J815D01*
G02X457368Y1138749I202J12D01*
G02X457655I143J-144D01*
G02X457710Y1138646I-143J-143D01*
G01Y1138559D01*
G03X457930Y1138032I752J5D01*
G03X458992I531J531D01*
G03X459212Y1138525I-531J532D01*
G01Y1138649D01*
G37*
G36*
G01X455512D02*
G02X455567Y1138753I199J-39D01*
G02X455854I143J-144D01*
G02X455914Y1138603I-143J-144D01*
G02X455576Y1137748I-1152J-39D01*
G02X453946I-815J815D01*
G02X453609Y1138594I815J815D01*
G02X453668Y1138749I202J12D01*
G02X453955I143J-144D01*
G02X454010Y1138646I-143J-143D01*
G01Y1138559D01*
G03X454230Y1138032I752J5D01*
G03X455292I531J531D01*
G03X455512Y1138525I-531J532D01*
G01Y1138649D01*
G37*
G36*
G01X442562Y1135445D02*
G02X442618Y1135548I199J-41D01*
G02X442904I143J-143D01*
G02X442964Y1135399I-142J-144D01*
G02X442627Y1134544I-1152J-40D01*
G02X440997I-815J815D01*
G02X440659Y1135389I814J816D01*
G02X440718Y1135544I202J12D01*
G02X441005I143J-143D01*
G02X441060Y1135442I-143J-143D01*
G01Y1135360D01*
X441059Y1135359D01*
X441060Y1135358D01*
Y1135354D01*
G03X441281Y1134828I752J6D01*
G03X442343I531J531D01*
G03X442564Y1135361I-531J532D01*
G02X442562Y1135364I161J109D01*
G01Y1135445D01*
G37*
G36*
G01X438862D02*
G02X438918Y1135548I199J-41D01*
G02X439204I143J-143D01*
G02X439264Y1135399I-142J-144D01*
G02X438927Y1134544I-1152J-40D01*
G02X437297I-815J815D01*
G02X436959Y1135389I814J816D01*
G02X437018Y1135544I202J12D01*
G02X437305I143J-143D01*
G02X437360Y1135442I-143J-143D01*
G01Y1135360D01*
X437359Y1135359D01*
X437360Y1135358D01*
Y1135354D01*
G03X437581Y1134828I752J6D01*
G03X438643I531J531D01*
G03X438864Y1135361I-531J532D01*
G02X438862Y1135364I161J109D01*
G01Y1135445D01*
G37*
G36*
G01X431462D02*
G02X431517Y1135548I199J-40D01*
G02X431804I143J-143D01*
G02X431864Y1135399I-143J-144D01*
G02X431526Y1134544I-1152J-39D01*
G02X429896I-815J815D01*
G02X429559Y1135389I815J815D01*
G02X429618Y1135544I202J12D01*
G02X429905I143J-143D01*
G02X429960Y1135442I-143J-143D01*
G01Y1135360D01*
X429959Y1135359D01*
X429960Y1135358D01*
Y1135354D01*
G03X430180Y1134828I752J5D01*
G03X431242I531J531D01*
G03X431463Y1135361I-531J532D01*
G02X431462Y1135364I191J65D01*
G01Y1135445D01*
G37*
G36*
G01X453662D02*
G02X453718Y1135548I199J-41D01*
G02X454004I143J-143D01*
G02X454064Y1135399I-142J-144D01*
G02X453727Y1134544I-1152J-40D01*
G02X452097I-815J815D01*
G02X451759Y1135389I814J816D01*
G02X451818Y1135544I202J12D01*
G02X452105I143J-143D01*
G02X452160Y1135442I-143J-143D01*
G01Y1135360D01*
X452159Y1135359D01*
X452160Y1135358D01*
Y1135354D01*
G03X452381Y1134828I752J6D01*
G03X453443I531J531D01*
G03X453664Y1135361I-531J532D01*
G02X453662Y1135364I161J109D01*
G01Y1135445D01*
G37*
G36*
G01X463084Y1172162D02*
X464436Y1170810D01*
Y1152420D01*
X463164Y1151148D01*
X454134D01*
X452838Y1152445D01*
Y1170425D01*
X454574Y1172162D01*
X463084D01*
G37*
G36*
G01X438084D02*
X439466Y1170780D01*
Y1152450D01*
X438164Y1151148D01*
X429134D01*
X427838Y1152445D01*
Y1170425D01*
X429574Y1172162D01*
X438084D01*
G37*
G36*
G01X414460Y1170505D02*
Y1152390D01*
X413314Y1151244D01*
X407149D01*
X405882Y1152510D01*
Y1170380D01*
X407149Y1171646D01*
X413319D01*
X414460Y1170505D01*
G37*
G36*
G01X433023Y945187D02*
G03X433018Y945463I-147J135D01*
G02X432627Y946414I961J951D01*
G02X435331I1352J0D01*
G02X434941Y945464I-1352J0D01*
G03X434936Y945187I142J-141D01*
G02X435281Y944305I-955J-882D01*
G02X432679I-1301J0D01*
G02X433023Y945187I1301J1D01*
G37*
G36*
G01X445973Y948391D02*
G03X445968Y948667I-147J135D01*
G02X448280Y949619I960J952D01*
G02X447890Y948669I-1352J0D01*
G03X447886Y948393I143J-140D01*
G02X448231Y947510I-956J-882D01*
G02X445629I-1301J0D01*
G02X445973Y948391I1300J0D01*
G37*
G36*
G01X433023Y951596D02*
G03X433018Y951872I-147J135D01*
G02X432627Y952823I961J951D01*
G02X435331I1352J0D01*
G02X434941Y951873I-1352J0D01*
G03X434936Y951596I142J-141D01*
G02X435281Y950714I-955J-882D01*
G02X432679I-1301J0D01*
G02X433023Y951596I1301J1D01*
G37*
G36*
G01X445973Y954799D02*
G03X445968Y955075I-147J135D01*
G02X448280Y956027I960J952D01*
G02X447890Y955077I-1352J0D01*
G03X447886Y954801I143J-140D01*
G02X448231Y953918I-956J-882D01*
G02X445629I-1301J0D01*
G02X445973Y954799I1300J0D01*
G37*
G36*
G01X465355Y955617D02*
G03X464791I-282J-284D01*
G02X463874Y955239I-917J923D01*
G02Y957841I0J1301D01*
G02X464791Y957463I0J-1301D01*
G03X465355I282J284D01*
G02X466272Y957841I917J-923D01*
G02Y955239I0J-1301D01*
G02X465355Y955617I0J1301D01*
G37*
G36*
G01X433023Y958005D02*
G03X433018Y958281I-147J135D01*
G02X432627Y959232I961J951D01*
G02X435331I1352J0D01*
G02X434941Y958282I-1352J0D01*
G03X434936Y958005I142J-141D01*
G02X435281Y957123I-955J-882D01*
G02X432679I-1301J0D01*
G02X433023Y958005I1301J1D01*
G37*
G36*
G01X445973Y961208D02*
G03X445968Y961484I-147J135D01*
G02X448280Y962436I960J952D01*
G02X447890Y961486I-1352J0D01*
G03X447886Y961210I143J-140D01*
G02X448231Y960327I-956J-882D01*
G02X445629I-1301J0D01*
G02X445973Y961208I1300J0D01*
G37*
G36*
G01X433023Y964413D02*
G03X433018Y964689I-147J135D01*
G02X432627Y965640I961J951D01*
G02X435331I1352J0D01*
G02X434941Y964690I-1352J0D01*
G03X434936Y964413I142J-141D01*
G02X435281Y963531I-955J-882D01*
G02X432679I-1301J0D01*
G02X433023Y964413I1301J1D01*
G37*
G36*
G01X445973Y967617D02*
G03X445968Y967893I-147J135D01*
G02X448280Y968845I960J952D01*
G02X447890Y967895I-1352J0D01*
G03X447886Y967619I143J-140D01*
G02X448231Y966736I-956J-882D01*
G02X445629I-1301J0D01*
G02X445973Y967617I1300J0D01*
G37*
G36*
G01X433023Y970822D02*
G03X433018Y971098I-147J135D01*
G02X432627Y972049I961J951D01*
G02X435331I1352J0D01*
G02X434941Y971099I-1352J0D01*
G03X434936Y970822I142J-141D01*
G02X435281Y969940I-955J-882D01*
G02X432679I-1301J0D01*
G02X433023Y970822I1301J1D01*
G37*
G36*
G01X445973Y974025D02*
G03X445968Y974301I-147J135D01*
G02X448280Y975253I960J952D01*
G02X447890Y974303I-1352J0D01*
G03X447886Y974027I143J-140D01*
G02X448231Y973144I-956J-882D01*
G02X445629I-1301J0D01*
G02X445973Y974025I1300J0D01*
G37*
G36*
G01X433023Y977230D02*
G03X433018Y977506I-147J135D01*
G02X432627Y978457I961J951D01*
G02X435331I1352J0D01*
G02X434941Y977507I-1352J0D01*
G03X434936Y977230I142J-141D01*
G02X435281Y976348I-955J-882D01*
G02X432679I-1301J0D01*
G02X433023Y977230I1301J1D01*
G37*
G36*
G01X445973Y980434D02*
G03X445968Y980710I-147J135D01*
G02X448280Y981662I960J952D01*
G02X447890Y980712I-1352J0D01*
G03X447886Y980436I143J-140D01*
G02X448231Y979553I-956J-882D01*
G02X445629I-1301J0D01*
G02X445973Y980434I1300J0D01*
G37*
G36*
G01X433023Y983639D02*
G03X433018Y983915I-147J135D01*
G02X432627Y984866I961J951D01*
G02X435331I1352J0D01*
G02X434941Y983916I-1352J0D01*
G03X434936Y983639I142J-141D01*
G02X435281Y982757I-955J-882D01*
G02X432679I-1301J0D01*
G02X433023Y983639I1301J1D01*
G37*
G36*
G01X416661Y984654D02*
G03X416099I-281J-284D01*
G02X415185Y984279I-914J926D01*
G02Y986881I0J1301D01*
G02X416099Y986506I0J-1301D01*
G03X416661I281J284D01*
G02X417575Y986881I914J-926D01*
G02Y984279I0J-1301D01*
G02X416661Y984654I0J1301D01*
G37*
G36*
G01X465355Y984657D02*
G03X464791I-282J-284D01*
G02X463874Y984279I-917J923D01*
G02Y986881I0J1301D01*
G02X464791Y986503I0J-1301D01*
G03X465355I282J284D01*
G02X466272Y986881I917J-923D01*
G02Y984279I0J-1301D01*
G02X465355Y984657I0J1301D01*
G37*
G36*
G01X446401Y998526D02*
G03X446406Y998803I-142J141D01*
G02X446061Y999685I955J882D01*
G02X448663I1301J0D01*
G02X448317Y998802I-1300J0D01*
G03X448322Y998525I147J-136D01*
G02X448713Y997574I-961J-951D01*
G02X446401Y998526I-1352J0D01*
G37*
G36*
G01X416661Y999134D02*
G03X416099I-281J-284D01*
G02X415185Y998759I-914J926D01*
G02Y1001361I0J1301D01*
G02X416099Y1000986I0J-1301D01*
G03X416661I281J284D01*
G02X417575Y1001361I914J-926D01*
G02Y998759I0J-1301D01*
G02X416661Y999134I0J1301D01*
G37*
G36*
G01X465355Y999137D02*
G03X464791I-282J-284D01*
G02X463874Y998759I-917J923D01*
G02Y1001361I0J1301D01*
G02X464791Y1000983I0J-1301D01*
G03X465355I282J284D01*
G02X466272Y1001361I917J-923D01*
G02Y998759I0J-1301D01*
G02X465355Y999137I0J1301D01*
G37*
G36*
G01X433452Y1001730D02*
G03X433456Y1002006I-143J140D01*
G02X433111Y1002889I956J882D01*
G02X435713I1301J0D01*
G02X435368Y1002006I-1301J-1D01*
G03X435372Y1001730I147J-136D01*
G02X433452I-960J-952D01*
G37*
G36*
G01X446401Y1004935D02*
G03X446406Y1005212I-142J141D01*
G02X446061Y1006094I955J882D01*
G02X448663I1301J0D01*
G02X448317Y1005211I-1300J0D01*
G03X448322Y1004934I147J-136D01*
G02X448713Y1003983I-961J-951D01*
G02X446401Y1004935I-1352J0D01*
G37*
G36*
G01X433451Y1008138D02*
G03X433456Y1008415I-142J141D01*
G02X433110Y1009298I954J883D01*
G02X435712I1301J0D01*
G02X435367Y1008416I-1300J0D01*
G03X435372Y1008139I147J-136D01*
G02X433060Y1007187I-960J-952D01*
G02X433451Y1008138I1352J0D01*
G37*
G36*
G01X446401Y1011343D02*
G03X446406Y1011620I-142J141D01*
G02X446061Y1012502I955J882D01*
G02X448663I1301J0D01*
G02X448317Y1011619I-1300J0D01*
G03X448322Y1011342I147J-136D01*
G02X448713Y1010391I-961J-951D01*
G02X446401Y1011343I-1352J0D01*
G37*
G36*
G01X433452Y1014547D02*
G03X433456Y1014823I-143J140D01*
G02X433111Y1015706I956J882D01*
G02X435713I1301J0D01*
G02X435368Y1014823I-1301J-1D01*
G03X435372Y1014547I147J-136D01*
G02X433452I-960J-952D01*
G37*
G36*
G01X446401Y1017752D02*
G03X446406Y1018029I-142J141D01*
G02X446061Y1018911I955J882D01*
G02X448663I1301J0D01*
G02X448317Y1018028I-1300J0D01*
G03X448322Y1017751I147J-136D01*
G02X448713Y1016800I-961J-951D01*
G02X446401Y1017752I-1352J0D01*
G37*
G36*
G01X433451Y1020955D02*
G03X433456Y1021232I-142J141D01*
G02X433110Y1022115I954J883D01*
G02X435712I1301J0D01*
G02X435367Y1021233I-1300J0D01*
G03X435372Y1020956I147J-136D01*
G02X433060Y1020004I-960J-952D01*
G02X433451Y1020955I1352J0D01*
G37*
G36*
G01X446401Y1024160D02*
G03X446406Y1024437I-142J141D01*
G02X446061Y1025319I955J882D01*
G02X448663I1301J0D01*
G02X448317Y1024436I-1300J0D01*
G03X448322Y1024159I147J-136D01*
G02X448713Y1023208I-961J-951D01*
G02X446401Y1024160I-1352J0D01*
G37*
G36*
G01X433451Y1027364D02*
G03X433456Y1027641I-142J141D01*
G02X433110Y1028524I954J883D01*
G02X435712I1301J0D01*
G02X435367Y1027642I-1300J0D01*
G03X435372Y1027365I147J-136D01*
G02X433060Y1026413I-960J-952D01*
G02X433451Y1027364I1352J0D01*
G37*
G36*
G01X446401Y1030569D02*
G03X446406Y1030846I-142J141D01*
G02X446061Y1031728I955J882D01*
G02X448663I1301J0D01*
G02X448317Y1030845I-1300J0D01*
G03X448322Y1030568I147J-136D01*
G02X448713Y1029617I-961J-951D01*
G02X446401Y1030569I-1352J0D01*
G37*
G36*
G01X433452Y1033773D02*
G03X433456Y1034049I-143J140D01*
G02X433111Y1034932I956J882D01*
G02X435713I1301J0D01*
G02X435368Y1034049I-1301J-1D01*
G03X435372Y1033773I147J-136D01*
G02X433452I-960J-952D01*
G37*
G36*
G01X446400Y1036977D02*
G03X446404Y1037253I-143J140D01*
G02X446059Y1038136I956J882D01*
G02X448661I1301J0D01*
G02X448316Y1037254I-1300J0D01*
G03X448321Y1036978I147J-135D01*
G02X446009Y1036026I-960J-952D01*
G02X446400Y1036977I1352J0D01*
G37*
G36*
G01Y1101062D02*
G03X446405Y1101339I-142J141D01*
G02X446060Y1102221I955J882D01*
G02X448662I1301J0D01*
G02X448317Y1101339I-1300J0D01*
G03X448322Y1101062I147J-136D01*
G02X448713Y1100111I-961J-951D01*
G02X446009I-1352J0D01*
G02X446400Y1101062I1352J0D01*
G37*
G36*
G01X433451Y1104267D02*
G03X433455Y1104543I-143J140D01*
G02X433110Y1105426I956J882D01*
G02X435712I1301J0D01*
G02X435367Y1104544I-1300J0D01*
G03X435372Y1104268I147J-135D01*
G02X433060Y1103316I-960J-952D01*
G02X433451Y1104267I1352J0D01*
G37*
G36*
G01X446400Y1107471D02*
G03X446405Y1107748I-142J141D01*
G02X446060Y1108630I955J882D01*
G02X448662I1301J0D01*
G02X448317Y1107748I-1300J0D01*
G03X448322Y1107471I147J-136D01*
G02X448713Y1106520I-961J-951D01*
G02X446009I-1352J0D01*
G02X446400Y1107471I1352J0D01*
G37*
G36*
G01X433451Y1110675D02*
G03X433455Y1110951I-143J140D01*
G02X433110Y1111834I956J882D01*
G02X435712I1301J0D01*
G02X435367Y1110952I-1300J0D01*
G03X435372Y1110676I147J-135D01*
G02X433060Y1109724I-960J-952D01*
G02X433451Y1110675I1352J0D01*
G37*
G36*
G01X446400Y1113880D02*
G03X446405Y1114157I-142J141D01*
G02X446060Y1115039I955J882D01*
G02X448662I1301J0D01*
G02X448317Y1114157I-1300J0D01*
G03X448322Y1113880I147J-136D01*
G02X448713Y1112929I-961J-951D01*
G02X446009I-1352J0D01*
G02X446400Y1113880I1352J0D01*
G37*
G36*
G01X457501Y1113881D02*
G03X457506Y1114157I-142J141D01*
G02X457161Y1115039I955J882D01*
G02X459763I1301J0D01*
G02X459418Y1114156I-1301J-1D01*
G03X459422Y1113880I147J-136D01*
G02X459813Y1112929I-961J-951D01*
G02X457501Y1113881I-1352J0D01*
G37*
G36*
G01X433451Y1117084D02*
G03X433455Y1117360I-143J140D01*
G02X433110Y1118243I956J882D01*
G02X435712I1301J0D01*
G02X435367Y1117361I-1300J0D01*
G03X435372Y1117085I147J-135D01*
G02X433060Y1116133I-960J-952D01*
G02X433451Y1117084I1352J0D01*
G37*
G36*
G01X446400Y1120288D02*
G03X446405Y1120565I-142J141D01*
G02X446060Y1121447I955J882D01*
G02X448662I1301J0D01*
G02X448317Y1120565I-1300J0D01*
G03X448322Y1120288I147J-136D01*
G02X448713Y1119337I-961J-951D01*
G02X446009I-1352J0D01*
G02X446400Y1120288I1352J0D01*
G37*
G36*
G01X457501Y1120289D02*
G03X457506Y1120565I-142J141D01*
G02X457161Y1121447I955J882D01*
G02X459763I1301J0D01*
G02X459418Y1120564I-1301J-1D01*
G03X459422Y1120288I147J-136D01*
G02X459813Y1119337I-961J-951D01*
G02X457501Y1120289I-1352J0D01*
G37*
G36*
G01X422351Y1123492D02*
G03X422355Y1123768I-143J140D01*
G02X422010Y1124651I956J882D01*
G02X424612I1301J0D01*
G02X424267Y1123769I-1300J0D01*
G03X424272Y1123493I147J-135D01*
G02X421960Y1122541I-960J-952D01*
G02X422351Y1123492I1352J0D01*
G37*
G36*
G01X433451D02*
G03X433455Y1123768I-143J140D01*
G02X433110Y1124651I956J882D01*
G02X435712I1301J0D01*
G02X435367Y1123769I-1300J0D01*
G03X435372Y1123493I147J-135D01*
G02X433060Y1122541I-960J-952D01*
G02X433451Y1123492I1352J0D01*
G37*
G36*
G01X446400Y1126697D02*
G03X446405Y1126974I-142J141D01*
G02X446060Y1127856I955J882D01*
G02X448662I1301J0D01*
G02X448317Y1126974I-1300J0D01*
G03X448322Y1126697I147J-136D01*
G02X448713Y1125746I-961J-951D01*
G02X446009I-1352J0D01*
G02X446400Y1126697I1352J0D01*
G37*
G36*
G01X457501Y1126698D02*
G03X457506Y1126974I-142J141D01*
G02X457161Y1127856I955J882D01*
G02X459763I1301J0D01*
G02X459418Y1126973I-1301J-1D01*
G03X459422Y1126697I147J-136D01*
G02X459813Y1125746I-961J-951D01*
G02X457501Y1126698I-1352J0D01*
G37*
G36*
G01X422351Y1129901D02*
G03X422355Y1130177I-143J140D01*
G02X422010Y1131060I956J882D01*
G02X424612I1301J0D01*
G02X424267Y1130178I-1300J0D01*
G03X424272Y1129902I147J-135D01*
G02X421960Y1128950I-960J-952D01*
G02X422351Y1129901I1352J0D01*
G37*
G36*
G01X433451D02*
G03X433455Y1130177I-143J140D01*
G02X433110Y1131060I956J882D01*
G02X435712I1301J0D01*
G02X435367Y1130178I-1300J0D01*
G03X435372Y1129902I147J-135D01*
G02X433060Y1128950I-960J-952D01*
G02X433451Y1129901I1352J0D01*
G37*
G36*
G01X457501Y1133106D02*
G03X457506Y1133382I-142J141D01*
G02X457161Y1134264I955J882D01*
G02X459763I1301J0D01*
G02X459418Y1133381I-1301J-1D01*
G03X459422Y1133105I147J-136D01*
G02X459813Y1132154I-961J-951D01*
G02X457501Y1133106I-1352J0D01*
G37*
G36*
G01X446262Y1135445D02*
G02X446317Y1135548I199J-40D01*
G02X446604I143J-143D01*
G02X446622Y1135527I-144J-142D01*
G03X446858Y1135464I159J121D01*
G02X447361Y1135565I503J-1200D01*
G02X447866Y1135463I0J-1301D01*
G03X448102Y1135525I78J184D01*
G02X448118Y1135544I163J-121D01*
G02X448405I143J-143D01*
G02X448460Y1135442I-143J-143D01*
G01Y1135360D01*
X448459Y1135359D01*
X448460Y1135358D01*
Y1135354D01*
G03X448681Y1134828I752J6D01*
G03X449743I531J531D01*
G03X449964Y1135361I-531J532D01*
G02X449962Y1135364I161J109D01*
G01Y1135445D01*
G02X450018Y1135548I199J-41D01*
G02X450304I143J-143D01*
G02X450364Y1135399I-142J-144D01*
G02X450027Y1134544I-1152J-40D01*
G02X449057Y1134217I-815J815D01*
G03X448617Y1133925I-54J-396D01*
G02X448317Y1133382I-1256J339D01*
G03X448322Y1133105I147J-136D01*
G02X448713Y1132154I-961J-951D01*
G02X446009I-1352J0D01*
G02X446400Y1133105I1352J0D01*
G03X446405Y1133382I-142J141D01*
G02X446105Y1133925I956J882D01*
G03X445665Y1134217I-386J-104D01*
G02X444696Y1134544I-154J1142D01*
G02X444359Y1135389I815J815D01*
G02X444418Y1135544I202J12D01*
G02X444705I143J-143D01*
G02X444760Y1135442I-143J-143D01*
G01Y1135360D01*
X444759Y1135359D01*
X444760Y1135358D01*
Y1135354D01*
G03X444980Y1134828I752J5D01*
G03X446042I531J531D01*
G03X446263Y1135361I-531J532D01*
G02X446262Y1135364I191J65D01*
G01Y1135445D01*
G37*
G36*
G01X425912Y1138649D02*
G02X425967Y1138753I199J-39D01*
G02X426254I143J-144D01*
G02X426314Y1138603I-143J-144D01*
G02X425976Y1137748I-1152J-39D01*
G02X425007Y1137421I-815J815D01*
G03X424568Y1137129I-53J-396D01*
G02X424268Y1136587I-1256J341D01*
G03X424273Y1136310I147J-136D01*
G02X424664Y1135359I-961J-951D01*
G02X421960I-1352J0D01*
G02X422351Y1136310I1352J0D01*
G03X422356Y1136587I-142J141D01*
G02X422056Y1137129I956J883D01*
G03X421616Y1137421I-386J-104D01*
G02X420646Y1137748I-155J1142D01*
G02X420309Y1138594I815J815D01*
G02X420368Y1138749I202J12D01*
G02X420655I143J-144D01*
G02X420710Y1138646I-143J-143D01*
G01Y1138559D01*
G03X420930Y1138032I752J5D01*
G03X421992I531J531D01*
G03X422212Y1138525I-531J532D01*
G01Y1138649D01*
G02X422267Y1138753I199J-39D01*
G02X422554I143J-144D01*
G02X422572Y1138732I-145J-142D01*
G03X422809Y1138669I159J121D01*
G02X423312Y1138770I503J-1200D01*
G02X423816Y1138668I-1J-1301D01*
G03X424052Y1138730I78J185D01*
G02X424068Y1138749I162J-121D01*
G02X424355I143J-144D01*
G02X424410Y1138646I-143J-143D01*
G01Y1138559D01*
G03X424630Y1138032I752J5D01*
G03X425692I531J531D01*
G03X425912Y1138525I-531J532D01*
G01Y1138649D01*
G37*
G36*
G01X433510Y1136630D02*
Y1136828D01*
X433457Y1136885D01*
G02X433111Y1137769I956J884D01*
G02X435713I1301J0D01*
G02X435367Y1136885I-1302J0D01*
G01X435314Y1136828D01*
Y1136630D01*
X435362Y1136574D01*
G02X435664Y1135759I-949J-815D01*
G01Y1135359D01*
G02X433160I-1252J0D01*
G01Y1135759D01*
G02X433462Y1136574I1251J0D01*
G01X433510Y1136630D01*
G37*
G36*
G01X372035Y1302030D02*
Y1304984D01*
X391727D01*
Y1302030D01*
X391547D01*
Y1292380D01*
X391549Y1292378D01*
Y1288278D01*
X390839Y1287568D01*
X372829D01*
X372195Y1288202D01*
Y1302030D01*
X372035D01*
G37*
G36*
G01X404163D02*
Y1304984D01*
X423855D01*
Y1302030D01*
X423675D01*
Y1291559D01*
X423629Y1291513D01*
Y1288598D01*
X423019Y1287988D01*
X404669D01*
X404323Y1288334D01*
Y1302030D01*
X404163D01*
G37*
G36*
G01X436291D02*
Y1304984D01*
X455983D01*
Y1302030D01*
X455803D01*
Y1292216D01*
X455799Y1292212D01*
Y1288218D01*
X455529Y1287948D01*
X437019D01*
X436451Y1288516D01*
Y1302030D01*
X436291D01*
G37*
G36*
G01X468419D02*
Y1304984D01*
X488111D01*
Y1302030D01*
X487931D01*
Y1292356D01*
X487939Y1292348D01*
Y1289098D01*
X486659Y1287818D01*
X469119D01*
X468579Y1288358D01*
Y1302030D01*
X468419D01*
G37*
G36*
G01X339907Y1315456D02*
Y1318410D01*
X359599D01*
Y1315456D01*
X359419D01*
Y1301258D01*
X359039Y1300878D01*
X340609D01*
X340067Y1301420D01*
Y1315456D01*
X339907D01*
G37*
G36*
G01X500547D02*
Y1318410D01*
X520239D01*
Y1315456D01*
X520059D01*
Y1302138D01*
X519179Y1301258D01*
X501619D01*
X500707Y1302170D01*
Y1315456D01*
X500547D01*
G37*
G36*
G01X307779Y1338254D02*
Y1341208D01*
X327471D01*
Y1338254D01*
X327291D01*
Y1328446D01*
X327299Y1328438D01*
Y1324568D01*
X326689Y1323958D01*
X308349D01*
X307939Y1324368D01*
Y1338254D01*
X307779D01*
G37*
G36*
G01X532675D02*
Y1341208D01*
X552367D01*
Y1338254D01*
X552187D01*
Y1335770D01*
X552387Y1335570D01*
Y1328370D01*
X552399Y1328358D01*
Y1324328D01*
X551799Y1323728D01*
X533279D01*
X532835Y1324172D01*
Y1338254D01*
X532675D01*
G37*
G36*
G01X469298Y1356962D02*
G02X469700Y1357364I402J0D01*
G01X475700D01*
G02X476102Y1356962I0J-402D01*
G01Y1350962D01*
G02X475700Y1350560I-402J0D01*
G01X469700D01*
G02X469298Y1350962I0J402D01*
G01Y1356962D01*
G37*
G36*
G01X482543Y1350460D02*
G02Y1357464I0J3502D01*
G02X485376Y1356020I0J-3501D01*
G03X485699Y1355855I324J235D01*
G02X486037Y1354446I-2764J-1408D01*
G02X486032Y1354275I-3102J5D01*
G02X486046Y1353962I-3489J-313D01*
G02X485396Y1351929I-3504J0D01*
G03X485376Y1351904I302J-262D01*
G02X482543Y1350460I-2833J2057D01*
G37*
G36*
G01X379822Y1357446D02*
G02X380224Y1357848I402J0D01*
G01X386224D01*
G02X386626Y1357446I0J-402D01*
G01Y1351446D01*
G02X386224Y1351044I-402J0D01*
G01X380224D01*
G02X379822Y1351446I0J402D01*
G01Y1357446D01*
G37*
G36*
G01X409588D02*
G02X409990Y1357848I402J0D01*
G01X415990D01*
G02X416392Y1357446I0J-402D01*
G01Y1351446D01*
G02X415990Y1351044I-402J0D01*
G01X409990D01*
G02X409588Y1351446I0J402D01*
G01Y1357446D01*
G37*
G36*
G01X439924D02*
G02X440326Y1357848I402J0D01*
G01X446326D01*
G02X446728Y1357446I0J-402D01*
G01Y1351446D01*
G02X446326Y1351044I-402J0D01*
G01X440326D01*
G02X439924Y1351446I0J402D01*
G01Y1357446D01*
G37*
G36*
G01X455198Y1382662D02*
G02X455600Y1383064I402J0D01*
G01X461600D01*
G02X462002Y1382662I0J-402D01*
G01Y1376662D01*
G02X461600Y1376260I-402J0D01*
G01X455600D01*
G02X455198Y1376662I0J402D01*
G01Y1382662D01*
G37*
G36*
G01X465700Y1381839D02*
Y1381841D01*
G02X468443Y1383165I2743J-2179D01*
G02Y1376159I0J-3503D01*
G02X465700Y1377483I0J3503D01*
G01Y1377485D01*
G02Y1381839I2743J2177D01*
G37*
G36*
G01X457654Y937658D02*
X472042D01*
X473266Y936434D01*
Y929138D01*
X471131Y927002D01*
X458434D01*
X456940Y928497D01*
Y936487D01*
X457654Y937201D01*
Y937658D01*
G37*
G36*
G01X630870Y1291266D02*
X635770D01*
G02Y1284062I0J-3602D01*
G01X630870D01*
G02Y1291266I0J3602D01*
G37*
G36*
G01X690270D02*
X695170D01*
G02Y1284062I0J-3602D01*
G01X690270D01*
G02Y1291266I0J3602D01*
G37*
G36*
G01X749670D02*
X754570D01*
G02Y1284062I0J-3602D01*
G01X749670D01*
G02Y1291266I0J3602D01*
G37*
G36*
G01X809070D02*
X813970D01*
G02Y1284062I0J-3602D01*
G01X809070D01*
G02Y1291266I0J3602D01*
G37*
G36*
G01X660570D02*
X665470D01*
G02Y1284062I0J-3602D01*
G01X660570D01*
G02Y1291266I0J3602D01*
G37*
G36*
G01X779370D02*
X784270D01*
G02Y1284062I0J-3602D01*
G01X779370D01*
G02Y1291266I0J3602D01*
G37*
G36*
G01X840957Y1272181D02*
G03X840335I-311J-252D01*
G02X839246Y1271662I-1089J883D01*
G02Y1274466I0J1402D01*
G02X840335Y1273947I0J-1402D01*
G03X840957I311J252D01*
G02X842046Y1274466I1089J-883D01*
G02Y1271662I0J-1402D01*
G02X840957Y1272181I0J1402D01*
G37*
G36*
G01X626712Y1272118D02*
G03X626180I-266J-298D01*
G02X625246Y1271762I-934J1047D01*
G02Y1274566I0J1402D01*
G02X626180Y1274210I0J-1403D01*
G03X626712I266J298D01*
G02X627646Y1274566I934J-1047D01*
G02Y1271762I0J-1402D01*
G02X626712Y1272118I0J1403D01*
G37*
G36*
G01X641657Y1272481D02*
G03X641035I-311J-252D01*
G02X639946Y1271962I-1089J883D01*
G02Y1274766I0J1402D01*
G02X641035Y1274247I0J-1402D01*
G03X641657I311J252D01*
G02X642746Y1274766I1089J-883D01*
G02Y1271962I0J-1402D01*
G02X641657Y1272481I0J1402D01*
G37*
G36*
G01X655357D02*
G03X654735I-311J-252D01*
G02X653646Y1271962I-1089J883D01*
G02Y1274766I0J1402D01*
G02X654735Y1274247I0J-1402D01*
G03X655357I311J252D01*
G02X656446Y1274766I1089J-883D01*
G02Y1271962I0J-1402D01*
G02X655357Y1272481I0J1402D01*
G37*
G36*
G01X671357D02*
G03X670735I-311J-252D01*
G02X669646Y1271962I-1089J883D01*
G02Y1274766I0J1402D01*
G02X670735Y1274247I0J-1402D01*
G03X671357I311J252D01*
G02X672446Y1274766I1089J-883D01*
G02Y1271962I0J-1402D01*
G02X671357Y1272481I0J1402D01*
G37*
G36*
G01X685057D02*
G03X684435I-311J-252D01*
G02X683346Y1271962I-1089J883D01*
G02Y1274766I0J1402D01*
G02X684435Y1274247I0J-1402D01*
G03X685057I311J252D01*
G02X686146Y1274766I1089J-883D01*
G02Y1271962I0J-1402D01*
G02X685057Y1272481I0J1402D01*
G37*
G36*
G01X701057D02*
G03X700435I-311J-252D01*
G02X699346Y1271962I-1089J883D01*
G02Y1274766I0J1402D01*
G02X700435Y1274247I0J-1402D01*
G03X701057I311J252D01*
G02X702146Y1274766I1089J-883D01*
G02Y1271962I0J-1402D01*
G02X701057Y1272481I0J1402D01*
G37*
G36*
G01X714757D02*
G03X714135I-311J-252D01*
G02X713046Y1271962I-1089J883D01*
G02Y1274766I0J1402D01*
G02X714135Y1274247I0J-1402D01*
G03X714757I311J252D01*
G02X715846Y1274766I1089J-883D01*
G02Y1271962I0J-1402D01*
G02X714757Y1272481I0J1402D01*
G37*
G36*
G01X744457D02*
G03X743835I-311J-252D01*
G02X742746Y1271962I-1089J883D01*
G02Y1274766I0J1402D01*
G02X743835Y1274247I0J-1402D01*
G03X744457I311J252D01*
G02X745546Y1274766I1089J-883D01*
G02Y1271962I0J-1402D01*
G02X744457Y1272481I0J1402D01*
G37*
G36*
G01X760457D02*
G03X759835I-311J-252D01*
G02X758746Y1271962I-1089J883D01*
G02Y1274766I0J1402D01*
G02X759835Y1274247I0J-1402D01*
G03X760457I311J252D01*
G02X761546Y1274766I1089J-883D01*
G02Y1271962I0J-1402D01*
G02X760457Y1272481I0J1402D01*
G37*
G36*
G01X774157D02*
G03X773535I-311J-252D01*
G02X772446Y1271962I-1089J883D01*
G02Y1274766I0J1402D01*
G02X773535Y1274247I0J-1402D01*
G03X774157I311J252D01*
G02X775246Y1274766I1089J-883D01*
G02Y1271962I0J-1402D01*
G02X774157Y1272481I0J1402D01*
G37*
G36*
G01X790157D02*
G03X789535I-311J-252D01*
G02X788446Y1271962I-1089J883D01*
G02Y1274766I0J1402D01*
G02X789535Y1274247I0J-1402D01*
G03X790157I311J252D01*
G02X791246Y1274766I1089J-883D01*
G02Y1271962I0J-1402D01*
G02X790157Y1272481I0J1402D01*
G37*
G36*
G01X803857D02*
G03X803235I-311J-252D01*
G02X802146Y1271962I-1089J883D01*
G02Y1274766I0J1402D01*
G02X803235Y1274247I0J-1402D01*
G03X803857I311J252D01*
G02X804946Y1274766I1089J-883D01*
G02Y1271962I0J-1402D01*
G02X803857Y1272481I0J1402D01*
G37*
G36*
G01X819857D02*
G03X819235I-311J-252D01*
G02X818146Y1271962I-1089J883D01*
G02Y1274766I0J1402D01*
G02X819235Y1274247I0J-1402D01*
G03X819857I311J252D01*
G02X820946Y1274766I1089J-883D01*
G02Y1271962I0J-1402D01*
G02X819857Y1272481I0J1402D01*
G37*
G36*
G01X833557D02*
G03X832935I-311J-252D01*
G02X831846Y1271962I-1089J883D01*
G02Y1274766I0J1402D01*
G02X832935Y1274247I0J-1402D01*
G03X833557I311J252D01*
G02X834646Y1274766I1089J-883D01*
G02Y1271962I0J-1402D01*
G02X833557Y1272481I0J1402D01*
G37*
G36*
G01X730513Y1272356D02*
G03X729997Y1272334I-245J-316D01*
G02X729046Y1271962I-951J1030D01*
G02Y1274766I0J1402D01*
G02X729905Y1274472I0J-1402D01*
G03X730421Y1274494I245J316D01*
G02X731372Y1274866I951J-1030D01*
G02Y1272062I0J-1402D01*
G02X730513Y1272356I0J1402D01*
G37*
G36*
G01X707077Y1302644D02*
G03X707387Y1303178I-65J395D01*
G02X707293Y1303701I1408J523D01*
G02X710297I1502J0D01*
G02X709038Y1302219I-1502J0D01*
G03X708728Y1301685I65J-395D01*
G02X708822Y1301162I-1408J-523D01*
G02X705818I-1502J0D01*
G02X707077Y1302644I1502J0D01*
G37*
G36*
G01X716369Y1287603D02*
G02X716368Y1287664I3601J90D01*
G02X719970Y1291266I3602J0D01*
G01X724870D01*
G02Y1284062I0J-3602D01*
G01X719970D01*
G02X716882Y1285811I1J3602D01*
G03X716156Y1285722I-343J-205D01*
G02X715394Y1284820I-1436J440D01*
G03X715208Y1284300I180J-358D01*
G02X715338Y1283689I-1371J-611D01*
G02X712334I-1502J0D01*
G02X712410Y1284160I1502J-1D01*
G03X711965Y1284680I-380J125D01*
G02X711720Y1284660I-244J1482D01*
G02Y1287664I0J1502D01*
G02X712905Y1287085I0J-1502D01*
G03X713535I315J246D01*
G02X714720Y1287664I1185J-923D01*
G02X715706Y1287295I0J-1502D01*
G03X716369Y1287603I263J301D01*
G37*
G36*
G01X667260Y1362878D02*
Y1383045D01*
X667262Y1383047D01*
X687262D01*
X687268Y1383041D01*
Y1363152D01*
G02X687209Y1363010I-200J0D01*
G01X686082Y1361883D01*
G02X685940Y1361824I-142J141D01*
G01X668314D01*
G02X668172Y1361883I0J200D01*
G01X667319Y1362736D01*
G02X667260Y1362878I141J142D01*
G37*
G36*
G01X705403D02*
Y1383045D01*
X705405Y1383047D01*
X725405D01*
X725411Y1383041D01*
Y1363152D01*
G02X725352Y1363010I-200J0D01*
G01X724225Y1361883D01*
G02X724083Y1361824I-142J141D01*
G01X706457D01*
G02X706315Y1361883I0J200D01*
G01X705462Y1362736D01*
G02X705403Y1362878I141J142D01*
G37*
G36*
G01X654159Y1355891D02*
X655387Y1357119D01*
G02X655529Y1357178I142J-141D01*
G01X736087D01*
G02X736229Y1357119I0J-200D01*
G01X737789Y1355559D01*
G02X737848Y1355417I-141J-142D01*
G01Y1325585D01*
G02X737789Y1325443I-200J0D01*
G01X736487Y1324141D01*
G02X736345Y1324082I-142J141D01*
G01X724364D01*
X724130Y1323479D01*
X724231Y1323387D01*
G02X725369Y1320803I-2365J-2584D01*
G02X718363I-3503J0D01*
G02X719501Y1323387I3503J0D01*
G01X719602Y1323479D01*
X719368Y1324082D01*
X699964D01*
X699730Y1323479D01*
X699831Y1323387D01*
G02X700969Y1320803I-2365J-2584D01*
G02X693963I-3503J0D01*
G02X695101Y1323387I3503J0D01*
G01X695202Y1323479D01*
X694968Y1324082D01*
X675563D01*
X675331Y1323476D01*
X675433Y1323384D01*
G02X676596Y1320778I-2340J-2607D01*
G02X669590I-3503J0D01*
G02X670753Y1323384I3503J-1D01*
G01X670855Y1323476D01*
X670623Y1324082D01*
X655273D01*
G02X655131Y1324141I0J200D01*
G01X654159Y1325113D01*
G02X654100Y1325255I141J142D01*
G01Y1355749D01*
G02X654159Y1355891I200J0D01*
G37*
G36*
G01X710597Y1435662D02*
G02X709938Y1436905I843J1243D01*
G02X712942I1502J0D01*
G02X712283Y1435662I-1502J0D01*
G02X711732Y1435432I-842J1243D01*
G01X711716Y1435429D01*
G02X711440Y1435403I-278J1476D01*
G02X711164Y1435429I2J1502D01*
G01X711148Y1435432D01*
G02X710597Y1435662I291J1473D01*
G37*
G36*
G01X701024Y84525D02*
G03X701499Y84906I75J393D01*
G02X703000Y86364I1501J-44D01*
G02X703541Y86263I0J-1502D01*
G03X704044Y86459I144J373D01*
G02X705390Y87294I1346J-667D01*
G02Y84290I0J-1502D01*
G02X704849Y84391I0J1502D01*
G03X704346Y84195I-144J-373D01*
G02X703000Y83360I-1346J667D01*
G02X702717Y83387I1J1502D01*
G03X702242Y83006I-75J-393D01*
G02X700741Y81548I-1501J44D01*
G02Y84552I0J1502D01*
G02X701024Y84525I-1J-1502D01*
G37*
G36*
G01X709456Y104794D02*
X709779D01*
X709793Y104795D01*
G02X709998Y104810I212J-1487D01*
G01X712433D01*
G02Y101806I0J-1502D01*
G01X709998D01*
G02X709793Y101821I7J1502D01*
G01X709779Y101822D01*
X709456D01*
Y101902D01*
X709344Y101957D01*
G02X709165Y102058I647J1355D01*
G01X708414D01*
Y104558D01*
X709165D01*
G02X709344Y104659I826J-1254D01*
G01X709456Y104714D01*
Y104794D01*
G37*
G36*
G01X919577Y1534155D02*
X920655Y1535233D01*
X940065D01*
X941513Y1533785D01*
Y1522125D01*
X940345Y1520957D01*
X922045D01*
X919577Y1523425D01*
Y1534155D01*
G37*
G36*
G01X750685Y50696D02*
X750604Y50777D01*
Y56349D01*
X750645Y56390D01*
X751337D01*
X751448Y56279D01*
Y50787D01*
X751357Y50696D01*
X750685D01*
G37*
G36*
G01Y62310D02*
X750604Y62391D01*
Y67963D01*
X750645Y68004D01*
X751337D01*
X751448Y67893D01*
Y62401D01*
X751357Y62310D01*
X750685D01*
G37*
G36*
G01X920136Y309603D02*
G02X937342I8603J12050D01*
G01X920136D01*
G37*
G36*
G01X1093650Y1726368D02*
X1095049Y1727767D01*
X1115443D01*
X1115986Y1727224D01*
Y1712773D01*
X1115027Y1711814D01*
Y1704508D01*
X1113839Y1703320D01*
X1108920D01*
X1104820Y1707420D01*
X1095230D01*
X1093650Y1709000D01*
Y1726368D01*
G37*
G36*
G01X1118330Y1729076D02*
G02X1117698Y1730300I869J1224D01*
G02X1120702I1502J0D01*
G02X1120070Y1729076I-1501J0D01*
G03Y1728424I232J-326D01*
G02X1120702Y1727200I-869J-1224D01*
G02X1120109Y1726004I-1503J0D01*
G03X1120130Y1725352I242J-319D01*
G02X1120802Y1724100I-830J-1252D01*
G02X1117798I-1502J0D01*
G02X1118391Y1725296I1503J0D01*
G03X1118370Y1725948I-242J319D01*
G02X1117698Y1727200I830J1252D01*
G02X1118330Y1728424I1501J0D01*
G03Y1729076I-232J326D01*
G37*
G36*
G01X1221712Y1291266D02*
X1226612D01*
G02Y1284062I0J-3602D01*
G01X1221712D01*
G02Y1291266I0J3602D01*
G37*
G36*
G01X1162312D02*
X1167212D01*
G02Y1284062I0J-3602D01*
G01X1162312D01*
G02Y1291266I0J3602D01*
G37*
G36*
G01X1102912D02*
X1107812D01*
G02Y1284062I0J-3602D01*
G01X1102912D01*
G02Y1291266I0J3602D01*
G37*
G36*
G01X1043512D02*
X1048412D01*
G02Y1284062I0J-3602D01*
G01X1043512D01*
G02Y1291266I0J3602D01*
G37*
G36*
G01X1192012D02*
X1196912D01*
G02Y1284062I0J-3602D01*
G01X1192012D01*
G02Y1291266I0J3602D01*
G37*
G36*
G01X1132612D02*
X1137512D01*
G02Y1284062I0J-3602D01*
G01X1132612D01*
G02Y1291266I0J3602D01*
G37*
G36*
G01X1073212D02*
X1078112D01*
G02Y1284062I0J-3602D01*
G01X1073212D01*
G02Y1291266I0J3602D01*
G37*
G36*
G01X1013812D02*
X1018712D01*
G02Y1284062I0J-3602D01*
G01X1013812D01*
G02Y1291266I0J3602D01*
G37*
G36*
G01X1203609Y1272136D02*
G03X1203039Y1272137I-285J-281D01*
G02X1202043Y1271721I-997J986D01*
G02Y1274525I0J1402D01*
G02X1203042Y1274106I-1J-1402D01*
G03X1203612Y1274105I285J281D01*
G02X1204608Y1274521I997J-986D01*
G02Y1271717I0J-1402D01*
G02X1203609Y1272136I1J1402D01*
G37*
G36*
G01X1024599Y1272461D02*
G03X1023977I-311J-252D01*
G02X1022888Y1271942I-1089J883D01*
G02Y1274746I0J1402D01*
G02X1023977Y1274227I0J-1402D01*
G03X1024599I311J252D01*
G02X1025688Y1274746I1089J-883D01*
G02Y1271942I0J-1402D01*
G02X1024599Y1272461I0J1402D01*
G37*
G36*
G01X1038299D02*
G03X1037677I-311J-252D01*
G02X1036588Y1271942I-1089J883D01*
G02Y1274746I0J1402D01*
G02X1037677Y1274227I0J-1402D01*
G03X1038299I311J252D01*
G02X1039388Y1274746I1089J-883D01*
G02Y1271942I0J-1402D01*
G02X1038299Y1272461I0J1402D01*
G37*
G36*
G01X1054299D02*
G03X1053677I-311J-252D01*
G02X1052588Y1271942I-1089J883D01*
G02Y1274746I0J1402D01*
G02X1053677Y1274227I0J-1402D01*
G03X1054299I311J252D01*
G02X1055388Y1274746I1089J-883D01*
G02Y1271942I0J-1402D01*
G02X1054299Y1272461I0J1402D01*
G37*
G36*
G01X1067999D02*
G03X1067377I-311J-252D01*
G02X1066288Y1271942I-1089J883D01*
G02Y1274746I0J1402D01*
G02X1067377Y1274227I0J-1402D01*
G03X1067999I311J252D01*
G02X1069088Y1274746I1089J-883D01*
G02Y1271942I0J-1402D01*
G02X1067999Y1272461I0J1402D01*
G37*
G36*
G01X1083999D02*
G03X1083377I-311J-252D01*
G02X1082288Y1271942I-1089J883D01*
G02Y1274746I0J1402D01*
G02X1083377Y1274227I0J-1402D01*
G03X1083999I311J252D01*
G02X1085088Y1274746I1089J-883D01*
G02Y1271942I0J-1402D01*
G02X1083999Y1272461I0J1402D01*
G37*
G36*
G01X1097699D02*
G03X1097077I-311J-252D01*
G02X1095988Y1271942I-1089J883D01*
G02Y1274746I0J1402D01*
G02X1097077Y1274227I0J-1402D01*
G03X1097699I311J252D01*
G02X1098788Y1274746I1089J-883D01*
G02Y1271942I0J-1402D01*
G02X1097699Y1272461I0J1402D01*
G37*
G36*
G01X1113699D02*
G03X1113077I-311J-252D01*
G02X1111988Y1271942I-1089J883D01*
G02Y1274746I0J1402D01*
G02X1113077Y1274227I0J-1402D01*
G03X1113699I311J252D01*
G02X1114788Y1274746I1089J-883D01*
G02Y1271942I0J-1402D01*
G02X1113699Y1272461I0J1402D01*
G37*
G36*
G01X1127899D02*
G03X1127277I-311J-252D01*
G02X1126188Y1271942I-1089J883D01*
G02Y1274746I0J1402D01*
G02X1127277Y1274227I0J-1402D01*
G03X1127899I311J252D01*
G02X1128988Y1274746I1089J-883D01*
G02Y1271942I0J-1402D01*
G02X1127899Y1272461I0J1402D01*
G37*
G36*
G01X1231969Y1274165D02*
G03X1231537Y1274462I-387J-100D01*
G02X1231377Y1274453I-159J1393D01*
G02Y1277257I0J1402D01*
G02X1232735Y1276205I0J-1403D01*
G03X1233167Y1275908I387J100D01*
G02X1233327Y1275917I159J-1393D01*
G02Y1273113I0J-1402D01*
G02X1231969Y1274165I0J1403D01*
G37*
G36*
G01X1015278Y1272522D02*
G02X1014111Y1271897I-1167J777D01*
G02Y1274701I0J1402D01*
G02X1015278Y1274076I0J-1402D01*
G03X1015944I333J222D01*
G02X1017111Y1274701I1167J-777D01*
G02Y1271897I0J-1402D01*
G02X1015944Y1272522I0J1402D01*
G03X1015278I-333J-222D01*
G37*
G36*
G01X1006798Y1296980D02*
G02X1006098Y1298250I802J1270D01*
G02X1009102I1502J0D01*
G02X1008410Y1296985I-1502J0D01*
G03X1008412Y1296310I216J-337D01*
G02X1009112Y1295040I-802J-1270D01*
G02X1006108I-1502J0D01*
G02X1006800Y1296305I1502J0D01*
G03X1006798Y1296980I-216J337D01*
G37*
G36*
G01X1097298Y256262D02*
Y262462D01*
G02X1097700Y262864I402J0D01*
G01X1103900D01*
G02X1104302Y262462I0J-402D01*
G01Y256262D01*
G02X1103900Y255860I-402J0D01*
G01X1097700D01*
G02X1097298Y256262I0J402D01*
G37*
G36*
G01X1097198Y280562D02*
Y286762D01*
G02X1097600Y287164I402J0D01*
G01X1103800D01*
G02X1104202Y286762I0J-402D01*
G01Y280562D01*
G02X1103800Y280160I-402J0D01*
G01X1097600D01*
G02X1097198Y280562I0J402D01*
G37*
G36*
G01X1151998Y1361862D02*
Y1368062D01*
G02X1152400Y1368464I402J0D01*
G01X1158600D01*
G02X1159002Y1368062I0J-402D01*
G01Y1361862D01*
G02X1158600Y1361460I-402J0D01*
G01X1152400D01*
G02X1151998Y1361862I0J402D01*
G37*
G36*
G01X1176398D02*
Y1368062D01*
G02X1176800Y1368464I402J0D01*
G01X1183000D01*
G02X1183402Y1368062I0J-402D01*
G01Y1361862D01*
G02X1183000Y1361460I-402J0D01*
G01X1176800D01*
G02X1176398Y1361862I0J402D01*
G37*
G36*
G01X1127598D02*
Y1368062D01*
G02X1128000Y1368464I402J0D01*
G01X1134200D01*
G02X1134602Y1368062I0J-402D01*
G01Y1361862D01*
G02X1134200Y1361460I-402J0D01*
G01X1128000D01*
G02X1127598Y1361862I0J402D01*
G37*
G36*
G01X1126952Y1419349D02*
X1126954Y1419351D01*
X1146954D01*
X1146960Y1419345D01*
Y1399373D01*
X1145715Y1398128D01*
X1127923D01*
X1126952Y1399099D01*
Y1419349D01*
G37*
G36*
G01X1165095D02*
X1165097Y1419351D01*
X1185097D01*
X1185103Y1419345D01*
Y1399373D01*
X1183858Y1398128D01*
X1166066D01*
X1165095Y1399099D01*
Y1419349D01*
G37*
G36*
G01X1289188Y751498D02*
X1267095D01*
X1267072Y751493D01*
G02X1266727Y751453I-344J1462D01*
G02Y754457I0J1502D01*
G02X1267072Y754417I1J-1502D01*
G01X1267095Y754412D01*
X1290022D01*
G02X1291040Y753996I-1J-1457D01*
G01X1294937D01*
G02X1295309Y753948I0J-1465D01*
G01X1295334Y753942D01*
X1295526D01*
G02X1296422Y753052I6J-890D01*
G01Y751998D01*
X1296295D01*
X1296239Y751888D01*
G02X1296186Y751792I-1300J655D01*
G01Y750545D01*
G02X1296638Y749390I-1250J-1155D01*
G01Y746965D01*
G02X1293236I-1701J0D01*
G01Y749390D01*
G02X1293640Y750491I1702J0D01*
G01X1293688Y750547D01*
Y751084D01*
X1291686D01*
Y750956D01*
X1289188D01*
Y751498D01*
G37*
G36*
G01X1409258Y1239685D02*
Y1245885D01*
G02X1409660Y1246286I402J-1D01*
G01X1415860D01*
G02X1416262Y1245885I1J-401D01*
G01Y1239685D01*
G02X1415860Y1239284I-402J1D01*
G01X1409660D01*
G02X1409258Y1239685I-1J401D01*
G37*
G36*
G01X1458058D02*
Y1245885D01*
G02X1458460Y1246286I402J-1D01*
G01X1464660D01*
G02X1465062Y1245885I1J-401D01*
G01Y1239685D01*
G02X1464660Y1239284I-402J1D01*
G01X1458460D01*
G02X1458058Y1239685I-1J401D01*
G37*
G36*
G01X1433658D02*
Y1245885D01*
G02X1434060Y1246286I402J-1D01*
G01X1440260D01*
G02X1440662Y1245885I1J-401D01*
G01Y1239685D01*
G02X1440260Y1239284I-402J1D01*
G01X1434060D01*
G02X1433658Y1239685I-1J401D01*
G37*
G36*
G01X1360536D02*
Y1245885D01*
G02X1360938Y1246286I402J-1D01*
G01X1367138D01*
G02X1367540Y1245885I1J-401D01*
G01Y1239685D01*
G02X1367138Y1239284I-402J1D01*
G01X1360938D01*
G02X1360536Y1239685I-1J401D01*
G37*
G36*
G01X1384936D02*
Y1245885D01*
G02X1385338Y1246286I402J-1D01*
G01X1391538D01*
G02X1391940Y1245885I1J-401D01*
G01Y1239685D01*
G02X1391538Y1239284I-402J1D01*
G01X1385338D01*
G02X1384936Y1239685I-1J401D01*
G37*
G36*
G01X1405754Y1138649D02*
G02X1405809Y1138753I199J-39D01*
G02X1406096I144J-144D01*
G02X1406156Y1138603I-143J-144D01*
G02X1405818Y1137748I-1152J-39D01*
G02X1404188I-815J815D01*
G02X1403851Y1138594I815J815D01*
G02X1403910Y1138749I202J12D01*
G02X1404197I143J-144D01*
G02X1404252Y1138646I-143J-143D01*
G01Y1138559D01*
G03X1404472Y1138032I752J5D01*
G03X1405534I531J531D01*
G03X1405754Y1138525I-531J532D01*
G01Y1138649D01*
G37*
G36*
G01X1394654D02*
G02X1394709Y1138753I199J-39D01*
G02X1394996I143J-144D01*
G02X1395056Y1138603I-143J-144D01*
G02X1394718Y1137748I-1152J-39D01*
G02X1393088I-815J815D01*
G02X1392751Y1138594I815J815D01*
G02X1392810Y1138749I202J12D01*
G02X1393097I143J-144D01*
G02X1393152Y1138646I-143J-143D01*
G01Y1138559D01*
G03X1393372Y1138032I752J5D01*
G03X1394434I531J531D01*
G03X1394654Y1138525I-531J532D01*
G01Y1138649D01*
G37*
G36*
G01X1442754D02*
G02X1442809Y1138753I199J-39D01*
G02X1443096I143J-144D01*
G02X1443156Y1138603I-143J-144D01*
G02X1442818Y1137748I-1152J-39D01*
G02X1441188I-815J815D01*
G02X1440851Y1138594I815J815D01*
G02X1440910Y1138749I202J12D01*
G02X1441197I143J-144D01*
G02X1441252Y1138646I-143J-143D01*
G01Y1138559D01*
G03X1441472Y1138032I752J5D01*
G03X1442534I531J531D01*
G03X1442754Y1138525I-531J532D01*
G01Y1138649D01*
G37*
G36*
G01X1439054D02*
G02X1439109Y1138753I199J-39D01*
G02X1439396I143J-144D01*
G02X1439456Y1138603I-143J-144D01*
G02X1439118Y1137748I-1152J-39D01*
G02X1437488I-815J815D01*
G02X1437151Y1138594I815J815D01*
G02X1437210Y1138749I202J12D01*
G02X1437497I143J-144D01*
G02X1437552Y1138646I-143J-143D01*
G01Y1138559D01*
G03X1437772Y1138032I752J5D01*
G03X1438834I531J531D01*
G03X1439054Y1138525I-531J532D01*
G01Y1138649D01*
G37*
G36*
G01X1435354D02*
G02X1435409Y1138753I199J-39D01*
G02X1435696I143J-144D01*
G02X1435756Y1138603I-143J-144D01*
G02X1435418Y1137748I-1152J-39D01*
G02X1433788I-815J815D01*
G02X1433451Y1138594I815J815D01*
G02X1433510Y1138749I202J12D01*
G02X1433797I143J-144D01*
G02X1433852Y1138646I-143J-143D01*
G01Y1138559D01*
G03X1434072Y1138032I752J5D01*
G03X1435134I531J531D01*
G03X1435354Y1138525I-531J532D01*
G01Y1138649D01*
G37*
G36*
G01X1431654D02*
G02X1431709Y1138753I199J-39D01*
G02X1431996I143J-144D01*
G02X1432056Y1138603I-143J-144D01*
G02X1431718Y1137748I-1152J-39D01*
G02X1430088I-815J815D01*
G02X1429751Y1138594I815J815D01*
G02X1429810Y1138749I202J12D01*
G02X1430097I144J-144D01*
G02X1430152Y1138646I-143J-143D01*
G01Y1138559D01*
G03X1430372Y1138032I752J5D01*
G03X1431434I531J531D01*
G03X1431654Y1138525I-531J532D01*
G01Y1138649D01*
G37*
G36*
G01X1418704Y1135445D02*
G02X1418760Y1135548I199J-41D01*
G02X1419046I143J-143D01*
G02X1419106Y1135399I-142J-144D01*
G02X1418769Y1134544I-1152J-40D01*
G02X1417139I-815J815D01*
G02X1416801Y1135389I814J816D01*
G02X1416860Y1135544I202J12D01*
G02X1417147I143J-143D01*
G02X1417202Y1135442I-143J-143D01*
G01Y1135360D01*
X1417201Y1135359D01*
X1417202Y1135358D01*
Y1135354D01*
G03X1417423Y1134828I752J6D01*
G03X1418485I531J531D01*
G03X1418706Y1135361I-531J532D01*
G02X1418704Y1135364I161J109D01*
G01Y1135445D01*
G37*
G36*
G01X1415004D02*
G02X1415060Y1135548I199J-41D01*
G02X1415346I143J-143D01*
G02X1415406Y1135399I-142J-144D01*
G02X1415069Y1134544I-1152J-40D01*
G02X1413439I-815J815D01*
G02X1413101Y1135389I814J816D01*
G02X1413160Y1135544I202J12D01*
G02X1413447I143J-143D01*
G02X1413502Y1135442I-143J-143D01*
G01Y1135360D01*
X1413501Y1135359D01*
X1413502Y1135358D01*
Y1135354D01*
G03X1413723Y1134828I752J6D01*
G03X1414785I531J531D01*
G03X1415006Y1135361I-531J532D01*
G02X1415004Y1135364I161J109D01*
G01Y1135445D01*
G37*
G36*
G01X1407604D02*
G02X1407659Y1135548I199J-40D01*
G02X1407946I143J-143D01*
G02X1408006Y1135399I-143J-144D01*
G02X1407668Y1134544I-1152J-39D01*
G02X1406038I-815J815D01*
G02X1405701Y1135389I815J815D01*
G02X1405760Y1135544I202J12D01*
G02X1406047I143J-143D01*
G02X1406102Y1135442I-143J-143D01*
G01Y1135360D01*
X1406101Y1135359D01*
X1406102Y1135358D01*
Y1135354D01*
G03X1406322Y1134828I752J5D01*
G03X1407384I531J531D01*
G03X1407605Y1135361I-531J532D01*
G02X1407604Y1135364I191J65D01*
G01Y1135445D01*
G37*
G36*
G01X1429804D02*
G02X1429860Y1135548I199J-41D01*
G02X1430146I143J-143D01*
G02X1430206Y1135399I-142J-144D01*
G02X1429869Y1134544I-1152J-40D01*
G02X1428239I-815J815D01*
G02X1427901Y1135389I814J816D01*
G02X1427960Y1135544I202J12D01*
G02X1428247I144J-143D01*
G02X1428302Y1135442I-143J-143D01*
G01Y1135360D01*
X1428301Y1135359D01*
X1428302Y1135358D01*
Y1135354D01*
G03X1428523Y1134828I752J6D01*
G03X1429585I531J531D01*
G03X1429806Y1135361I-531J532D01*
G02X1429804Y1135364I161J109D01*
G01Y1135445D01*
G37*
G36*
G01X1430409Y1172020D02*
X1439484D01*
X1440726Y1170779D01*
Y1152399D01*
X1439739Y1151412D01*
X1430159D01*
X1429122Y1152449D01*
Y1170734D01*
X1430409Y1172020D01*
G37*
G36*
G01X1405539D02*
X1414514D01*
X1415756Y1170779D01*
Y1152363D01*
X1414769Y1151376D01*
X1405753D01*
X1404152Y1152977D01*
Y1170634D01*
X1405539Y1172020D01*
G37*
G36*
G01X1382252Y1152589D02*
Y1170619D01*
X1383539Y1171906D01*
X1390069D01*
X1390956Y1171019D01*
Y1152489D01*
X1389969Y1151502D01*
X1383339D01*
X1382252Y1152589D01*
G37*
G36*
G01X1409165Y945186D02*
G03X1409160Y945463I-147J136D01*
G02X1408769Y946414I961J951D01*
G02X1411473I1352J0D01*
G02X1411082Y945463I-1352J0D01*
G03X1411077Y945186I142J-141D01*
G02X1411422Y944304I-955J-882D01*
G02X1408820I-1301J0D01*
G02X1409165Y945186I1300J0D01*
G37*
G36*
G01X1422115Y948391D02*
G03X1422110Y948667I-147J135D01*
G02X1424422Y949619I960J952D01*
G02X1424031Y948668I-1352J0D01*
G03X1424027Y948392I143J-140D01*
G02X1424372Y947509I-956J-882D01*
G02X1421770I-1301J0D01*
G02X1422115Y948391I1300J0D01*
G37*
G36*
G01X1409165Y951595D02*
G03X1409160Y951872I-147J136D01*
G02X1408769Y952823I961J951D01*
G02X1411473I1352J0D01*
G02X1411082Y951872I-1352J0D01*
G03X1411077Y951595I142J-141D01*
G02X1411422Y950713I-955J-882D01*
G02X1408820I-1301J0D01*
G02X1409165Y951595I1300J0D01*
G37*
G36*
G01X1422115Y954799D02*
G03X1422110Y955075I-147J135D01*
G02X1424422Y956027I960J952D01*
G02X1424031Y955076I-1352J0D01*
G03X1424027Y954800I143J-140D01*
G02X1424372Y953917I-956J-882D01*
G02X1421770I-1301J0D01*
G02X1422115Y954799I1300J0D01*
G37*
G36*
G01X1441496Y955616D02*
G03X1440932I-282J-284D01*
G02X1440015Y955238I-917J923D01*
G02Y957840I0J1301D01*
G02X1440932Y957462I0J-1301D01*
G03X1441496I282J284D01*
G02X1442413Y957840I917J-923D01*
G02Y955238I0J-1301D01*
G02X1441496Y955616I0J1301D01*
G37*
G36*
G01X1409165Y958004D02*
G03X1409160Y958281I-147J136D01*
G02X1408769Y959232I961J951D01*
G02X1411473I1352J0D01*
G02X1411082Y958281I-1352J0D01*
G03X1411077Y958004I142J-141D01*
G02X1411422Y957122I-955J-882D01*
G02X1408820I-1301J0D01*
G02X1409165Y958004I1300J0D01*
G37*
G36*
G01X1422115Y961208D02*
G03X1422110Y961484I-147J135D01*
G02X1424422Y962436I960J952D01*
G02X1424031Y961485I-1352J0D01*
G03X1424027Y961209I143J-140D01*
G02X1424372Y960326I-956J-882D01*
G02X1421770I-1301J0D01*
G02X1422115Y961208I1300J0D01*
G37*
G36*
G01X1409165Y964412D02*
G03X1409160Y964689I-147J136D01*
G02X1408769Y965640I961J951D01*
G02X1411473I1352J0D01*
G02X1411082Y964689I-1352J0D01*
G03X1411077Y964412I142J-141D01*
G02X1411422Y963530I-955J-882D01*
G02X1408820I-1301J0D01*
G02X1409165Y964412I1300J0D01*
G37*
G36*
G01X1422115Y967617D02*
G03X1422110Y967893I-147J135D01*
G02X1424422Y968845I960J952D01*
G02X1424031Y967894I-1352J0D01*
G03X1424027Y967618I143J-140D01*
G02X1424372Y966735I-956J-882D01*
G02X1421770I-1301J0D01*
G02X1422115Y967617I1300J0D01*
G37*
G36*
G01X1409165Y970821D02*
G03X1409160Y971098I-147J136D01*
G02X1408769Y972049I961J951D01*
G02X1411473I1352J0D01*
G02X1411082Y971098I-1352J0D01*
G03X1411077Y970821I142J-141D01*
G02X1411422Y969939I-955J-882D01*
G02X1408820I-1301J0D01*
G02X1409165Y970821I1300J0D01*
G37*
G36*
G01X1422115Y974025D02*
G03X1422110Y974301I-147J135D01*
G02X1424422Y975253I960J952D01*
G02X1424031Y974302I-1352J0D01*
G03X1424027Y974026I143J-140D01*
G02X1424372Y973143I-956J-882D01*
G02X1421770I-1301J0D01*
G02X1422115Y974025I1300J0D01*
G37*
G36*
G01X1409165Y977229D02*
G03X1409160Y977506I-147J136D01*
G02X1408769Y978457I961J951D01*
G02X1411473I1352J0D01*
G02X1411082Y977506I-1352J0D01*
G03X1411077Y977229I142J-141D01*
G02X1411422Y976347I-955J-882D01*
G02X1408820I-1301J0D01*
G02X1409165Y977229I1300J0D01*
G37*
G36*
G01X1422115Y980434D02*
G03X1422110Y980710I-147J135D01*
G02X1424422Y981662I960J952D01*
G02X1424031Y980711I-1352J0D01*
G03X1424027Y980435I143J-140D01*
G02X1424372Y979552I-956J-882D01*
G02X1421770I-1301J0D01*
G02X1422115Y980434I1300J0D01*
G37*
G36*
G01X1409165Y983638D02*
G03X1409160Y983915I-147J136D01*
G02X1408769Y984866I961J951D01*
G02X1411473I1352J0D01*
G02X1411082Y983915I-1352J0D01*
G03X1411077Y983638I142J-141D01*
G02X1411422Y982756I-955J-882D01*
G02X1408820I-1301J0D01*
G02X1409165Y983638I1300J0D01*
G37*
G36*
G01X1392802Y984653D02*
G03X1392240I-281J-284D01*
G02X1391326Y984278I-914J926D01*
G02Y986880I0J1301D01*
G02X1392240Y986505I0J-1301D01*
G03X1392802I281J284D01*
G02X1393716Y986880I914J-926D01*
G02Y984278I0J-1301D01*
G02X1392802Y984653I0J1301D01*
G37*
G36*
G01X1441496Y984656D02*
G03X1440932I-282J-284D01*
G02X1440015Y984278I-917J923D01*
G02Y986880I0J1301D01*
G02X1440932Y986502I0J-1301D01*
G03X1441496I282J284D01*
G02X1442413Y986880I917J-923D01*
G02Y984278I0J-1301D01*
G02X1441496Y984656I0J1301D01*
G37*
G36*
G01X1422542Y998525D02*
G03X1422547Y998802I-142J141D01*
G02X1422202Y999684I955J882D01*
G02X1424804I1301J0D01*
G02X1424459Y998802I-1300J0D01*
G03X1424464Y998525I147J-136D01*
G02X1424855Y997574I-961J-951D01*
G02X1422151I-1352J0D01*
G02X1422542Y998525I1352J0D01*
G37*
G36*
G01X1392802Y999133D02*
G03X1392240I-281J-284D01*
G02X1391326Y998758I-914J926D01*
G02Y1001360I0J1301D01*
G02X1392240Y1000985I0J-1301D01*
G03X1392802I281J284D01*
G02X1393716Y1001360I914J-926D01*
G02Y998758I0J-1301D01*
G02X1392802Y999133I0J1301D01*
G37*
G36*
G01X1441496Y999136D02*
G03X1440932I-282J-284D01*
G02X1440015Y998758I-917J923D01*
G02Y1001360I0J1301D01*
G02X1440932Y1000982I0J-1301D01*
G03X1441496I282J284D01*
G02X1442413Y1001360I917J-923D01*
G02Y998758I0J-1301D01*
G02X1441496Y999136I0J1301D01*
G37*
G36*
G01X1409593Y1001729D02*
G03X1409597Y1002005I-143J140D01*
G02X1409252Y1002888I956J882D01*
G02X1411854I1301J0D01*
G02X1411509Y1002006I-1300J0D01*
G03X1411514Y1001730I147J-135D01*
G02X1409202Y1000778I-960J-952D01*
G02X1409593Y1001729I1352J0D01*
G37*
G36*
G01X1422542Y1004934D02*
G03X1422547Y1005211I-142J141D01*
G02X1422202Y1006093I955J882D01*
G02X1424804I1301J0D01*
G02X1424459Y1005211I-1300J0D01*
G03X1424464Y1004934I147J-136D01*
G02X1424855Y1003983I-961J-951D01*
G02X1422151I-1352J0D01*
G02X1422542Y1004934I1352J0D01*
G37*
G36*
G01X1409593Y1008138D02*
G03X1409597Y1008414I-143J140D01*
G02X1409252Y1009297I956J882D01*
G02X1411854I1301J0D01*
G02X1411509Y1008415I-1300J0D01*
G03X1411514Y1008139I147J-135D01*
G02X1409202Y1007187I-960J-952D01*
G02X1409593Y1008138I1352J0D01*
G37*
G36*
G01X1422542Y1011342D02*
G03X1422547Y1011619I-142J141D01*
G02X1422202Y1012501I955J882D01*
G02X1424804I1301J0D01*
G02X1424459Y1011619I-1300J0D01*
G03X1424464Y1011342I147J-136D01*
G02X1424855Y1010391I-961J-951D01*
G02X1422151I-1352J0D01*
G02X1422542Y1011342I1352J0D01*
G37*
G36*
G01X1441496Y1013616D02*
G03X1440932I-282J-284D01*
G02X1440015Y1013238I-917J923D01*
G02Y1015840I0J1301D01*
G02X1440932Y1015462I0J-1301D01*
G03X1441496I282J284D01*
G02X1442413Y1015840I917J-923D01*
G02Y1013238I0J-1301D01*
G02X1441496Y1013616I0J1301D01*
G37*
G36*
G01X1409593Y1014546D02*
G03X1409597Y1014822I-143J140D01*
G02X1409252Y1015705I956J882D01*
G02X1411854I1301J0D01*
G02X1411509Y1014823I-1300J0D01*
G03X1411514Y1014547I147J-135D01*
G02X1409202Y1013595I-960J-952D01*
G02X1409593Y1014546I1352J0D01*
G37*
G36*
G01X1422542Y1017751D02*
G03X1422547Y1018028I-142J141D01*
G02X1422202Y1018910I955J882D01*
G02X1424804I1301J0D01*
G02X1424459Y1018028I-1300J0D01*
G03X1424464Y1017751I147J-136D01*
G02X1424855Y1016800I-961J-951D01*
G02X1422151I-1352J0D01*
G02X1422542Y1017751I1352J0D01*
G37*
G36*
G01X1409593Y1020955D02*
G03X1409597Y1021231I-143J140D01*
G02X1409252Y1022114I956J882D01*
G02X1411854I1301J0D01*
G02X1411509Y1021232I-1300J0D01*
G03X1411514Y1020956I147J-135D01*
G02X1409202Y1020004I-960J-952D01*
G02X1409593Y1020955I1352J0D01*
G37*
G36*
G01X1422542Y1024159D02*
G03X1422547Y1024436I-142J141D01*
G02X1422202Y1025318I955J882D01*
G02X1424804I1301J0D01*
G02X1424459Y1024436I-1300J0D01*
G03X1424464Y1024159I147J-136D01*
G02X1424855Y1023208I-961J-951D01*
G02X1422151I-1352J0D01*
G02X1422542Y1024159I1352J0D01*
G37*
G36*
G01X1409593Y1027364D02*
G03X1409597Y1027640I-143J140D01*
G02X1409252Y1028523I956J882D01*
G02X1411854I1301J0D01*
G02X1411509Y1027641I-1300J0D01*
G03X1411514Y1027365I147J-135D01*
G02X1409202Y1026413I-960J-952D01*
G02X1409593Y1027364I1352J0D01*
G37*
G36*
G01X1422542Y1030568D02*
G03X1422547Y1030845I-142J141D01*
G02X1422202Y1031727I955J882D01*
G02X1424804I1301J0D01*
G02X1424459Y1030845I-1300J0D01*
G03X1424464Y1030568I147J-136D01*
G02X1424855Y1029617I-961J-951D01*
G02X1422151I-1352J0D01*
G02X1422542Y1030568I1352J0D01*
G37*
G36*
G01X1409593Y1033772D02*
G03X1409597Y1034048I-143J140D01*
G02X1409252Y1034931I956J882D01*
G02X1411854I1301J0D01*
G02X1411509Y1034049I-1300J0D01*
G03X1411514Y1033773I147J-135D01*
G02X1409202Y1032821I-960J-952D01*
G02X1409593Y1033772I1352J0D01*
G37*
G36*
G01X1422542Y1036977D02*
G03X1422547Y1037254I-142J141D01*
G02X1422202Y1038136I955J882D01*
G02X1424804I1301J0D01*
G02X1424459Y1037254I-1300J0D01*
G03X1424464Y1036977I147J-136D01*
G02X1424855Y1036026I-961J-951D01*
G02X1422151I-1352J0D01*
G02X1422542Y1036977I1352J0D01*
G37*
G36*
G01Y1101062D02*
G03X1422547Y1101339I-142J141D01*
G02X1422202Y1102221I955J882D01*
G02X1424804I1301J0D01*
G02X1424459Y1101339I-1300J0D01*
G03X1424464Y1101062I147J-136D01*
G02X1424855Y1100111I-961J-951D01*
G02X1422151I-1352J0D01*
G02X1422542Y1101062I1352J0D01*
G37*
G36*
G01X1409593Y1104267D02*
G03X1409597Y1104543I-143J140D01*
G02X1409252Y1105426I956J882D01*
G02X1411854I1301J0D01*
G02X1411509Y1104544I-1300J0D01*
G03X1411514Y1104268I147J-135D01*
G02X1409202Y1103316I-960J-952D01*
G02X1409593Y1104267I1352J0D01*
G37*
G36*
G01X1422542Y1107471D02*
G03X1422547Y1107748I-142J141D01*
G02X1422202Y1108630I955J882D01*
G02X1424804I1301J0D01*
G02X1424459Y1107748I-1300J0D01*
G03X1424464Y1107471I147J-136D01*
G02X1424855Y1106520I-961J-951D01*
G02X1422151I-1352J0D01*
G02X1422542Y1107471I1352J0D01*
G37*
G36*
G01X1409593Y1110675D02*
G03X1409597Y1110951I-143J140D01*
G02X1409252Y1111834I956J882D01*
G02X1411854I1301J0D01*
G02X1411509Y1110952I-1300J0D01*
G03X1411514Y1110676I147J-135D01*
G02X1409202Y1109724I-960J-952D01*
G02X1409593Y1110675I1352J0D01*
G37*
G36*
G01X1422542Y1113880D02*
G03X1422547Y1114157I-142J141D01*
G02X1422202Y1115039I955J882D01*
G02X1424804I1301J0D01*
G02X1424459Y1114157I-1300J0D01*
G03X1424464Y1113880I147J-136D01*
G02X1424855Y1112929I-961J-951D01*
G02X1422151I-1352J0D01*
G02X1422542Y1113880I1352J0D01*
G37*
G36*
G01X1433643Y1113881D02*
G03X1433648Y1114157I-142J141D01*
G02X1433303Y1115039I955J882D01*
G02X1435905I1301J0D01*
G02X1435560Y1114156I-1301J-1D01*
G03X1435564Y1113880I147J-136D01*
G02X1435955Y1112929I-961J-951D01*
G02X1433643Y1113881I-1352J0D01*
G37*
G36*
G01X1409593Y1117084D02*
G03X1409597Y1117360I-143J140D01*
G02X1409252Y1118243I956J882D01*
G02X1411854I1301J0D01*
G02X1411509Y1117361I-1300J0D01*
G03X1411514Y1117085I147J-135D01*
G02X1409202Y1116133I-960J-952D01*
G02X1409593Y1117084I1352J0D01*
G37*
G36*
G01X1422542Y1120288D02*
G03X1422547Y1120565I-142J141D01*
G02X1422202Y1121447I955J882D01*
G02X1424804I1301J0D01*
G02X1424459Y1120565I-1300J0D01*
G03X1424464Y1120288I147J-136D01*
G02X1424855Y1119337I-961J-951D01*
G02X1422151I-1352J0D01*
G02X1422542Y1120288I1352J0D01*
G37*
G36*
G01X1433643Y1120289D02*
G03X1433648Y1120565I-142J141D01*
G02X1433303Y1121447I955J882D01*
G02X1435905I1301J0D01*
G02X1435560Y1120564I-1301J-1D01*
G03X1435564Y1120288I147J-136D01*
G02X1435955Y1119337I-961J-951D01*
G02X1433643Y1120289I-1352J0D01*
G37*
G36*
G01X1398493Y1123492D02*
G03X1398497Y1123768I-143J140D01*
G02X1398152Y1124651I956J882D01*
G02X1400754I1301J0D01*
G02X1400409Y1123769I-1300J0D01*
G03X1400414Y1123493I147J-135D01*
G02X1398102Y1122541I-960J-952D01*
G02X1398493Y1123492I1352J0D01*
G37*
G36*
G01X1409593D02*
G03X1409597Y1123768I-143J140D01*
G02X1409252Y1124651I956J882D01*
G02X1411854I1301J0D01*
G02X1411509Y1123769I-1300J0D01*
G03X1411514Y1123493I147J-135D01*
G02X1409202Y1122541I-960J-952D01*
G02X1409593Y1123492I1352J0D01*
G37*
G36*
G01X1422542Y1126697D02*
G03X1422547Y1126974I-142J141D01*
G02X1422202Y1127856I955J882D01*
G02X1424804I1301J0D01*
G02X1424459Y1126974I-1300J0D01*
G03X1424464Y1126697I147J-136D01*
G02X1424855Y1125746I-961J-951D01*
G02X1422151I-1352J0D01*
G02X1422542Y1126697I1352J0D01*
G37*
G36*
G01X1433643Y1126698D02*
G03X1433648Y1126974I-142J141D01*
G02X1433303Y1127856I955J882D01*
G02X1435905I1301J0D01*
G02X1435560Y1126973I-1301J-1D01*
G03X1435564Y1126697I147J-136D01*
G02X1435955Y1125746I-961J-951D01*
G02X1433643Y1126698I-1352J0D01*
G37*
G36*
G01X1398493Y1129901D02*
G03X1398497Y1130177I-143J140D01*
G02X1398152Y1131060I956J882D01*
G02X1400754I1301J0D01*
G02X1400409Y1130178I-1300J0D01*
G03X1400414Y1129902I147J-135D01*
G02X1398102Y1128950I-960J-952D01*
G02X1398493Y1129901I1352J0D01*
G37*
G36*
G01X1409593D02*
G03X1409597Y1130177I-143J140D01*
G02X1409252Y1131060I956J882D01*
G02X1411854I1301J0D01*
G02X1411509Y1130178I-1300J0D01*
G03X1411514Y1129902I147J-135D01*
G02X1409202Y1128950I-960J-952D01*
G02X1409593Y1129901I1352J0D01*
G37*
G36*
G01X1433643Y1133106D02*
G03X1433648Y1133382I-142J141D01*
G02X1433303Y1134264I955J882D01*
G02X1435905I1301J0D01*
G02X1435560Y1133381I-1301J-1D01*
G03X1435564Y1133105I147J-136D01*
G02X1435955Y1132154I-961J-951D01*
G02X1433643Y1133106I-1352J0D01*
G37*
G36*
G01X1422404Y1135445D02*
G02X1422459Y1135548I199J-40D01*
G02X1422746I143J-143D01*
G02X1422764Y1135527I-144J-142D01*
G03X1423000Y1135464I159J121D01*
G02X1423503Y1135565I503J-1200D01*
G02X1424008Y1135463I0J-1301D01*
G03X1424244Y1135525I78J184D01*
G02X1424260Y1135544I163J-121D01*
G02X1424547I143J-143D01*
G02X1424602Y1135442I-143J-143D01*
G01Y1135360D01*
X1424601Y1135359D01*
X1424602Y1135358D01*
Y1135354D01*
G03X1424823Y1134828I752J6D01*
G03X1425885I531J531D01*
G03X1426106Y1135361I-531J532D01*
G02X1426104Y1135364I161J109D01*
G01Y1135445D01*
G02X1426160Y1135548I199J-41D01*
G02X1426446I143J-143D01*
G02X1426506Y1135399I-142J-144D01*
G02X1426169Y1134544I-1152J-40D01*
G02X1425199Y1134217I-815J815D01*
G03X1424759Y1133925I-54J-396D01*
G02X1424459Y1133382I-1256J339D01*
G03X1424464Y1133105I147J-136D01*
G02X1424855Y1132154I-961J-951D01*
G02X1422151I-1352J0D01*
G02X1422542Y1133105I1352J0D01*
G03X1422547Y1133382I-142J141D01*
G02X1422247Y1133925I956J882D01*
G03X1421807Y1134217I-386J-104D01*
G02X1420838Y1134544I-154J1142D01*
G02X1420501Y1135389I815J815D01*
G02X1420560Y1135544I202J12D01*
G02X1420847I143J-143D01*
G02X1420902Y1135442I-143J-143D01*
G01Y1135360D01*
X1420901Y1135359D01*
X1420902Y1135358D01*
Y1135354D01*
G03X1421122Y1134828I752J5D01*
G03X1422184I531J531D01*
G03X1422405Y1135361I-531J532D01*
G02X1422404Y1135364I191J65D01*
G01Y1135445D01*
G37*
G36*
G01X1402054Y1138649D02*
G02X1402109Y1138753I199J-39D01*
G02X1402396I143J-144D01*
G02X1402456Y1138603I-143J-144D01*
G02X1402118Y1137748I-1152J-39D01*
G02X1401149Y1137421I-815J815D01*
G03X1400710Y1137129I-53J-396D01*
G02X1400410Y1136587I-1256J341D01*
G03X1400415Y1136310I147J-136D01*
G02X1400806Y1135359I-961J-951D01*
G02X1398102I-1352J0D01*
G02X1398493Y1136310I1352J0D01*
G03X1398498Y1136587I-142J141D01*
G02X1398198Y1137129I956J883D01*
G03X1397758Y1137421I-386J-104D01*
G02X1396788Y1137748I-155J1142D01*
G02X1396451Y1138594I815J815D01*
G02X1396510Y1138749I202J12D01*
G02X1396797I143J-144D01*
G02X1396852Y1138646I-143J-143D01*
G01Y1138559D01*
G03X1397072Y1138032I752J5D01*
G03X1398134I531J531D01*
G03X1398354Y1138525I-531J532D01*
G01Y1138649D01*
G02X1398409Y1138753I199J-39D01*
G02X1398696I143J-144D01*
G02X1398714Y1138732I-145J-142D01*
G03X1398951Y1138669I159J121D01*
G02X1399454Y1138770I503J-1200D01*
G02X1399958Y1138668I-1J-1301D01*
G03X1400194Y1138730I78J185D01*
G02X1400210Y1138749I163J-121D01*
G02X1400497I143J-144D01*
G02X1400552Y1138646I-143J-143D01*
G01Y1138559D01*
G03X1400772Y1138032I752J5D01*
G03X1401834I531J531D01*
G03X1402054Y1138525I-531J532D01*
G01Y1138649D01*
G37*
G36*
G01X1409652Y1136630D02*
Y1136828D01*
X1409599Y1136885D01*
G02X1409253Y1137769I956J884D01*
G02X1411855I1301J0D01*
G02X1411509Y1136885I-1302J0D01*
G01X1411456Y1136828D01*
Y1136630D01*
X1411504Y1136574D01*
G02X1411806Y1135759I-949J-815D01*
G01Y1135359D01*
G02X1409302I-1252J0D01*
G01Y1135759D01*
G02X1409604Y1136574I1251J0D01*
G01X1409652Y1136630D01*
G37*
G36*
G01X1348176Y1302030D02*
Y1304984D01*
X1367868D01*
Y1302030D01*
X1367688D01*
Y1289283D01*
X1366761Y1288356D01*
X1349261D01*
X1349250Y1288367D01*
X1348697D01*
X1348336Y1288728D01*
Y1302030D01*
X1348176D01*
G37*
G36*
G01X1380304D02*
Y1304984D01*
X1399996D01*
Y1302030D01*
X1399816D01*
Y1289761D01*
X1399809Y1289754D01*
Y1288981D01*
X1399154Y1288326D01*
X1381531D01*
X1381529Y1288328D01*
X1380746D01*
X1380464Y1288610D01*
Y1302030D01*
X1380304D01*
G37*
G36*
G01X1412432D02*
Y1304984D01*
X1432124D01*
Y1302030D01*
X1431944D01*
Y1292228D01*
X1431920Y1292203D01*
Y1288832D01*
X1431491Y1288403D01*
X1430798D01*
X1430791Y1288396D01*
X1413621D01*
X1412592Y1289425D01*
Y1302030D01*
X1412432D01*
G37*
G36*
G01X1444560D02*
Y1304984D01*
X1464316D01*
Y1289421D01*
X1463291Y1288396D01*
X1445691D01*
X1444720Y1289367D01*
Y1302030D01*
X1444560D01*
G37*
G36*
G01X1316048Y1315456D02*
Y1318410D01*
X1335740D01*
Y1315456D01*
X1335560D01*
Y1301742D01*
X1335260Y1301442D01*
X1334087D01*
X1334081Y1301436D01*
X1317161D01*
X1316594Y1302004D01*
X1316584Y1302012D01*
G02X1316495Y1302101I307J396D01*
G01X1316487Y1302111D01*
X1316208Y1302389D01*
Y1315456D01*
X1316048D01*
G37*
G36*
G01X1476688D02*
Y1318410D01*
X1496380D01*
Y1315456D01*
X1496200D01*
Y1302915D01*
X1496196Y1302912D01*
Y1301978D01*
X1495748Y1301530D01*
X1494814D01*
X1494811Y1301526D01*
X1477951D01*
X1476848Y1302629D01*
Y1315456D01*
X1476688D01*
G37*
G36*
G01X1283920Y1338254D02*
Y1341208D01*
X1303612D01*
Y1338254D01*
X1303432D01*
Y1324974D01*
X1302904Y1324446D01*
X1285201D01*
X1284651Y1324997D01*
X1284629Y1325010D01*
G02X1284451Y1325188I254J432D01*
G01X1284438Y1325210D01*
X1284080Y1325567D01*
Y1338254D01*
X1283920D01*
G37*
G36*
G01X1508816D02*
Y1341208D01*
X1528508D01*
Y1338254D01*
X1528328D01*
Y1335078D01*
G02X1528528Y1334677I-302J-401D01*
G01Y1325177D01*
G02X1528526Y1325144I-501J14D01*
G01Y1324648D01*
X1528116Y1324238D01*
X1527032D01*
X1527031Y1324236D01*
X1510141D01*
X1508976Y1325401D01*
Y1338254D01*
X1508816D01*
G37*
G36*
G01X1355964Y1356946D02*
G02X1356365Y1357348I401J1D01*
G01X1362365D01*
G02X1362766Y1356946I-1J-402D01*
G01Y1350946D01*
G02X1362365Y1350544I-401J-1D01*
G01X1356365D01*
G02X1355964Y1350946I1J402D01*
G01Y1356946D01*
G37*
G36*
G01X1385730D02*
G02X1386131Y1357348I401J1D01*
G01X1392131D01*
G02X1392532Y1356946I-1J-402D01*
G01Y1350946D01*
G02X1392131Y1350544I-401J-1D01*
G01X1386131D01*
G02X1385730Y1350946I1J402D01*
G01Y1356946D01*
G37*
G36*
G01X1416066D02*
G02X1416467Y1357348I401J1D01*
G01X1422467D01*
G02X1422868Y1356946I-1J-402D01*
G01Y1350946D01*
G02X1422467Y1350544I-401J-1D01*
G01X1416467D01*
G02X1416066Y1350946I1J402D01*
G01Y1356946D01*
G37*
G36*
G01X1445832D02*
G02X1446233Y1357348I401J1D01*
G01X1452233D01*
G02X1452634Y1356946I-1J-402D01*
G01Y1350946D01*
G02X1452233Y1350544I-401J-1D01*
G01X1446233D01*
G02X1445832Y1350946I1J402D01*
G01Y1356946D01*
G37*
G36*
G01X1430798Y1382362D02*
G02X1431200Y1382764I402J0D01*
G01X1437200D01*
G02X1437602Y1382362I0J-402D01*
G01Y1376362D01*
G02X1437200Y1375960I-402J0D01*
G01X1431200D01*
G02X1430798Y1376362I0J402D01*
G01Y1382362D01*
G37*
G36*
G01X1444043Y1375860D02*
G02Y1382864I0J3502D01*
G02X1444812Y1382778I-2J-3502D01*
G03X1444844Y1382772I90J390D01*
G02X1447546Y1379362I-801J-3410D01*
G02X1444844Y1375952I-3503J0D01*
G03X1444812Y1375946I58J-396D01*
G02X1444043Y1375860I-771J3416D01*
G37*
G36*
G01X1433796Y937656D02*
X1434252D01*
X1434253Y937658D01*
X1448183D01*
X1449408Y936433D01*
Y929137D01*
X1447272Y927002D01*
X1434575D01*
X1433080Y928496D01*
Y936486D01*
X1433796Y937200D01*
Y937656D01*
G37*
G36*
G01X1573498Y596662D02*
Y602862D01*
G02X1573900Y603264I402J0D01*
G01X1580100D01*
G02X1580502Y602862I0J-402D01*
G01Y596662D01*
G02X1580100Y596260I-402J0D01*
G01X1573900D01*
G02X1573498Y596662I0J402D01*
G37*
G36*
G01Y645662D02*
Y651862D01*
G02X1573900Y652264I402J0D01*
G01X1580100D01*
G02X1580502Y651862I0J-402D01*
G01Y645662D01*
G02X1580100Y645260I-402J0D01*
G01X1573900D01*
G02X1573498Y645662I0J402D01*
G37*
G36*
G01Y694562D02*
Y700762D01*
G02X1573900Y701164I402J0D01*
G01X1580100D01*
G02X1580502Y700762I0J-402D01*
G01Y694562D01*
G02X1580100Y694160I-402J0D01*
G01X1573900D01*
G02X1573498Y694562I0J402D01*
G37*
G36*
G01Y670062D02*
Y676262D01*
G02X1573900Y676664I402J0D01*
G01X1580100D01*
G02X1580502Y676262I0J-402D01*
G01Y670062D01*
G02X1580100Y669660I-402J0D01*
G01X1573900D01*
G02X1573498Y670062I0J402D01*
G37*
G36*
G01Y719062D02*
Y725262D01*
G02X1573900Y725664I402J0D01*
G01X1580100D01*
G02X1580502Y725262I0J-402D01*
G01Y719062D01*
G02X1580100Y718660I-402J0D01*
G01X1573900D01*
G02X1573498Y719062I0J402D01*
G37*
G36*
G01X1607012Y748156D02*
X1611912D01*
G02Y740952I0J-3602D01*
G01X1607012D01*
G02Y748156I0J3602D01*
G37*
G36*
G01X1666412D02*
X1671312D01*
G02Y740952I0J-3602D01*
G01X1666412D01*
G02Y748156I0J3602D01*
G37*
G36*
G01X1725812D02*
X1730712D01*
G02Y740952I0J-3602D01*
G01X1725812D01*
G02Y748156I0J3602D01*
G37*
G36*
G01X1636712D02*
X1641612D01*
G02Y740952I0J-3602D01*
G01X1636712D01*
G02Y748156I0J3602D01*
G37*
G36*
G01X1702010Y748702D02*
G02X1701808Y749455I1300J752D01*
G02X1704812I1502J0D01*
G02X1703563Y747974I-1503J0D01*
G03X1703368Y747278I67J-394D01*
G02X1704614Y744554I-2355J-2724D01*
G02X1701012Y740952I-3602J0D01*
G01X1696112D01*
G02Y748156I0J3602D01*
G01X1701012D01*
G02X1701599Y748107I-5J-3602D01*
G03X1702010Y748702I65J395D01*
G37*
G36*
G01X1607012Y1291266D02*
X1611912D01*
G02Y1284062I0J-3602D01*
G01X1607012D01*
G02Y1291266I0J3602D01*
G37*
G36*
G01X1666412D02*
X1671312D01*
G02Y1284062I0J-3602D01*
G01X1666412D01*
G02Y1291266I0J3602D01*
G37*
G36*
G01X1725812D02*
X1730712D01*
G02Y1284062I0J-3602D01*
G01X1725812D01*
G02Y1291266I0J3602D01*
G37*
G36*
G01X1785212D02*
X1790112D01*
G02Y1284062I0J-3602D01*
G01X1785212D01*
G02Y1291266I0J3602D01*
G37*
G36*
G01X1636712D02*
X1641612D01*
G02Y1284062I0J-3602D01*
G01X1636712D01*
G02Y1291266I0J3602D01*
G37*
G36*
G01X1696112D02*
X1701012D01*
G02Y1284062I0J-3602D01*
G01X1696112D01*
G02Y1291266I0J3602D01*
G37*
G36*
G01X1755512D02*
X1760412D01*
G02Y1284062I0J-3602D01*
G01X1755512D01*
G02Y1291266I0J3602D01*
G37*
G36*
G01X1814912D02*
X1819812D01*
G02Y1284062I0J-3602D01*
G01X1814912D01*
G02Y1291266I0J3602D01*
G37*
G36*
G01X1640183Y1268656D02*
G03X1639650Y1268455I-167J-363D01*
G02X1638277Y1267563I-1373J611D01*
G02Y1270567I0J1502D01*
G02X1638906Y1270429I0J-1502D01*
G03X1639439Y1270630I167J363D01*
G02X1640812Y1271522I1373J-611D01*
G02Y1268518I0J-1502D01*
G02X1640183Y1268656I0J1502D01*
G37*
G36*
G01X1817099Y1272161D02*
G03X1816477I-311J-252D01*
G02X1815388Y1271642I-1089J883D01*
G02Y1274446I0J1402D01*
G02X1816477Y1273927I0J-1402D01*
G03X1817099I311J252D01*
G02X1818188Y1274446I1089J-883D01*
G02Y1271642I0J-1402D01*
G02X1817099Y1272161I0J1402D01*
G37*
G36*
G01X1602854Y1272098D02*
G03X1602322I-266J-298D01*
G02X1601388Y1271742I-934J1047D01*
G02Y1274546I0J1402D01*
G02X1602322Y1274190I0J-1403D01*
G03X1602854I266J298D01*
G02X1603788Y1274546I934J-1047D01*
G02Y1271742I0J-1402D01*
G02X1602854Y1272098I0J1403D01*
G37*
G36*
G01X1617799Y1272461D02*
G03X1617177I-311J-252D01*
G02X1616088Y1271942I-1089J883D01*
G02Y1274746I0J1402D01*
G02X1617177Y1274227I0J-1402D01*
G03X1617799I311J252D01*
G02X1618888Y1274746I1089J-883D01*
G02Y1271942I0J-1402D01*
G02X1617799Y1272461I0J1402D01*
G37*
G36*
G01X1631499D02*
G03X1630877I-311J-252D01*
G02X1629788Y1271942I-1089J883D01*
G02Y1274746I0J1402D01*
G02X1630877Y1274227I0J-1402D01*
G03X1631499I311J252D01*
G02X1632588Y1274746I1089J-883D01*
G02Y1271942I0J-1402D01*
G02X1631499Y1272461I0J1402D01*
G37*
G36*
G01X1647499D02*
G03X1646877I-311J-252D01*
G02X1645788Y1271942I-1089J883D01*
G02Y1274746I0J1402D01*
G02X1646877Y1274227I0J-1402D01*
G03X1647499I311J252D01*
G02X1648588Y1274746I1089J-883D01*
G02Y1271942I0J-1402D01*
G02X1647499Y1272461I0J1402D01*
G37*
G36*
G01X1661199D02*
G03X1660577I-311J-252D01*
G02X1659488Y1271942I-1089J883D01*
G02Y1274746I0J1402D01*
G02X1660577Y1274227I0J-1402D01*
G03X1661199I311J252D01*
G02X1662288Y1274746I1089J-883D01*
G02Y1271942I0J-1402D01*
G02X1661199Y1272461I0J1402D01*
G37*
G36*
G01X1677199D02*
G03X1676577I-311J-252D01*
G02X1675488Y1271942I-1089J883D01*
G02Y1274746I0J1402D01*
G02X1676577Y1274227I0J-1402D01*
G03X1677199I311J252D01*
G02X1678288Y1274746I1089J-883D01*
G02Y1271942I0J-1402D01*
G02X1677199Y1272461I0J1402D01*
G37*
G36*
G01X1690899D02*
G03X1690277I-311J-252D01*
G02X1689188Y1271942I-1089J883D01*
G02Y1274746I0J1402D01*
G02X1690277Y1274227I0J-1402D01*
G03X1690899I311J252D01*
G02X1691988Y1274746I1089J-883D01*
G02Y1271942I0J-1402D01*
G02X1690899Y1272461I0J1402D01*
G37*
G36*
G01X1720599D02*
G03X1719977I-311J-252D01*
G02X1718888Y1271942I-1089J883D01*
G02Y1274746I0J1402D01*
G02X1719977Y1274227I0J-1402D01*
G03X1720599I311J252D01*
G02X1721688Y1274746I1089J-883D01*
G02Y1271942I0J-1402D01*
G02X1720599Y1272461I0J1402D01*
G37*
G36*
G01X1736599D02*
G03X1735977I-311J-252D01*
G02X1734888Y1271942I-1089J883D01*
G02Y1274746I0J1402D01*
G02X1735977Y1274227I0J-1402D01*
G03X1736599I311J252D01*
G02X1737688Y1274746I1089J-883D01*
G02Y1271942I0J-1402D01*
G02X1736599Y1272461I0J1402D01*
G37*
G36*
G01X1750299D02*
G03X1749677I-311J-252D01*
G02X1748588Y1271942I-1089J883D01*
G02Y1274746I0J1402D01*
G02X1749677Y1274227I0J-1402D01*
G03X1750299I311J252D01*
G02X1751388Y1274746I1089J-883D01*
G02Y1271942I0J-1402D01*
G02X1750299Y1272461I0J1402D01*
G37*
G36*
G01X1766299D02*
G03X1765677I-311J-252D01*
G02X1764588Y1271942I-1089J883D01*
G02Y1274746I0J1402D01*
G02X1765677Y1274227I0J-1402D01*
G03X1766299I311J252D01*
G02X1767388Y1274746I1089J-883D01*
G02Y1271942I0J-1402D01*
G02X1766299Y1272461I0J1402D01*
G37*
G36*
G01X1779999D02*
G03X1779377I-311J-252D01*
G02X1778288Y1271942I-1089J883D01*
G02Y1274746I0J1402D01*
G02X1779377Y1274227I0J-1402D01*
G03X1779999I311J252D01*
G02X1781088Y1274746I1089J-883D01*
G02Y1271942I0J-1402D01*
G02X1779999Y1272461I0J1402D01*
G37*
G36*
G01X1795999D02*
G03X1795377I-311J-252D01*
G02X1794288Y1271942I-1089J883D01*
G02Y1274746I0J1402D01*
G02X1795377Y1274227I0J-1402D01*
G03X1795999I311J252D01*
G02X1797088Y1274746I1089J-883D01*
G02Y1271942I0J-1402D01*
G02X1795999Y1272461I0J1402D01*
G37*
G36*
G01X1809699D02*
G03X1809077I-311J-252D01*
G02X1807988Y1271942I-1089J883D01*
G02Y1274746I0J1402D01*
G02X1809077Y1274227I0J-1402D01*
G03X1809699I311J252D01*
G02X1810788Y1274746I1089J-883D01*
G02Y1271942I0J-1402D01*
G02X1809699Y1272461I0J1402D01*
G37*
G36*
G01X1706655Y1272336D02*
G03X1706139Y1272314I-245J-316D01*
G02X1705188Y1271942I-951J1030D01*
G02Y1274746I0J1402D01*
G02X1706047Y1274452I0J-1402D01*
G03X1706563Y1274474I245J316D01*
G02X1707514Y1274846I951J-1030D01*
G02Y1272042I0J-1402D01*
G02X1706655Y1272336I0J1402D01*
G37*
G36*
G01X1613263Y716401D02*
X1628133D01*
X1628973Y715561D01*
Y697429D01*
X1628203Y696659D01*
X1612973D01*
X1612342Y697290D01*
Y715480D01*
X1613263Y716401D01*
G37*
G36*
G01X1628133Y648401D02*
X1628973Y647561D01*
Y629429D01*
X1628203Y628659D01*
X1612973D01*
X1612342Y629290D01*
Y647480D01*
X1613263Y648401D01*
X1628133D01*
G37*
G36*
G01X1613263Y682401D02*
X1628133D01*
X1628973Y681561D01*
Y663429D01*
X1628203Y662659D01*
X1612973D01*
X1612342Y663290D01*
Y681480D01*
X1613263Y682401D01*
G37*
G36*
G01X1620320Y610882D02*
X1622060Y612622D01*
X1639090D01*
X1640490Y611222D01*
Y594542D01*
X1640200Y594252D01*
X1621530D01*
X1620320Y595462D01*
Y610882D01*
G37*
G36*
G01X1655130Y1359173D02*
Y1365373D01*
G02X1655532Y1365774I402J-1D01*
G01X1661732D01*
G02X1662134Y1365373I1J-401D01*
G01Y1359173D01*
G02X1661732Y1358772I-402J1D01*
G01X1655532D01*
G02X1655130Y1359173I-1J401D01*
G37*
G36*
G01X1679530D02*
Y1365373D01*
G02X1679932Y1365774I402J-1D01*
G01X1686132D01*
G02X1686534Y1365373I1J-401D01*
G01Y1359173D01*
G02X1686132Y1358772I-402J1D01*
G01X1679932D01*
G02X1679530Y1359173I-1J401D01*
G37*
G36*
G01X1630758Y1359148D02*
Y1365348D01*
G02X1631159Y1365750I401J1D01*
G01X1637359D01*
G02X1637760Y1365348I-1J-402D01*
G01Y1359148D01*
G02X1637359Y1358746I-401J-1D01*
G01X1631159D01*
G02X1630758Y1359148I1J402D01*
G37*
G36*
G01X1666569Y1416641D02*
X1666680Y1416752D01*
X1686462D01*
X1686577Y1416637D01*
Y1396665D01*
X1685332Y1395420D01*
X1667540D01*
X1666569Y1396391D01*
Y1416641D01*
G37*
G36*
G01X1628426D02*
X1628507Y1416722D01*
X1648280D01*
X1648434Y1416568D01*
Y1396665D01*
X1647189Y1395420D01*
X1629397D01*
X1628426Y1396391D01*
Y1416641D01*
G37*
G36*
G01X1679438Y669748D02*
X1679453Y669821D01*
G02X1686311I3429J-712D01*
G01X1686326Y669748D01*
G02X1686385Y669109I-3444J-640D01*
G02X1679379I-3503J0D01*
G02X1679438Y669748I3503J-1D01*
G37*
G36*
G01X1681433Y621362D02*
G02X1682882Y621676I1449J-3188D01*
G02X1684331Y621362I0J-3502D01*
G02X1684708Y621162I-1450J-3188D01*
G02X1686384Y618174I-1826J-2988D01*
G02X1686110Y616817I-3502J1D01*
G03X1686099Y616788I368J-156D01*
G02X1682882Y614671I-3217J1386D01*
G02X1679665Y616788I0J3503D01*
G03X1679654Y616817I-379J-127D01*
G02X1679380Y618174I3228J1358D01*
G02X1681056Y621162I3502J0D01*
G02X1681433Y621362I1827J-2988D01*
G37*
G36*
G01X1679944Y1460153D02*
G02Y1467157I0J3502D01*
G02X1682687Y1465832I0J-3502D01*
G03X1682705Y1465811I313J250D01*
G02X1683447Y1463655I-2761J-2156D01*
G02X1682705Y1461499I-3503J0D01*
G03X1682687Y1461478I295J-271D01*
G02X1679944Y1460153I-2743J2177D01*
G37*
G36*
G01X1766388Y201632D02*
Y207632D01*
G02X1766790Y208034I402J0D01*
G01X1772790D01*
G02X1773192Y207632I0J-402D01*
G01Y201632D01*
G02X1772790Y201230I-402J0D01*
G01X1766790D01*
G02X1766388Y201632I0J402D01*
G37*
G36*
G01X1755832Y277370D02*
X1755794D01*
X1755832Y277408D01*
Y277574D01*
X1756629Y278370D01*
X1772739D01*
X1772800Y278310D01*
X1776760D01*
X1777786Y277284D01*
Y259134D01*
X1776929Y258278D01*
X1757199D01*
X1755832Y259644D01*
Y277370D01*
G37*
G36*
G01X1725113Y41522D02*
X1725032Y41603D01*
Y47175D01*
X1725073Y47216D01*
X1725765D01*
X1725876Y47105D01*
Y41613D01*
X1725785Y41522D01*
X1725113D01*
G37*
G36*
G01X1722751D02*
X1722670Y41603D01*
Y47175D01*
X1722711Y47216D01*
X1723403D01*
X1723514Y47105D01*
Y41613D01*
X1723423Y41522D01*
X1722751D01*
G37*
G36*
G01X1729838D02*
X1729756Y41603D01*
Y47175D01*
X1729798Y47216D01*
X1730490D01*
X1730602Y47105D01*
Y41613D01*
X1730510Y41522D01*
X1729838D01*
G37*
G36*
G01X1732200D02*
X1732118Y41603D01*
Y47175D01*
X1732160Y47216D01*
X1732852D01*
X1732964Y47105D01*
Y41613D01*
X1732872Y41522D01*
X1732200D01*
G37*
G36*
G01X1727475D02*
X1727394Y41603D01*
Y47175D01*
X1727435Y47216D01*
X1728127D01*
X1728238Y47105D01*
Y41613D01*
X1728147Y41522D01*
X1727475D01*
G37*
G54D349*
X224900Y713293D03*
X344446Y739434D03*
X216842Y756865D03*
X211220Y740362D03*
X227430Y719772D03*
X270100Y727262D03*
X269600Y715792D03*
X238940Y716652D03*
X290077Y739735D03*
X358902Y743035D03*
X317967Y746985D03*
X287820Y727962D03*
X289137Y735275D03*
X284358Y732562D03*
X199720Y732862D03*
X290680Y745312D03*
X298273Y715400D03*
X285046Y746702D03*
X150877Y757969D03*
X281046Y746702D03*
X242460Y716652D03*
X207602Y756855D03*
X199602D03*
X110527Y758869D03*
X63930Y739300D03*
X81966Y759246D03*
X82357Y737803D03*
X84623Y741249D03*
X85877Y759275D03*
X96626Y736187D03*
X483030Y1170070D03*
Y1153370D03*
Y1161570D03*
X622860Y487310D03*
X703755Y1290545D03*
X692784Y1298845D03*
X696810Y1300162D03*
X692280Y1302532D03*
X707720Y1290162D03*
X705720Y1286662D03*
X704795Y1294559D03*
X706680Y1437535D03*
X701730Y1437855D03*
X696940Y1437955D03*
X712290Y106722D03*
X722415Y77862D03*
X718425Y77882D03*
X719100Y85262D03*
X771630Y258102D03*
X1156609Y1286685D03*
X1099030Y245140D03*
X1311420Y738262D03*
X1458911Y1161569D03*
Y1170069D03*
X1538757Y1356355D03*
Y1360855D03*
Y1365355D03*
X1571577Y747145D03*
X1590915Y755793D03*
X1606788Y756199D03*
X1602788D03*
X1610788D03*
X1614788D03*
X1618788D03*
X1638928D03*
X1630928D03*
X1634928D03*
X1651509Y756492D03*
X1666686Y757162D03*
X1681810Y752955D03*
X1690620Y760702D03*
X1704973Y753019D03*
X1697725Y205120D03*
X1702490Y204780D03*
G54D350*
X283350Y728483D03*
X285046Y737964D03*
G54D357*
X1074010Y1510650D03*
X1066462Y1520088D03*
G54D352*
X88520Y1487982D03*
Y1491482D03*
Y1484482D03*
X92071Y1492888D03*
X661100Y1451012D03*
X219752Y1405499D03*
X303647Y1307981D03*
G54D351*
X174393Y668511D03*
X205159Y1430034D03*
X393067Y1354446D03*
X422833D03*
X453169D03*
X718638Y1429579D03*
X1178470Y1466363D03*
X1369208Y1353946D03*
X1398974D03*
X1429310D03*
X1459076D03*
X1836248Y269763D03*
Y299056D03*
G54D362*
X1131715Y1532913D03*
G54D354*
X275289Y575702D03*
Y599861D03*
Y624015D03*
Y648169D03*
X493293Y1242785D03*
X395771D03*
X420171D03*
X468893D03*
X444493D03*
X1100700Y275788D03*
X1100800Y251488D03*
X1371912Y1242785D03*
X1469434D03*
X1396312D03*
X1445034D03*
X1420634D03*
X1577000Y591888D03*
Y640888D03*
Y714288D03*
Y689788D03*
Y665288D03*
G54D361*
X1138201Y1270277D03*
X1147681Y1269684D03*
X1152381D03*
X1161781D03*
X1176867Y1270029D03*
X1220601Y1269684D03*
X1625729Y1266766D03*
G54D353*
X199139Y422882D03*
X287800Y60062D03*
X1759700Y57662D03*
X1764400Y57462D03*
G54D356*
X526478Y1439952D03*
X1502956Y1439530D03*
G54D360*
X1066280Y1704890D03*
G54D363*
X1766929Y1714960D03*
G54D355*
X525275Y1171319D03*
X356062D03*
X1332204D03*
X1501417D03*
G54D358*
X805690Y204724D03*
X1057658D03*
G54D359*
X841240Y1420330D03*
X1016240D03*
%LPD*%
G75*
G36*
G01X154958Y1363298D02*
Y1381669D01*
X155158Y1381869D01*
X172158D01*
X172306Y1381721D01*
Y1363407D01*
X171757Y1362858D01*
X155398D01*
X154958Y1363298D01*
G37*
G36*
G01X199859Y422882D02*
G03I-720J0D01*
G37*
G36*
G01X193101Y1363298D02*
Y1381669D01*
X193301Y1381869D01*
X210301D01*
X210449Y1381721D01*
Y1363407D01*
X209900Y1362858D01*
X193541D01*
X193101Y1363298D01*
G37*
G36*
G01X222311Y693369D02*
X234686D01*
X235616Y692439D01*
Y679415D01*
X234706Y678505D01*
X220356D01*
X218177D01*
X217528Y679154D01*
Y681570D01*
Y683268D01*
Y690314D01*
Y692670D01*
X218227Y693369D01*
X220764D01*
X222311D01*
G37*
G36*
G01X226457Y590655D02*
X240285D01*
X240485Y590455D01*
Y573655D01*
X240285Y573455D01*
X226457D01*
X226257Y573655D01*
Y590455D01*
X226457Y590655D01*
G37*
G36*
G01Y624655D02*
X240285D01*
X240485Y624455D01*
Y607655D01*
X240285Y607455D01*
X226457D01*
X226257Y607655D01*
Y624455D01*
X226457Y624655D01*
G37*
G36*
G01Y658655D02*
X240250D01*
X240485Y658420D01*
Y641655D01*
X240285Y641455D01*
X226457D01*
X226257Y641655D01*
Y658455D01*
X226457Y658655D01*
G37*
G36*
G01X288520Y60062D02*
G03I-720J0D01*
G37*
G36*
G01X326041Y1339885D02*
X309285D01*
X308720Y1339320D01*
Y1325642D01*
X308920Y1325442D01*
X326360D01*
X326540Y1325622D01*
Y1339386D01*
X326041Y1339885D01*
G37*
G36*
G01X341069Y1316801D02*
X341485Y1317217D01*
X358269D01*
X358417Y1317069D01*
Y1305764D01*
Y1302856D01*
X357929Y1302368D01*
X341679D01*
X341069Y1302978D01*
Y1316801D01*
G37*
G36*
G01X373197Y1292594D02*
Y1303591D01*
X373397Y1303791D01*
X390397D01*
X390545Y1303643D01*
Y1292936D01*
X390543Y1292934D01*
Y1290472D01*
X389509Y1289438D01*
X374029D01*
X373197Y1290270D01*
Y1292594D01*
G37*
G36*
G01X407564Y1152245D02*
X406884Y1152925D01*
Y1169965D01*
X407564Y1170645D01*
X412904D01*
X413459Y1170090D01*
Y1152805D01*
X412899Y1152245D01*
X407564D01*
G37*
G36*
G01X405325Y1292680D02*
Y1303591D01*
X405525Y1303791D01*
X422525D01*
X422673Y1303643D01*
Y1292937D01*
Y1289952D01*
X422069Y1289348D01*
X405929D01*
X405325Y1289952D01*
Y1292680D01*
G37*
G36*
G01X437749Y1152150D02*
X429549D01*
X428839Y1152860D01*
Y1170010D01*
X429989Y1171160D01*
X437669D01*
X438464Y1170365D01*
Y1152865D01*
X437749Y1152150D01*
G37*
G36*
G01X437453Y1292637D02*
Y1303591D01*
X437653Y1303791D01*
X454653D01*
X454801Y1303643D01*
Y1292699D01*
X454759Y1292658D01*
Y1290238D01*
X454039Y1289518D01*
X438209D01*
X437453Y1290274D01*
Y1292637D01*
G37*
G36*
G01X458320Y937157D02*
X471834D01*
X472765Y936226D01*
Y929346D01*
X470923Y927504D01*
X458642D01*
X457441Y928705D01*
Y936279D01*
X458320Y937157D01*
G37*
G36*
G01X462749Y1152150D02*
X454549D01*
X453839Y1152860D01*
Y1170010D01*
X454989Y1171160D01*
X462669D01*
X463434Y1170395D01*
Y1152835D01*
X462749Y1152150D01*
G37*
G36*
G01X469581Y1292765D02*
Y1303591D01*
X469781Y1303791D01*
X486781D01*
X486929Y1303643D01*
Y1293121D01*
Y1290588D01*
X485779Y1289438D01*
X470519D01*
X469581Y1290376D01*
Y1292765D01*
G37*
G36*
G01X501709Y1303318D02*
Y1317017D01*
X501909Y1317217D01*
X518909D01*
X519057Y1317069D01*
Y1303446D01*
X518219Y1302608D01*
X502419D01*
X501709Y1303318D01*
G37*
G36*
G01X533837Y1328621D02*
Y1339815D01*
X534037Y1340015D01*
X551037D01*
X551185Y1339867D01*
Y1328664D01*
Y1325934D01*
X550449Y1325198D01*
X534619D01*
X533837Y1325980D01*
Y1328621D01*
G37*
G36*
G01X700566Y1332178D02*
X694346D01*
G03X693964Y1331778I20J-401D01*
G01Y1325576D01*
G03X693986Y1325447I402J2D01*
G01X693997Y1325415D01*
Y1325182D01*
X676770D01*
G02X676578Y1325439I0J200D01*
G03X676594Y1325552I-385J112D01*
G01Y1328233D01*
X676595Y1331752D01*
G03X676194Y1332154I-402J0D01*
G01X669993D01*
G03X669592Y1331752I0J-401D01*
G01Y1325552D01*
G03X669608Y1325439I401J-1D01*
G02X669416Y1325182I-192J-57D01*
G01X656810D01*
X656210Y1325782D01*
Y1355045D01*
X657122Y1355957D01*
X734875D01*
X735979Y1354853D01*
Y1325871D01*
X735290Y1325182D01*
X725335D01*
Y1325415D01*
X725346Y1325447D01*
G03X725368Y1325576I-380J131D01*
G01Y1331777D01*
G03X724966Y1332178I-401J0D01*
G01X718746D01*
G03X718364Y1331778I20J-401D01*
G01Y1325576D01*
G03X718386Y1325447I402J2D01*
G01X718397Y1325415D01*
Y1325182D01*
X700935D01*
Y1325415D01*
X700946Y1325447D01*
G03X700968Y1325576I-380J131D01*
G01Y1331777D01*
G03X700566Y1332178I-401J0D01*
G37*
G36*
G01X668577Y1363323D02*
Y1381694D01*
X668777Y1381894D01*
X685777D01*
X685925Y1381746D01*
Y1363432D01*
X685376Y1362883D01*
X669017D01*
X668577Y1363323D01*
G37*
G36*
G01X693248Y1298845D02*
G03I-464J0D01*
G37*
G36*
G01X701234Y83050D02*
G03I-493J0D01*
G37*
G36*
G01X704219Y1290545D02*
G03I-464J0D01*
G37*
G36*
G01X709259Y1303701D02*
G03I-464J0D01*
G37*
G36*
G01X706720Y1363323D02*
Y1381694D01*
X706920Y1381894D01*
X723920D01*
X724068Y1381746D01*
Y1363432D01*
X723519Y1362883D01*
X707160D01*
X706720Y1363323D01*
G37*
G36*
G01X714300Y1283689D02*
G03I-464J0D01*
G37*
G36*
G01X763088Y84088D02*
G03I-720J0D01*
G37*
G36*
G01X766370Y87340D02*
G03I-512J0D01*
G37*
G36*
G01X770004Y103895D02*
G03I-720J0D01*
G37*
G36*
G01X767748Y91490D02*
G03I-720J0D01*
G37*
G36*
G01X770495Y107977D02*
G03I-720J0D01*
G37*
G36*
G01X853520Y288562D02*
G03I-720J0D01*
G37*
G36*
G01X939930Y1521960D02*
X922460D01*
X920580Y1523840D01*
Y1533740D01*
X921070Y1534230D01*
X939650D01*
X940510Y1533370D01*
Y1522540D01*
X939930Y1521960D01*
G37*
G36*
G01X1116829Y1711380D02*
G03I-491J0D01*
G37*
G36*
G01X1113546Y1718338D02*
G03I-491J0D01*
G37*
G36*
G01X1128269Y1399627D02*
Y1417998D01*
X1128469Y1418198D01*
X1145469D01*
X1145617Y1418050D01*
Y1399736D01*
X1145068Y1399187D01*
X1128709D01*
X1128269Y1399627D01*
G37*
G36*
G01X1166412D02*
Y1417998D01*
X1166612Y1418198D01*
X1183612D01*
X1183760Y1418050D01*
Y1399736D01*
X1183211Y1399187D01*
X1166852D01*
X1166412Y1399627D01*
G37*
G36*
G01X1285186Y1329191D02*
Y1339815D01*
X1285386Y1340015D01*
X1302386D01*
X1302534Y1339867D01*
Y1328834D01*
Y1326172D01*
X1301810Y1325448D01*
X1285720D01*
X1285186Y1325982D01*
Y1329191D01*
G37*
G36*
G01X1317210Y1305957D02*
Y1317017D01*
X1317410Y1317217D01*
X1334410D01*
X1334558Y1317069D01*
Y1306342D01*
Y1303330D01*
X1333666Y1302438D01*
X1317576D01*
X1317210Y1302804D01*
Y1305957D01*
G37*
G36*
G01X1349338Y1292478D02*
Y1303591D01*
X1349538Y1303791D01*
X1366538D01*
X1366686Y1303643D01*
Y1292665D01*
Y1289698D01*
X1366346Y1289358D01*
X1349676D01*
X1349338Y1289696D01*
Y1292478D01*
G37*
G36*
G01X1389654Y1170904D02*
X1389954Y1170604D01*
Y1152904D01*
X1389554Y1152504D01*
X1383754D01*
X1383254Y1153004D01*
Y1170204D01*
X1383954Y1170904D01*
X1389654D01*
G37*
G36*
G01X1381466Y1292008D02*
Y1303591D01*
X1381666Y1303791D01*
X1398666D01*
X1398814Y1303643D01*
Y1291974D01*
Y1290176D01*
X1397966Y1289328D01*
X1381946D01*
X1381466Y1289808D01*
Y1292008D01*
G37*
G36*
G01X1406527Y1171019D02*
X1414099D01*
X1414754Y1170364D01*
Y1152778D01*
X1414354Y1152378D01*
X1406168D01*
X1405154Y1153392D01*
Y1170219D01*
X1405954Y1171019D01*
X1406527D01*
G37*
G36*
G01X1413594Y1292500D02*
Y1303591D01*
X1413794Y1303791D01*
X1430794D01*
X1430942Y1303643D01*
Y1292631D01*
X1430918Y1292606D01*
Y1289940D01*
X1430376Y1289398D01*
X1414036D01*
X1413594Y1289840D01*
Y1292500D01*
G37*
G36*
G01X1434461Y937156D02*
X1447975D01*
X1448906Y936225D01*
Y929345D01*
X1447064Y927503D01*
X1434783D01*
X1433582Y928704D01*
Y936278D01*
X1434461Y937156D01*
G37*
G36*
G01X1430824Y1171019D02*
X1438797D01*
X1439069D01*
X1439724Y1170364D01*
Y1152814D01*
X1439324Y1152414D01*
X1430574D01*
X1430124Y1152864D01*
Y1170319D01*
X1430824Y1171019D01*
G37*
G36*
G01X1445722Y1292585D02*
Y1303591D01*
X1445922Y1303791D01*
X1462922D01*
X1463316Y1303397D01*
Y1289838D01*
X1462876Y1289398D01*
X1446106D01*
X1445722Y1289782D01*
Y1292584D01*
Y1292585D01*
G37*
G36*
G01X1477850Y1305743D02*
Y1317017D01*
X1478050Y1317217D01*
X1495050D01*
X1495198Y1317069D01*
Y1305798D01*
Y1303330D01*
X1494396Y1302528D01*
X1478366D01*
X1477850Y1303044D01*
Y1305743D01*
G37*
G36*
G01X1509978Y1328335D02*
Y1339815D01*
X1510178Y1340015D01*
X1527178D01*
X1527326Y1339867D01*
Y1328385D01*
Y1325948D01*
X1526616Y1325238D01*
X1510556D01*
X1509978Y1325816D01*
Y1328335D01*
G37*
G36*
G01X1622497Y611560D02*
X1638452D01*
X1639332Y610680D01*
Y595663D01*
X1638888Y595219D01*
X1622017D01*
X1621357Y595879D01*
Y610420D01*
X1622497Y611560D01*
G37*
G36*
G01X1627516Y629927D02*
X1613688D01*
X1613488Y630127D01*
Y646927D01*
X1613688Y647127D01*
X1627516D01*
X1627716Y646927D01*
Y630127D01*
X1627516Y629927D01*
G37*
G36*
G01Y663927D02*
X1613688D01*
X1613488Y664127D01*
Y680927D01*
X1613688Y681127D01*
X1627516D01*
X1627716Y680927D01*
Y664127D01*
X1627516Y663927D01*
G37*
G36*
G01Y697927D02*
X1613688D01*
X1613488Y698127D01*
Y714927D01*
X1613688Y715127D01*
X1627516D01*
X1627716Y714927D01*
Y698127D01*
X1627516Y697927D01*
G37*
G36*
G01X1629743Y1396919D02*
Y1415290D01*
X1629943Y1415490D01*
X1646943D01*
X1647091Y1415342D01*
Y1397028D01*
X1646542Y1396479D01*
X1630183D01*
X1629743Y1396919D01*
G37*
G36*
G01X1667886D02*
Y1415290D01*
X1668086Y1415490D01*
X1685086D01*
X1685234Y1415342D01*
Y1397028D01*
X1684685Y1396479D01*
X1668326D01*
X1667886Y1396919D01*
G37*
G36*
G01X1765120Y57462D02*
G03I-720J0D01*
G37*
G36*
G01X1760420Y57662D02*
G03I-720J0D01*
G37*
G36*
G01X1772324Y277369D02*
X1757764D01*
X1757044D01*
X1756834Y277159D01*
Y260059D01*
X1757614Y259279D01*
X1775234D01*
X1776514D01*
X1776784Y259549D01*
Y276869D01*
X1776345Y277308D01*
X1775325D01*
X1773935D01*
X1772385D01*
X1772324Y277369D01*
G37*
G54D100*
X158307Y1537521D03*
X156339D03*
X154370D03*
X152402D03*
Y1552481D03*
X154370D03*
X156339D03*
X158307D03*
X162244Y1537521D03*
X160276D03*
Y1552481D03*
X162244D03*
G54D110*
X211120Y578610D03*
Y612610D03*
Y646610D03*
X1642853Y641972D03*
Y675972D03*
Y709972D03*
G54D200*
X676508Y145866D03*
G54D101*
X149843Y1540080D03*
Y1542048D03*
Y1544017D03*
Y1545985D03*
Y1547954D03*
Y1549922D03*
X164803D03*
Y1547954D03*
Y1545985D03*
Y1544017D03*
Y1542048D03*
Y1540080D03*
G54D120*
X218862Y685948D03*
X1638111Y602634D03*
G54D111*
X211101Y588157D03*
Y622157D03*
Y656157D03*
X1642872Y632425D03*
Y666425D03*
Y700425D03*
G54D102*
X170014Y230928D03*
X166274D03*
X241354Y278685D03*
X232494D03*
X228754D03*
X240624Y311334D03*
X231764D03*
X228024D03*
X245094Y278685D03*
X257694D03*
X253954D03*
X244364Y311334D03*
X256964D03*
X253224D03*
X270294Y278685D03*
X266554D03*
X269564Y311334D03*
X265824D03*
X282894Y278685D03*
X279154D03*
X282164Y311334D03*
X278424D03*
X295494Y278685D03*
X291754D03*
X304354D03*
X294764Y311334D03*
X291024D03*
X303624D03*
X320694Y278685D03*
X316954D03*
X308094D03*
X319964Y311334D03*
X316224D03*
X307364D03*
X333294Y278685D03*
X329554D03*
X332564Y311334D03*
X328824D03*
X345894Y278685D03*
X342154D03*
X354754D03*
X345164Y311334D03*
X341424D03*
X354024D03*
X358494Y278685D03*
X371094D03*
X367354D03*
X370364Y311334D03*
X366624D03*
X357764D03*
X383694Y278685D03*
X379954D03*
X382964Y311334D03*
X379224D03*
X396294Y278685D03*
X392554D03*
X395564Y311334D03*
X391824D03*
X408894Y278685D03*
X405154D03*
X417754D03*
X408164Y311334D03*
X404424D03*
X417024D03*
X435654Y278715D03*
X431914D03*
X421494Y278685D03*
X420764Y311334D03*
X433364D03*
X429624D03*
X445964D03*
X442224D03*
X863450Y437462D03*
X867190D03*
X1453670Y281190D03*
X1449930D03*
G54D201*
X667551Y149803D03*
Y151771D03*
Y153740D03*
Y155708D03*
Y165551D03*
Y167519D03*
Y169488D03*
Y171456D03*
Y173425D03*
Y175393D03*
Y177362D03*
Y179330D03*
Y181299D03*
Y183268D03*
Y185236D03*
Y187204D03*
Y189173D03*
Y191142D03*
Y193110D03*
Y195079D03*
Y197047D03*
Y199016D03*
Y200984D03*
Y202953D03*
Y204921D03*
Y206890D03*
Y208858D03*
Y210827D03*
Y212795D03*
Y214764D03*
Y216732D03*
Y218701D03*
Y220669D03*
X697276Y148819D03*
Y150787D03*
Y152756D03*
Y154724D03*
Y156693D03*
Y166535D03*
Y168504D03*
Y170472D03*
Y172441D03*
Y174409D03*
Y176378D03*
Y178346D03*
Y180315D03*
Y182283D03*
Y184252D03*
Y186220D03*
Y188189D03*
Y190157D03*
Y192126D03*
Y194094D03*
Y196063D03*
Y198031D03*
Y200000D03*
Y201968D03*
Y203937D03*
Y205905D03*
Y207874D03*
Y209842D03*
Y211811D03*
Y213779D03*
Y215748D03*
Y217716D03*
Y219685D03*
Y221653D03*
G54D300*
X1633305Y638527D03*
Y672527D03*
Y706527D03*
G54D210*
X728402Y1576712D03*
X726630D03*
X724858D03*
X723087D03*
X721315D03*
Y1594330D03*
X723087D03*
X724858D03*
X726630D03*
X728402D03*
X742575Y1576712D03*
X740803D03*
X739032D03*
X737260D03*
X735488D03*
X733717D03*
X731945D03*
X730173D03*
Y1594330D03*
X731945D03*
X733717D03*
X735488D03*
X737260D03*
X739032D03*
X740803D03*
X742575D03*
G54D112*
X205439Y684016D03*
G54D10*
X27559Y87795D03*
X40708Y631890D03*
Y1368897D03*
X38346Y1420330D03*
X51181Y1714961D03*
X117932Y605380D03*
X373622Y87795D03*
X395670Y1714961D03*
X661023Y631890D03*
X707677Y1714961D03*
X763601Y605413D03*
X800787Y87795D03*
X931692Y757874D03*
Y1072834D03*
Y1387795D03*
X1045865Y87795D03*
X1094074Y605380D03*
X1155708Y1714961D03*
X1271260Y631890D03*
X1461805Y1714961D03*
X1499606Y87795D03*
X1739706Y605455D03*
X1816771Y631890D03*
Y1368897D03*
X1819208Y1420330D03*
X1806299Y1714961D03*
X1829921Y87795D03*
G54D103*
X180336Y593159D03*
Y578789D03*
X1831062Y251934D03*
Y237564D03*
G54D310*
X1766878Y222028D03*
Y266320D03*
G54D220*
X805690Y204724D03*
X1057658D03*
G54D211*
X726010Y1627615D03*
X722270D03*
X718530D03*
Y1638245D03*
X726010D03*
X726830Y1659065D03*
X719350D03*
X723090Y1668395D03*
X785400Y365335D03*
X781660Y374665D03*
X789140D03*
X803540Y372315D03*
X799800D03*
X796060D03*
Y382945D03*
X803540D03*
X824800Y434035D03*
X821060Y443365D03*
X842940Y430185D03*
X839200D03*
X835460D03*
X828540Y443365D03*
X835460Y440815D03*
X842940D03*
G54D301*
X1645030Y185952D03*
X1641290Y196188D03*
X1648770D03*
G54D130*
X272333Y104291D03*
X270364D03*
X268395D03*
X266427D03*
X264459D03*
X262490D03*
X260521D03*
X258553D03*
Y115315D03*
X260521D03*
X262490D03*
X264459D03*
X266427D03*
X268395D03*
X270364D03*
X272333D03*
X274301Y104291D03*
X467736Y302358D03*
Y309838D03*
X501136Y301658D03*
Y309138D03*
X695646Y108416D03*
X693677D03*
X691709D03*
Y119440D03*
X693677D03*
X695646D03*
X707457Y108416D03*
X705489D03*
X703520D03*
X701551D03*
X699583D03*
X697615D03*
Y119440D03*
X699583D03*
X701551D03*
X703520D03*
X705489D03*
X997487Y207742D03*
X1001423D03*
X1737611Y105415D03*
X1735642D03*
X1733674D03*
Y116439D03*
X1735642D03*
X1737611D03*
X1749422Y105415D03*
X1747454D03*
X1745485D03*
X1743516D03*
X1741548D03*
X1739580D03*
Y116439D03*
X1741548D03*
X1743516D03*
X1745485D03*
X1747454D03*
G54D202*
X676508Y224606D03*
G54D121*
X213303Y685948D03*
G36*
G01X253476Y197836D02*
G02Y172636I0J-12600D01*
G01X250331D01*
Y176926D01*
X253476D01*
G03Y193546I0J8310D01*
G01X247176D01*
G03Y176926I0J-8310D01*
G01X250321D01*
Y172636D01*
X247176D01*
G02Y197836I0J12600D01*
G01X253476D01*
G37*
G36*
G01X371587D02*
G02Y172636I0J-12600D01*
G01X368442D01*
Y176926D01*
X371587D01*
G03Y193546I0J8310D01*
G01X365287D01*
G03Y176926I0J-8310D01*
G01X368432D01*
Y172636D01*
X365287D01*
G02Y197836I0J12600D01*
G01X371587D01*
G37*
G54D311*
X1765429Y287264D03*
G54D212*
X746517Y126419D03*
X757935D03*
G54D113*
X205161Y691777D03*
X1651812Y596805D03*
G54D140*
X306757Y112844D03*
Y124262D03*
X1022484Y146805D03*
Y158223D03*
X1776878Y113968D03*
Y125386D03*
G54D20*
X25981Y387783D03*
Y394475D03*
X31099D03*
Y387783D03*
X593299Y152575D03*
Y145883D03*
X588181D03*
Y152575D03*
G54D221*
X793000Y1576714D03*
X791032D03*
X789063D03*
X787095D03*
X785126D03*
X783158D03*
Y1594332D03*
X785126D03*
X787095D03*
X789063D03*
X791032D03*
X793000D03*
X825158Y1576714D03*
Y1594332D03*
X835000Y1576714D03*
X833032D03*
X831063D03*
X829095D03*
X827126D03*
Y1594332D03*
X829095D03*
X831063D03*
X833032D03*
X835000D03*
X875032Y1576714D03*
X873063D03*
X871095D03*
X869126D03*
X867158D03*
Y1594332D03*
X869126D03*
X871095D03*
X873063D03*
X875032D03*
X877000Y1576714D03*
Y1594332D03*
X919000Y1576714D03*
X917032D03*
X915063D03*
X913095D03*
X911126D03*
X909158D03*
Y1594332D03*
X911126D03*
X913095D03*
X915063D03*
X917032D03*
X919000D03*
G54D131*
X260128Y109803D03*
X263671D03*
X267214D03*
X270758D03*
X693284Y113928D03*
X696827D03*
X700370D03*
X703914D03*
X1735249Y110927D03*
X1738792D03*
X1742335D03*
X1745879D03*
G54D230*
X837875Y525849D03*
X834922D03*
Y527817D03*
X837875Y529786D03*
Y527817D03*
G54D302*
X1651534Y604566D03*
G54D104*
X174685Y637367D03*
X174393Y668511D03*
X205159Y1430034D03*
X393067Y1354446D03*
X422833D03*
X453169D03*
X468443Y1379662D03*
X482543Y1353962D03*
X526478Y1439952D03*
X718638Y1429579D03*
X1077638Y133866D03*
X1178470Y1466363D03*
X1369208Y1353946D03*
X1398974D03*
X1429310D03*
X1444043Y1379362D03*
X1459076Y1353946D03*
X1502956Y1439530D03*
X1682882Y618174D03*
Y669109D03*
X1679944Y1463655D03*
X1769790Y194789D03*
X1799350D03*
X1836248Y269763D03*
Y299056D03*
G54D11*
G01X159474Y1317051D02*
Y1320753D01*
G01X155772D02*
X159474D01*
G01D02*
X163176D01*
G01X159474Y1328627D02*
Y1332329D01*
G01X155772Y1328627D02*
X159474D01*
G01D02*
X163176D01*
G01X184971Y430883D02*
X187371D01*
G01X183847Y1317076D02*
Y1320778D01*
G01X180145D02*
X183847D01*
G01D02*
X187549D01*
G01X183847Y1328652D02*
Y1332354D01*
G01X180145Y1328652D02*
X183847D01*
G01D02*
X187549D01*
G01X208247Y1317076D02*
Y1320778D01*
G01X204545D02*
X208247D01*
G01D02*
X211949D01*
G01X208247Y1328652D02*
Y1332354D01*
G01X204545Y1328652D02*
X208247D01*
G01D02*
X211949D01*
G01X271587Y579874D02*
X275289Y583576D01*
G01X271587Y587278D02*
X275289Y583576D01*
G01X271587Y604033D02*
X275289Y607735D01*
G01X271587Y611437D02*
X275289Y607735D01*
G01Y631889D02*
X272259Y634919D01*
X271570Y635680D01*
G01X271289Y627889D02*
X275289Y631889D01*
G01X271587Y652341D02*
X275289Y656043D01*
G01X266550Y672558D02*
X270252Y676260D01*
G01D02*
X273954Y672558D01*
G01X271587Y659745D02*
X275289Y656043D01*
G01X270252Y676260D02*
Y671025D01*
G01X266550Y696712D02*
X270252Y700414D01*
G01D02*
X273954Y704116D01*
G01X266550D02*
X270252Y700414D01*
G01D02*
X273954Y696712D01*
G01X275289Y583576D02*
X278991Y587278D01*
G01X275289Y583576D02*
X278991Y579874D01*
G01X275289Y607735D02*
X278991Y611437D01*
G01X275289Y607735D02*
X278991Y604033D01*
G01X275289Y631889D02*
X279289Y627889D01*
G01X275289Y631889D02*
X279289Y635889D01*
G01X275289Y656043D02*
X278991Y659745D01*
G01X275289Y656043D02*
X278991Y652341D01*
G01X316070Y66812D02*
X328020D01*
X329957Y68749D01*
Y93803D01*
X327957Y95803D01*
X320132D01*
G01D02*
X320178Y95849D01*
Y99837D01*
G01X313530Y213932D02*
Y211334D01*
X321202Y203662D01*
X339885D01*
X342285Y206062D01*
G01Y210534D02*
X342303Y210552D01*
X346203D01*
G01X342285Y206062D02*
Y210534D01*
G01X384195Y1239083D02*
X387897Y1242785D01*
G01D02*
X391599Y1246487D01*
G01X384195D02*
X387897Y1242785D01*
G01D02*
X391599Y1239083D01*
G01X379622Y1350844D02*
X383224Y1354446D01*
G01D02*
X386826Y1358048D01*
G01X379622D02*
X383224Y1354446D01*
G01D02*
X386826Y1350844D01*
G01X408595Y1239083D02*
X412297Y1242785D01*
G01D02*
X415999Y1246487D01*
G01X408595D02*
X412297Y1242785D01*
G01D02*
X415999Y1239083D01*
G01X409388Y1350844D02*
X412990Y1354446D01*
G01D02*
X416592Y1358048D01*
G01X409388D02*
X412990Y1354446D01*
G01D02*
X416592Y1350844D01*
G01X432917Y1239083D02*
X436619Y1242785D01*
G01D02*
X440321Y1246487D01*
G01X432917D02*
X436619Y1242785D01*
G01D02*
X440321Y1239083D01*
G01X439724Y1350844D02*
X443326Y1354446D01*
G01D02*
X446928Y1358048D01*
G01X439724D02*
X443326Y1354446D01*
G01D02*
X446928Y1350844D01*
G01X457317Y1239083D02*
X461019Y1242785D01*
G01D02*
X464721Y1246487D01*
G01X457317D02*
X461019Y1242785D01*
G01D02*
X464721Y1239083D01*
G01X469098Y1350360D02*
X472700Y1353962D01*
G01X469098Y1357564D02*
X472700Y1353962D01*
G01X454598Y1375660D02*
X458600Y1379662D01*
G01D02*
X462602Y1383664D01*
G01X454598D02*
X458600Y1379662D01*
G01D02*
X462602Y1375660D01*
G01X481717Y1239083D02*
X485419Y1242785D01*
G01D02*
X489121Y1246487D01*
G01X481717D02*
X485419Y1242785D01*
G01D02*
X489121Y1239083D01*
G01X472700Y1353962D02*
X476302Y1357564D01*
G01X472700Y1353962D02*
X476302Y1350360D01*
G01X485150Y1624942D02*
X485760D01*
X488225Y1627407D01*
Y1631038D01*
G01X523731Y1437205D02*
X526478Y1439952D01*
G01D02*
X529225Y1437205D01*
G01X526478Y1439952D02*
X529225Y1442699D01*
G01X523731D02*
X526478Y1439952D01*
G01X598693Y742072D02*
Y637401D01*
X546926Y585634D01*
Y574154D01*
X541722Y568950D01*
Y568054D01*
G01X669093Y1320778D02*
X673093D01*
G01D02*
X677093D01*
G01X673093Y1316778D02*
Y1320778D01*
G01Y1328652D02*
Y1332354D01*
G01X669391Y1328652D02*
X673093D01*
G01D02*
X676795D01*
G01X693466Y1320803D02*
X697466D01*
G01X693764Y1328677D02*
X697466D01*
G01Y1320803D02*
X701466D01*
G01X697466Y1316803D02*
Y1320803D01*
G01Y1328677D02*
Y1332379D01*
G01Y1328677D02*
X701168D01*
G01X854200Y138562D02*
X856931Y141293D01*
Y147679D01*
X853533Y151077D01*
X834582D01*
X831054Y154605D01*
X816197D01*
X803332Y167470D01*
X789610D01*
X765954Y191126D01*
Y222978D01*
X763760Y225172D01*
X721300D01*
X719720Y223592D01*
Y220142D01*
G01X717866Y1320803D02*
X721866D01*
G01D02*
X725866D01*
G01X721866Y1316803D02*
Y1320803D01*
G01Y1328677D02*
Y1332379D01*
G01X718164Y1328677D02*
X721866D01*
G01D02*
X725568D01*
G01X750239Y86682D02*
X761519D01*
X764286Y89449D01*
Y102795D01*
X767030Y105539D01*
Y117362D01*
X765736Y118656D01*
X764286D01*
Y119250D01*
X763786Y119750D01*
X755288D01*
X754710Y119172D01*
G01Y115290D02*
Y119172D01*
G01Y115290D02*
X754708Y115288D01*
G01X877058Y264232D02*
X889198D01*
X890843Y265877D01*
Y291347D01*
X888843Y293347D01*
X881018D01*
G01D02*
X880926Y293439D01*
Y295831D01*
X880949Y295854D01*
Y298573D01*
X881041Y298665D01*
G01X1076018Y289400D02*
Y312236D01*
X1067313Y320941D01*
X998805D01*
X993536Y315672D01*
X966750D01*
X965170Y317252D01*
X961864D01*
X960715Y316103D01*
X960220Y314907D01*
Y301994D01*
X945918Y287692D01*
X916449D01*
X894412Y309729D01*
Y329889D01*
X890422Y333879D01*
G01X1257672Y1351008D02*
X1206307D01*
X1198361Y1343062D01*
X998930D01*
X977080Y1321212D01*
Y1276368D01*
X998276Y1255172D01*
Y1168264D01*
X995557Y1165545D01*
Y802945D01*
X998970Y799532D01*
Y766210D01*
X1011735Y753445D01*
X1080941D01*
X1084637Y749749D01*
Y744635D01*
G01X1081282Y180937D02*
X1137562D01*
X1144575Y173924D01*
X1158363D01*
X1168515Y184076D01*
Y226640D01*
X1180847Y238972D01*
X1187013D01*
G01X1097098Y255660D02*
X1100800Y259362D01*
G01D02*
X1104502Y263064D01*
G01X1097098D02*
X1100800Y259362D01*
G01D02*
X1104502Y255660D01*
G01X1096998Y279960D02*
X1100700Y283662D01*
G01D02*
X1104402Y287364D01*
G01X1096998D02*
X1100700Y283662D01*
G01D02*
X1104402Y279960D01*
G01X1131100Y1353386D02*
Y1357088D01*
G01X1127398D02*
X1131100D01*
G01D02*
X1134802D01*
G01X1131100Y1364962D02*
Y1368664D01*
G01X1127398Y1364962D02*
X1131100D01*
G01D02*
X1134802D01*
G01X1151798Y1357088D02*
X1155500D01*
G01X1151798Y1364962D02*
X1155500D01*
G01Y1353386D02*
Y1357088D01*
G01D02*
X1159202D01*
G01X1155500Y1364962D02*
Y1368664D01*
G01Y1364962D02*
X1159202D01*
G01X1179900Y1353386D02*
Y1357088D01*
G01X1176198D02*
X1179900D01*
G01D02*
X1183602D01*
G01X1179900Y1364962D02*
Y1368664D01*
G01X1176198Y1364962D02*
X1179900D01*
G01D02*
X1183602D01*
G01X1195100Y217662D02*
Y217062D01*
X1195413Y216749D01*
Y212648D01*
G01X1207220Y207287D02*
X1211720D01*
G01X1203200Y202514D02*
X1205220D01*
X1207220Y204514D01*
Y207287D01*
G01X1426647Y329050D02*
X1404167Y351530D01*
X1205321D01*
X1204475Y350684D01*
G01X1278456Y96187D02*
Y98568D01*
X1278716Y98828D01*
G01X1271284Y108971D02*
X1273118Y107137D01*
X1274864D01*
G01X1602980Y560002D02*
X1547930D01*
X1496317Y611615D01*
Y621559D01*
X1477671Y640205D01*
X1382045D01*
X1364897Y657353D01*
Y685165D01*
X1363482Y686580D01*
X1360342D01*
X1358907Y685145D01*
Y681262D01*
G01X1360336Y1239083D02*
X1364038Y1242785D01*
G01D02*
X1367740Y1246487D01*
G01X1360336D02*
X1364038Y1242785D01*
G01D02*
X1367740Y1239083D01*
G01X1355363Y1349944D02*
X1359365Y1353946D01*
G01D02*
X1363367Y1357948D01*
G01X1355363D02*
X1359365Y1353946D01*
G01D02*
X1363367Y1349944D01*
G01X1384736Y1239083D02*
X1388438Y1242785D01*
G01D02*
X1392140Y1246487D01*
G01X1384736D02*
X1388438Y1242785D01*
G01D02*
X1392140Y1239083D01*
G01X1385129Y1349944D02*
X1389131Y1353946D01*
G01D02*
X1393133Y1357948D01*
G01X1385129D02*
X1389131Y1353946D01*
G01D02*
X1393133Y1349944D01*
G01X1409058Y1239083D02*
X1412760Y1242785D01*
G01D02*
X1416462Y1246487D01*
G01X1409058D02*
X1412760Y1242785D01*
G01D02*
X1416462Y1239083D01*
G01X1415465Y1349944D02*
X1419467Y1353946D01*
G01D02*
X1423469Y1357948D01*
G01X1415465D02*
X1419467Y1353946D01*
G01D02*
X1423469Y1349944D01*
G01X1433458Y1239083D02*
X1437160Y1242785D01*
G01D02*
X1440862Y1246487D01*
G01X1433458D02*
X1437160Y1242785D01*
G01D02*
X1440862Y1239083D01*
G01X1445231Y1349944D02*
X1449233Y1353946D01*
G01X1445231Y1357948D02*
X1449233Y1353946D01*
G01X1430198Y1375360D02*
X1434200Y1379362D01*
G01D02*
X1438202Y1383364D01*
G01X1430198D02*
X1434200Y1379362D01*
G01D02*
X1438202Y1375360D01*
G01X1460849Y343327D02*
X1457100Y347076D01*
Y360463D01*
X1458300Y361663D01*
G01X1457858Y1239083D02*
X1461560Y1242785D01*
G01D02*
X1465262Y1246487D01*
G01X1457858D02*
X1461560Y1242785D01*
G01D02*
X1465262Y1239083D01*
G01X1449233Y1353946D02*
X1453235Y1357948D01*
G01X1449233Y1353946D02*
X1453235Y1349944D01*
G01X1484805Y431972D02*
Y427577D01*
G01X1502956Y1439530D02*
X1505415Y1437071D01*
G01X1500497D02*
X1502956Y1439530D01*
G01X1500497Y1441989D02*
X1502956Y1439530D01*
G01D02*
X1505415Y1441989D01*
G01X1570675Y267857D02*
X1576164Y262368D01*
X1590732D01*
X1591914Y261186D01*
Y256244D01*
G01X1573298Y596060D02*
X1577000Y599762D01*
G01X1573298Y603464D02*
X1577000Y599762D01*
G01X1573298Y624262D02*
X1577000D01*
G01X1573298Y645060D02*
X1577000Y648762D01*
G01X1573298Y652464D02*
X1577000Y648762D01*
G01X1573298Y669460D02*
X1577000Y673162D01*
G01X1573298Y676864D02*
X1577000Y673162D01*
G01X1573298Y693960D02*
X1577000Y697662D01*
G01X1573298Y701364D02*
X1577000Y697662D01*
G01X1573298Y718460D02*
X1577000Y722162D01*
G01X1573298Y725864D02*
X1577000Y722162D01*
G01Y599762D02*
X1580702Y603464D01*
G01X1577000Y599762D02*
X1580702Y596060D01*
G01X1577000Y624262D02*
Y627964D01*
G01Y624262D02*
X1580702D01*
G01X1577000Y648762D02*
X1580702Y652464D01*
G01X1577000Y648762D02*
X1580702Y645060D01*
G01X1577000Y673162D02*
X1580702Y676864D01*
G01X1577000Y673162D02*
X1580702Y669460D01*
G01X1577000Y697662D02*
X1580702Y701364D01*
G01X1577000Y697662D02*
X1580702Y693960D01*
G01X1577000Y722162D02*
X1580702Y725864D01*
G01X1577000Y722162D02*
X1580702Y718460D01*
G01X1634259Y1350672D02*
Y1354374D01*
G01X1630557D02*
X1634259D01*
G01D02*
X1637961D01*
G01X1634259Y1362248D02*
Y1365950D01*
G01X1630557Y1362248D02*
X1634259D01*
G01D02*
X1637961D01*
G01X1654930Y1354399D02*
X1658632D01*
G01X1654930Y1362273D02*
X1658632D01*
G01Y1350697D02*
Y1354399D01*
G01D02*
X1662334D01*
G01X1658632Y1362273D02*
Y1365975D01*
G01Y1362273D02*
X1662334D01*
G01X1683032Y1350697D02*
Y1354399D01*
G01X1679330D02*
X1683032D01*
G01D02*
X1686734D01*
G01X1683032Y1362273D02*
Y1365975D01*
G01X1679330Y1362273D02*
X1683032D01*
G01D02*
X1686734D01*
G01X1769790Y194789D02*
X1773392D01*
G01X1766188D02*
X1769790D01*
G01Y191187D02*
Y194789D01*
G01Y201030D02*
Y204632D01*
G01D02*
Y208234D01*
G01X1766188Y204632D02*
X1769790D01*
G01D02*
X1773392D01*
G01X1781945Y68306D02*
X1792129D01*
X1792514Y68691D01*
G01X1785253Y96927D02*
X1791466D01*
X1794120Y94273D01*
Y70297D01*
X1792514Y68691D01*
G01X1785253Y96927D02*
Y100897D01*
X1785211Y100939D01*
G01X1799350Y194789D02*
X1802952D01*
G01X1795748D02*
X1799350D01*
G01Y191187D02*
Y194789D01*
X3010Y63308D03*
Y123308D03*
Y163308D03*
Y183308D03*
Y203308D03*
Y223308D03*
Y243308D03*
Y263308D03*
Y283308D03*
X14092Y287115D03*
X3010Y303308D03*
X10884Y321693D03*
Y341693D03*
Y361693D03*
Y381693D03*
Y401693D03*
Y421693D03*
Y441693D03*
Y461693D03*
Y481693D03*
Y501693D03*
Y521693D03*
Y661693D03*
Y681693D03*
Y701693D03*
Y721693D03*
Y741693D03*
Y781693D03*
Y801693D03*
Y821693D03*
Y841693D03*
Y861693D03*
Y881693D03*
Y901693D03*
Y921693D03*
Y941693D03*
Y961693D03*
Y981693D03*
Y1001693D03*
Y1021693D03*
Y1041693D03*
Y1061693D03*
Y1081693D03*
Y1101693D03*
Y1121693D03*
Y1141693D03*
Y1161693D03*
Y1181693D03*
Y1201693D03*
Y1221693D03*
Y1241693D03*
Y1401693D03*
Y1421693D03*
Y1441693D03*
Y1461693D03*
Y1481693D03*
Y1501693D03*
Y1521693D03*
Y1541693D03*
Y1561693D03*
Y1581693D03*
X17371Y49388D03*
X26054Y195148D03*
X16925Y203366D03*
X17061Y196368D03*
X25752Y203274D03*
X24720Y216362D03*
X24754Y220220D03*
X24720Y232362D03*
Y224362D03*
X24814Y236472D03*
X24720Y240362D03*
X22223Y388057D03*
X29509Y398132D03*
X29962Y401000D03*
X16420Y420662D03*
X26615Y670036D03*
X26500Y672862D03*
Y675862D03*
X24700Y765600D03*
X27300Y764200D03*
X27520Y1245162D03*
X20188Y1599396D03*
X28601Y1617541D03*
Y1637541D03*
Y1657541D03*
Y1677541D03*
X37371Y49388D03*
X33500Y200862D03*
X33670Y192862D03*
Y208362D03*
X30795Y213358D03*
X35600Y227380D03*
X33670Y232362D03*
X42500Y224409D03*
X30795Y227366D03*
X33670Y240362D03*
X41492Y290637D03*
X40000Y298707D03*
Y293392D03*
X36255Y304972D03*
X33105D03*
X42809Y360862D03*
X35740Y363337D03*
X39410Y384582D03*
X39226Y395346D03*
X33020Y382822D03*
X39320Y392269D03*
X40940Y387302D03*
X43020Y382942D03*
X41933Y395652D03*
X36524Y398013D03*
X45182Y426310D03*
X45960Y428806D03*
X30680Y438142D03*
X45034Y449106D03*
X38220Y589862D03*
Y592862D03*
Y595862D03*
X33020Y595232D03*
X32720Y598402D03*
X34790Y666595D03*
X31390D03*
X38470Y688122D03*
Y683122D03*
Y680622D03*
Y685622D03*
Y693122D03*
Y690622D03*
Y695622D03*
X34899Y711400D03*
X45700Y724100D03*
X45800Y726874D03*
X43841Y1248688D03*
X44833Y1659909D03*
Y1656759D03*
X48269Y1672771D03*
X54593Y19183D03*
X58379Y69340D03*
X60379Y66844D03*
Y71836D03*
X61157Y69340D03*
X60692Y87118D03*
X61470Y84622D03*
X54920Y185039D03*
Y177165D03*
X62020Y295952D03*
X62731Y305426D03*
X46834Y360862D03*
X55190D03*
X59322Y360702D03*
X51114Y360862D03*
X61340Y384362D03*
X61250Y396142D03*
X49250Y396332D03*
X49400Y384392D03*
X47618Y413113D03*
X62833Y410047D03*
X62812Y412708D03*
X53406Y402862D03*
X47619Y421155D03*
X62808Y418425D03*
X53825Y421746D03*
X50138Y426310D03*
X60393D03*
X62813Y415750D03*
X49360Y428806D03*
X61171D03*
X47619Y418655D03*
X47618Y415613D03*
X54762Y444993D03*
X53800Y435451D03*
X49990Y449106D03*
X48400Y586000D03*
X57595Y603476D03*
X59500Y738700D03*
X58658Y754145D03*
X55177Y1322328D03*
X56777Y1314165D03*
X55277Y1326068D03*
X56799Y1520094D03*
Y1524094D03*
Y1528094D03*
Y1532094D03*
Y1536094D03*
Y1544094D03*
Y1548094D03*
Y1552094D03*
Y1540094D03*
Y1556094D03*
Y1560094D03*
X54333Y1604359D03*
X59833D03*
X54333Y1613359D03*
X50333D03*
X46994Y1663165D03*
X54478Y1663669D03*
X54535Y1658447D03*
X50900Y1677775D03*
X57833Y1671809D03*
X53333Y1671862D03*
X65000Y1681900D03*
X58325Y1679275D03*
X69058Y3010D03*
X79047Y23978D03*
X74091D03*
X72091Y25974D03*
X73020Y37106D03*
Y28406D03*
X78269Y26474D03*
X74869D03*
X65937Y28403D03*
X73020Y48720D03*
Y40020D03*
X65937Y48720D03*
X67335Y69340D03*
X65335Y66844D03*
Y71836D03*
X64557Y69340D03*
X65648Y87118D03*
X71379Y72844D03*
Y77836D03*
X76335Y72844D03*
Y77836D03*
X78335Y75340D03*
X69379D03*
X72157D03*
X75557D03*
X64870Y84622D03*
X77165Y278798D03*
Y295798D03*
Y286262D03*
X65881Y305426D03*
X77165Y303262D03*
X63429Y360702D03*
X67681D03*
X77220Y379022D03*
Y381522D03*
X68020Y395222D03*
X71772Y421746D03*
X65349Y426310D03*
X75516Y420319D03*
Y424319D03*
X64571Y428806D03*
X75516Y436519D03*
X75490Y432519D03*
X68365Y443677D03*
X64150Y434972D03*
X63540Y438802D03*
X72610Y441262D03*
Y444762D03*
X72981Y466385D03*
X77000Y485362D03*
X74550Y487812D03*
X80300Y641862D03*
X80241Y659011D03*
X74340Y663422D03*
X80123Y664031D03*
X80135Y667933D03*
X74559Y667814D03*
X76365Y699244D03*
X78080Y701832D03*
X76565Y717949D03*
X72315Y717414D03*
X64325Y715674D03*
X63930Y739300D03*
X73759Y754726D03*
X73865Y763164D03*
X68315Y765664D03*
X73759Y759246D03*
X72485Y1304152D03*
X75485D03*
X78485D03*
X72485Y1307152D03*
X75485D03*
X69485Y1304152D03*
Y1307152D03*
X65600Y1318588D03*
X65240Y1326068D03*
X75485Y1316152D03*
X72485Y1313152D03*
Y1310152D03*
X75485Y1313152D03*
Y1310152D03*
X69485D03*
X69809Y1333918D03*
Y1331418D03*
Y1336418D03*
X72809Y1333918D03*
Y1331418D03*
Y1336418D03*
X75809Y1333918D03*
Y1331418D03*
Y1336418D03*
X72909Y1339938D03*
X79009Y1340238D03*
X75909Y1339938D03*
X73027Y1347925D03*
X73059Y1345138D03*
X72987Y1342535D03*
X75909Y1342438D03*
X79009Y1342738D03*
Y1345238D03*
X78977Y1348025D03*
X75859Y1348138D03*
Y1345138D03*
X75564Y1509952D03*
X78120Y1512936D03*
Y1515436D03*
Y1518836D03*
X76369Y1507456D03*
X78120Y1521336D03*
X76680Y1530482D03*
X72774Y1549669D03*
Y1546519D03*
X75922Y1564874D03*
Y1556474D03*
Y1558974D03*
Y1562374D03*
X73429Y1570008D03*
X78415D03*
X77618Y1572504D03*
X74218D03*
X66906Y1598324D03*
Y1603280D03*
X74100Y1613300D03*
X73832Y1689362D03*
X77833Y1689162D03*
X89058Y3010D03*
X81196Y17042D03*
Y22034D03*
X86152Y17042D03*
Y22034D03*
X95369Y17042D03*
Y22034D03*
X79196Y19538D03*
X88152D03*
X93369D03*
X85374D03*
X81974D03*
X88264Y23978D03*
X93220D03*
X86264Y25974D03*
X95220D03*
X81047D03*
X94279Y37106D03*
Y28406D03*
X87193Y37106D03*
Y28406D03*
X80106Y37106D03*
Y28406D03*
X92442Y26474D03*
X89042D03*
X94279Y48720D03*
Y40020D03*
X87193Y48720D03*
Y40020D03*
X80106Y48720D03*
Y40020D03*
X80379Y69340D03*
X89335D03*
X82379Y66844D03*
Y71836D03*
X87335Y66844D03*
Y71836D03*
X86557Y69340D03*
X83157D03*
X91379Y75340D03*
X93379Y72844D03*
Y77836D03*
X94157Y75340D03*
X86490Y200787D03*
Y208661D03*
X85960Y224409D03*
X85788Y240157D03*
X90700Y282762D03*
X87620Y285321D03*
X87845Y278798D03*
Y295798D03*
X90700Y300262D03*
X87820Y302821D03*
X87654Y376026D03*
X87520Y386502D03*
Y395865D03*
Y391391D03*
Y382219D03*
X85826Y424319D03*
Y420319D03*
Y428319D03*
X84410Y438519D03*
X83320Y445212D03*
X82661Y449604D03*
X94439Y450081D03*
X81505Y447377D03*
X79400Y482862D03*
X94811Y510173D03*
X91027Y643276D03*
X89859Y628246D03*
X86459D03*
X80460Y655672D03*
X83100Y649762D03*
X82961Y657111D03*
X95725Y654540D03*
X95860Y659622D03*
X83165Y652564D03*
X91078Y649584D03*
X83208Y646436D03*
X87565Y670441D03*
X83250Y665428D03*
X84470Y668702D03*
X86433Y688160D03*
X81285Y689804D03*
X84035Y697604D03*
X94473Y698926D03*
X79451Y699517D03*
X93547Y692260D03*
X83004Y705141D03*
X97295Y699786D03*
X82735Y717949D03*
X87865Y714394D03*
X85165D03*
X81225Y715854D03*
X79635Y717949D03*
X85835Y718049D03*
X85095Y722164D03*
X95849Y716358D03*
X91610Y721414D03*
X82357Y737803D03*
X84623Y741249D03*
X93295Y762019D03*
X81966Y759246D03*
X85877Y759275D03*
X93485Y1304152D03*
X87485D03*
X90485D03*
X93485Y1307152D03*
X84485Y1304152D03*
X81485D03*
X93485Y1318152D03*
Y1315652D03*
Y1310152D03*
Y1313152D03*
X94209Y1337738D03*
X81809Y1340238D03*
X84809D03*
X87809D03*
X90809D03*
X94209D03*
X84809Y1345238D03*
X81809Y1342738D03*
X84809D03*
X81809Y1348238D03*
Y1345238D03*
X84809Y1348238D03*
X87809D03*
Y1345238D03*
Y1342738D03*
X94209D03*
Y1348238D03*
Y1345238D03*
X90809Y1348238D03*
Y1345238D03*
Y1342738D03*
X88520Y1484482D03*
X92071Y1492888D03*
X88520Y1491482D03*
Y1487982D03*
Y1494982D03*
X80649Y1509944D03*
X84274Y1517619D03*
X93544Y1510099D03*
X88459Y1510107D03*
X90998Y1513037D03*
Y1518937D03*
Y1515537D03*
X89264Y1507611D03*
X92664D03*
X79769Y1507456D03*
X90998Y1521437D03*
X81038Y1536899D03*
X91538Y1539399D03*
X87500Y1567069D03*
X91500D03*
X84048Y1578008D03*
X90713Y1581852D03*
Y1585852D03*
Y1589852D03*
Y1593867D03*
Y1597867D03*
X81008Y1589872D03*
X90788Y1611821D03*
Y1605867D03*
Y1615821D03*
Y1601867D03*
X81900Y1613300D03*
X85800D03*
X90788Y1623821D03*
X84700Y1627000D03*
X90698Y1630362D03*
X90788Y1619821D03*
X90698Y1638362D03*
Y1634362D03*
Y1642362D03*
X90407Y1656672D03*
X88333Y1661334D03*
X86245Y1690362D03*
X81833Y1689162D03*
X94220Y1686622D03*
X86245Y1694362D03*
X96420Y1693803D03*
X86030Y1683092D03*
X92895Y1737108D03*
X109058Y3010D03*
X100325Y17042D03*
Y22034D03*
X109542Y17042D03*
Y22034D03*
X102325Y19538D03*
X107542D03*
X99547D03*
X110320D03*
X96147D03*
X102437Y23978D03*
X107393D03*
X100437Y25974D03*
X109393D03*
X108453Y37106D03*
Y28406D03*
X101366Y37106D03*
Y28406D03*
X106615Y26474D03*
X103215D03*
X108453Y48720D03*
Y40020D03*
X101366Y48720D03*
Y40020D03*
X102379Y69340D03*
X111335D03*
X104379Y66844D03*
Y71836D03*
X109335Y66844D03*
Y71836D03*
X108557Y69340D03*
X105157D03*
X98335Y72844D03*
Y77836D03*
X100335Y75340D03*
X97557D03*
X113490Y216596D03*
X113400Y232128D03*
X110937Y285495D03*
Y302854D03*
X107200Y393562D03*
X107301Y388071D03*
X104220Y400862D03*
X101720D03*
X101317Y431727D03*
X113597Y488434D03*
X102060Y493578D03*
X107419Y487807D03*
X104875Y490980D03*
X102152Y509374D03*
X102334Y500628D03*
X102359Y497374D03*
X102384Y505374D03*
X112480Y507792D03*
X110689Y498271D03*
X110464Y505374D03*
X102152Y513374D03*
X111087Y520052D03*
X101983Y518100D03*
X99880Y526300D03*
X110060Y515279D03*
X99773Y515606D03*
X105587Y520727D03*
X106110Y633732D03*
X107489Y630917D03*
X110374Y630879D03*
X102269Y634466D03*
X108909Y654926D03*
X102909Y648926D03*
Y642926D03*
Y655102D03*
X108909Y642926D03*
X107045Y661917D03*
X99021Y663732D03*
X103397Y667272D03*
X102120Y688650D03*
X102060Y692100D03*
X102420Y697262D03*
X98134Y722501D03*
X96626Y736187D03*
X110527Y758869D03*
X108465Y1304292D03*
Y1307292D03*
X105475Y1304222D03*
Y1307222D03*
X102485Y1304152D03*
X99485D03*
X96485D03*
X102485Y1307152D03*
X99485D03*
X96485D03*
X108465Y1318292D03*
Y1310292D03*
Y1313292D03*
Y1315792D03*
X105475Y1318222D03*
Y1310222D03*
Y1313222D03*
Y1315722D03*
X99485Y1318152D03*
X96485D03*
Y1315652D03*
Y1310152D03*
Y1313152D03*
X99485Y1310152D03*
Y1313152D03*
Y1315652D03*
X102485Y1318152D03*
Y1310152D03*
Y1313152D03*
Y1315652D03*
X96809Y1340238D03*
Y1345238D03*
Y1348238D03*
Y1342738D03*
X99274Y1526019D03*
Y1529169D03*
X96570Y1546187D03*
X99716Y1567878D03*
X99750Y1559478D03*
Y1565378D03*
Y1561978D03*
X96251Y1577532D03*
X107451Y1574704D03*
X100451D03*
X103902Y1584337D03*
X102251Y1576504D03*
X105651D03*
X104318Y1592304D03*
Y1589352D03*
X100620Y1596367D03*
X104318Y1603690D03*
X110200Y1605200D03*
X101500Y1604400D03*
X100020Y1615821D03*
X98738Y1605867D03*
X104318Y1622380D03*
X104400Y1632385D03*
X104430Y1628012D03*
X104318Y1641075D03*
Y1637862D03*
X99600Y1668332D03*
X99645Y1663217D03*
X99980Y1685362D03*
Y1696052D03*
Y1687921D03*
Y1698921D03*
X114498Y17042D03*
Y22034D03*
X123716Y17042D03*
Y22034D03*
X116498Y19538D03*
X121716D03*
X113720D03*
X127894D03*
X124494D03*
X121567Y23978D03*
X116611D03*
X114611Y25974D03*
X123567D03*
X122626Y37106D03*
Y28406D03*
X115539Y37106D03*
Y28406D03*
X120789Y26474D03*
X117389D03*
X122626Y48720D03*
Y40020D03*
X115539Y48720D03*
Y40020D03*
X124379Y69340D03*
X126379Y66844D03*
Y71836D03*
X127157Y69340D03*
X115379Y72844D03*
Y77836D03*
X120335Y72844D03*
Y77836D03*
X122335Y75340D03*
X113379D03*
X116157D03*
X119557D03*
X115850Y186362D03*
X122000Y207362D03*
X116920Y207462D03*
X114087Y285495D03*
X118920Y278875D03*
X114087Y302854D03*
X119220Y306236D03*
X119920Y379362D03*
X125007Y392071D03*
Y388071D03*
Y384071D03*
Y396071D03*
X119457Y392071D03*
Y388071D03*
X114507Y404571D03*
X117597Y488434D03*
X127206Y480216D03*
X125070Y486736D03*
X125013Y491829D03*
X124124Y495883D03*
X116171Y485041D03*
X126225Y504368D03*
X120225D03*
Y510368D03*
X112483Y510637D03*
X116411Y497707D03*
X126225Y516368D03*
X120225D03*
X118652Y528860D03*
X129762Y531942D03*
X115793Y528188D03*
X112393D03*
X123257Y547506D03*
X119087D03*
X115060D03*
X111920Y632922D03*
X114540Y633032D03*
X117750Y633232D03*
X120440Y633347D03*
X121400Y638062D03*
X127313Y649765D03*
X114909Y654926D03*
Y648926D03*
Y642926D03*
X125890Y644163D03*
X122329Y654660D03*
X122280Y651934D03*
X124431Y649570D03*
X114021Y669409D03*
X118021D03*
X127738Y659226D03*
X122575Y671930D03*
X118019Y661371D03*
X124737Y735726D03*
X118737D03*
X121737D03*
Y738726D03*
X118737D03*
X124737D03*
X123220Y1324662D03*
X120220D03*
X120267Y1327697D03*
X127366Y1535855D03*
X112749Y1524594D03*
Y1532594D03*
Y1528594D03*
X127366Y1541874D03*
Y1547935D03*
X112749Y1540594D03*
Y1544594D03*
Y1548594D03*
Y1536594D03*
Y1552594D03*
Y1564594D03*
Y1560594D03*
Y1556594D03*
X117707Y1553759D03*
X116798Y1586288D03*
Y1598572D03*
X125033Y1589352D03*
X116798D03*
X123230Y1597350D03*
X116798Y1617262D03*
X119500Y1622380D03*
X116798Y1635303D03*
X117220Y1680287D03*
X127195Y1670362D03*
X124795Y1681846D03*
X128195Y1674362D03*
X117795Y1698862D03*
X127195Y1688362D03*
Y1692362D03*
X114645Y1698862D03*
X117220Y1683437D03*
X127195Y1696362D03*
Y1708362D03*
Y1700362D03*
Y1704362D03*
X117255Y1730422D03*
X125082Y1727092D03*
X123394Y1723472D03*
X117426Y1726622D03*
X125720Y1719262D03*
X112895Y1737108D03*
X129058Y3010D03*
X128672Y17042D03*
Y22034D03*
X130672Y19538D03*
X129713Y37106D03*
Y28406D03*
Y48720D03*
Y40020D03*
X133335Y69340D03*
X131335Y66844D03*
Y71836D03*
X130557Y69340D03*
X137379Y72844D03*
Y77836D03*
X142335Y72844D03*
Y77836D03*
X135379Y75340D03*
X138157D03*
X141557D03*
X136301Y179095D03*
X141520Y181462D03*
X139720Y179162D03*
X143470Y184012D03*
X143340Y204622D03*
X133590Y212382D03*
X129394Y278875D03*
X129375Y274800D03*
X129394Y306236D03*
X140974Y396885D03*
X135220Y397071D03*
X140974Y401885D03*
Y399385D03*
X132490Y420062D03*
X138042Y480238D03*
X132833D03*
X142166Y490835D03*
X136982Y497090D03*
X131737Y496295D03*
X135006Y487753D03*
X131295Y487822D03*
X132225Y504368D03*
Y510368D03*
X141325Y503806D03*
X141462Y507600D03*
X141329Y510487D03*
X141220Y498810D03*
X138878Y512550D03*
X138408Y507366D03*
X132401Y516368D03*
X139153Y516453D03*
X132600Y537072D03*
Y540472D03*
X130057Y636103D03*
X133467Y634531D03*
X131740Y640103D03*
X130067Y650213D03*
X134205Y643603D03*
X131600Y646861D03*
X128193Y662015D03*
X128275Y665515D03*
X129600Y669400D03*
X131330Y665740D03*
X142960Y690807D03*
X140460D03*
X142754Y698811D03*
X140254D03*
X142778Y706835D03*
X140278D03*
X140326Y721660D03*
X142826D03*
X132967Y760525D03*
X141470Y1359100D03*
X140142Y1392545D03*
Y1396275D03*
X144263Y1412275D03*
X129670Y1563160D03*
X140104Y1560136D03*
X129627Y1556360D03*
X129586Y1553759D03*
X129813Y1604367D03*
X130533Y1622321D03*
X129533Y1637862D03*
X137420Y1708362D03*
X144520Y1717562D03*
X138492Y1717592D03*
X139080Y1731398D03*
X141642Y1717592D03*
X134557Y1722778D03*
X137852Y1726572D03*
X132895Y1737108D03*
X149058Y3010D03*
X159582Y17042D03*
Y22034D03*
X157582Y19538D03*
X160360D03*
X152477Y23978D03*
X157433D03*
X150477Y25974D03*
X159433D03*
X158492Y37106D03*
Y28406D03*
X151405Y37106D03*
Y28406D03*
X156655Y26474D03*
X153255D03*
X147924Y28258D03*
X158492Y48720D03*
Y40020D03*
X151405Y48720D03*
Y40020D03*
X148784Y48720D03*
X146379Y69340D03*
X155335D03*
X148379Y66844D03*
Y71836D03*
X153335Y66844D03*
Y71836D03*
X152557Y69340D03*
X149157D03*
X158583Y75340D03*
X144335D03*
X147901Y188852D03*
X145720Y186462D03*
Y202862D03*
Y206362D03*
X156670Y344542D03*
X159170D03*
X154220Y375682D03*
X158110Y376172D03*
X160090Y391170D03*
Y397470D03*
X149371Y423383D03*
Y419383D03*
Y427383D03*
Y439383D03*
Y431383D03*
Y435383D03*
Y443383D03*
X152826Y439397D03*
Y434362D03*
X159125Y448664D03*
X156306Y449045D03*
X153360Y449112D03*
X152171Y490615D03*
X149557Y494353D03*
X150113Y488487D03*
X161267Y503143D03*
X149472Y502810D03*
X149486Y498810D03*
X149472Y506810D03*
X160000Y510052D03*
X152470Y495383D03*
X151378Y526924D03*
X149518Y522810D03*
X149512Y514810D03*
X150800Y512021D03*
X153737Y514893D03*
X149504Y519881D03*
X154647Y521783D03*
X147141Y698811D03*
X147435Y690807D03*
X149861Y698831D03*
X150155Y690807D03*
X156685Y706836D03*
X153965Y706816D03*
X153879Y721660D03*
X156469D03*
X147031Y706835D03*
X149621D03*
X149669Y721660D03*
X147079D03*
X150877Y757969D03*
X151277Y1339183D03*
X153877D03*
X156477D03*
X156417Y1336343D03*
X151217Y1336393D03*
X153817D03*
X156417Y1333843D03*
X151217Y1333893D03*
X153817D03*
X151277Y1346883D03*
X153877D03*
X151277Y1349383D03*
X153877D03*
X156477Y1346883D03*
Y1349383D03*
Y1344383D03*
X151277D03*
X153877D03*
X156477Y1341883D03*
X151277D03*
X153877D03*
X154477Y1360797D03*
X159898Y1360790D03*
X148663Y1378607D03*
X151163D03*
Y1383807D03*
Y1381207D03*
X148663Y1386407D03*
X151163D03*
X148663Y1383807D03*
Y1381207D03*
X147307Y1404745D03*
X149568Y1395145D03*
Y1397695D03*
X152684Y1403451D03*
X152806Y1414175D03*
X157490Y1421454D03*
X154990D03*
X159858Y1409361D03*
X155858Y1406669D03*
Y1409390D03*
X157530Y1432124D03*
X155030D03*
X157530Y1424124D03*
X155030D03*
X157530Y1429124D03*
X155030Y1426624D03*
Y1429124D03*
X157530Y1426624D03*
Y1435124D03*
X155030D03*
X157530Y1437754D03*
X155030D03*
X144748Y1514878D03*
X149728D03*
X146390Y1504240D03*
X145538Y1517374D03*
X148938D03*
X153600Y1505600D03*
X154581Y1520981D03*
X158570D03*
X153271Y1540961D03*
X153138Y1549032D03*
X147067Y1545985D03*
X150502Y1572021D03*
X145522D03*
X159107Y1571364D03*
X157441Y1581932D03*
X146312Y1569525D03*
X149712D03*
X152026Y1614138D03*
X158335Y1614452D03*
X155180Y1619872D03*
X156070Y1695702D03*
X144854Y1702389D03*
X154803Y1708532D03*
X145745Y1712362D03*
X161310Y1708022D03*
X148145Y1701862D03*
X155145Y1713517D03*
X155100Y1723262D03*
X152895Y1737108D03*
X169058Y3010D03*
X164538Y17042D03*
Y22034D03*
X173755Y17042D03*
Y22034D03*
X166538Y19538D03*
X171755D03*
X163760D03*
X174533D03*
X166650Y23978D03*
X171606D03*
X164650Y25974D03*
X173606D03*
X172665Y37106D03*
Y28406D03*
X165579Y37106D03*
Y28406D03*
X170828Y26474D03*
X167428D03*
X172665Y48720D03*
Y40020D03*
X165579Y48720D03*
Y40020D03*
X169583Y69340D03*
X171583Y66844D03*
Y71836D03*
X176539Y66844D03*
Y71836D03*
X175761Y69340D03*
X172361D03*
X165539Y72844D03*
X160583D03*
Y77836D03*
X165539D03*
X167539Y75340D03*
X161361D03*
X164761D03*
X174327Y230928D03*
X164830Y344542D03*
X161670D03*
X173275Y393497D03*
X171180Y401885D03*
X163900Y409362D03*
X164000Y415362D03*
X163926Y425383D03*
X164000Y420362D03*
X172507Y417205D03*
X163926Y430883D03*
Y443319D03*
Y439397D03*
Y435383D03*
X175640Y453779D03*
X178546Y453806D03*
X172632Y454095D03*
X163132Y493299D03*
X165176Y500782D03*
X162750Y512502D03*
X166986Y575918D03*
X176393Y575189D03*
X173793D03*
X176393Y572689D03*
X173793D03*
X171293D03*
Y575189D03*
X173793Y577790D03*
X171293D03*
X176393D03*
X176651Y596883D03*
Y594163D03*
X173878Y597027D03*
Y594307D03*
X176651Y599603D03*
X173878Y599747D03*
X161126Y721660D03*
X161078Y706835D03*
X163626Y721660D03*
X163578Y706835D03*
X170877Y1333783D03*
Y1336383D03*
X176077Y1333783D03*
X173477D03*
X176077Y1336383D03*
X173477D03*
X170907Y1339233D03*
X176107D03*
X173507D03*
X170877Y1341883D03*
X176077D03*
X173477D03*
Y1349383D03*
Y1346883D03*
Y1344383D03*
X176077D03*
Y1346883D03*
Y1349383D03*
X170877D03*
Y1346883D03*
Y1344383D03*
X162398Y1360790D03*
X164898D03*
X172807Y1360797D03*
X174932Y1378797D03*
Y1381397D03*
X176358Y1403669D03*
X176258Y1400669D03*
X173892Y1402749D03*
Y1405649D03*
X162693Y1411529D03*
X160490Y1421454D03*
X164000Y1408862D03*
X162257Y1406594D03*
X160530Y1432124D03*
Y1424124D03*
Y1429124D03*
Y1426624D03*
Y1435124D03*
Y1437754D03*
X171262Y1443390D03*
X165500Y1440362D03*
X173727Y1452134D03*
Y1448734D03*
X170570Y1509250D03*
X164710Y1518014D03*
X168110D03*
X168900Y1520510D03*
X163920D03*
X161321Y1540858D03*
X161374Y1549073D03*
X166476Y1572464D03*
X171456D03*
X173331Y1579399D03*
X167266Y1569968D03*
X170666D03*
X172099Y1588141D03*
X166529Y1707678D03*
X164920Y1712017D03*
X163060Y1717017D03*
X166661Y1721211D03*
X178226Y1726517D03*
X172962Y1721234D03*
X169777Y1726517D03*
X178142Y1720652D03*
X172895Y1737108D03*
X166761Y1732967D03*
X189058Y3010D03*
X178711Y17042D03*
Y22034D03*
X180711Y19538D03*
X177933D03*
X179752Y37106D03*
Y28406D03*
X186120Y24162D03*
X188620D03*
X179752Y48720D03*
Y40020D03*
X191583Y69340D03*
X178539D03*
X182583Y72844D03*
Y77836D03*
X187539Y72844D03*
Y77836D03*
X189539Y75340D03*
X180583D03*
X183361D03*
X186761D03*
X186457Y393071D03*
Y385071D03*
Y389071D03*
X190880Y383012D03*
Y387162D03*
Y391082D03*
X178375Y396571D03*
X186457Y405071D03*
X192220Y408662D03*
Y412162D03*
X184490Y402203D03*
X181845Y401071D03*
X177871Y421383D03*
Y425383D03*
X191305Y430216D03*
X187371Y425383D03*
X187532Y421387D03*
X187371Y430883D03*
X177871D03*
Y443383D03*
X187371D03*
X180740Y437562D03*
X184550Y435712D03*
X187371Y440742D03*
X194440Y433895D03*
Y439565D03*
X188221Y454048D03*
X184147Y447078D03*
X187371Y447172D03*
X177871D03*
X181994Y453932D03*
X180640Y447172D03*
X185211Y453942D03*
X185191Y502439D03*
X187490Y568752D03*
X186793Y575189D03*
X184193D03*
X186793Y572689D03*
X184193D03*
X181593Y575189D03*
X178993D03*
X181593Y572689D03*
X178993D03*
X189293Y575189D03*
X186793Y577790D03*
X184193D03*
X189293D03*
X181593D03*
X178993D03*
X181651Y596883D03*
X179151D03*
X186796Y594195D03*
Y596915D03*
X184151Y596883D03*
X179151Y594163D03*
X181651D03*
X184151D03*
X181651Y599603D03*
X179151D03*
X186796Y599635D03*
X184151Y599603D03*
X190977Y669718D03*
X190800Y675662D03*
X191976Y684326D03*
X189800Y705062D03*
X186720Y737862D03*
X180720D03*
X183720D03*
Y734862D03*
X180720D03*
X186720D03*
X185835Y757057D03*
X188978Y756855D03*
X191602Y756839D03*
X189377Y1333783D03*
X191977D03*
X189377Y1336383D03*
X191977D03*
X191947Y1339263D03*
X189347D03*
X189377Y1349383D03*
X191977D03*
X189377Y1346883D03*
X191977D03*
Y1344383D03*
X189377D03*
X191977Y1341883D03*
X189377D03*
X184215Y1361072D03*
X181403Y1361115D03*
X192620Y1360797D03*
X188233Y1387027D03*
Y1379227D03*
Y1381827D03*
Y1384427D03*
X183283Y1387987D03*
X185633Y1387027D03*
X180672Y1387987D03*
X185633Y1379227D03*
X180672Y1380187D03*
X183283D03*
X177532Y1378797D03*
X185633Y1384427D03*
Y1381827D03*
X180672Y1382787D03*
Y1385387D03*
X183283Y1382787D03*
Y1385387D03*
X177421Y1383997D03*
X177532Y1381397D03*
X182653Y1404535D03*
X187711Y1395170D03*
Y1397670D03*
X190827Y1403451D03*
X180977Y1396173D03*
X178458Y1399269D03*
Y1402169D03*
Y1405069D03*
X192767Y1413725D03*
X185643Y1413945D03*
X188211Y1406691D03*
X186165Y1422589D03*
X183135Y1419784D03*
X180510Y1420258D03*
X177510D03*
X186135Y1419784D03*
X183165Y1422589D03*
X177510Y1423278D03*
X180510D03*
X183075Y1430424D03*
Y1425424D03*
Y1427924D03*
X186075Y1430424D03*
Y1425424D03*
Y1427924D03*
X183075Y1432924D03*
X186075D03*
X185895Y1535462D03*
Y1539723D03*
Y1544029D03*
Y1548487D03*
Y1552875D03*
X192600Y1557360D03*
X185895Y1557875D03*
X189600Y1566300D03*
X187400Y1568132D03*
X176793Y1585173D03*
X192529Y1728947D03*
X183822Y1720517D03*
X187542Y1729092D03*
X193293Y1722197D03*
X188794Y1725092D03*
X192895Y1737108D03*
X209058Y3010D03*
X203716Y17042D03*
Y22034D03*
X208672Y17042D03*
Y22034D03*
X201716Y19538D03*
X207894D03*
X204494D03*
X201567Y23978D03*
X196611D03*
X194611Y25974D03*
X203567D03*
X208784D03*
X202626Y28406D03*
Y37106D03*
X195539Y28406D03*
Y37106D03*
X200789Y26474D03*
X197389D03*
X202626Y40020D03*
Y48720D03*
X195539Y40020D03*
Y48720D03*
X200539Y69340D03*
X193583Y66844D03*
Y71836D03*
X198539Y66844D03*
Y71836D03*
X197761Y69340D03*
X194361D03*
X204717Y72844D03*
Y77836D03*
X202717Y75340D03*
X205495D03*
X208895D03*
X195050Y412055D03*
X199047Y428626D03*
X199139Y422882D03*
X199149Y425755D03*
Y420255D03*
Y414755D03*
X204699Y423242D03*
Y428742D03*
X195050Y417465D03*
X199149Y436755D03*
Y442255D03*
Y431255D03*
X196215Y447565D03*
X199149Y453255D03*
Y447755D03*
X197650Y455712D03*
X199149Y468255D03*
X208200Y493510D03*
X196526Y567825D03*
X202338Y568746D03*
X201392Y574271D03*
X198336D03*
X204610Y571097D03*
X195888Y581071D03*
X194515Y583433D03*
X199164Y582481D03*
X200654Y578271D03*
X201622Y581009D03*
X202262Y592305D03*
X205162D03*
X197423Y601496D03*
X194059Y604901D03*
X202338Y602746D03*
X201392Y608271D03*
X198336D03*
X203892Y594471D03*
X202492Y596571D03*
X208292D03*
X206892Y594371D03*
X205392Y596571D03*
X204610Y605097D03*
X195888Y615071D03*
X194515Y617433D03*
X199164Y616481D03*
X200654Y612271D03*
X201622Y615009D03*
X194059Y638901D03*
X197423Y635496D03*
X202338Y636746D03*
X203892Y628471D03*
X202492Y630571D03*
X202262Y626305D03*
X208292Y630571D03*
X206892Y628371D03*
X205162Y626305D03*
X205392Y630571D03*
X204610Y639097D03*
X194515Y651433D03*
X195888Y649071D03*
X201392Y642271D03*
X199164Y650481D03*
X200654Y646271D03*
X201622Y649009D03*
X198336Y642271D03*
X205320Y667562D03*
X207620Y671262D03*
X198420Y672662D03*
X198495Y669487D03*
X205392Y664571D03*
X205162Y660305D03*
X206892Y662371D03*
X202262Y660305D03*
X202492Y664571D03*
X203892Y662471D03*
X208292Y664571D03*
X194858Y684348D03*
X196049Y678195D03*
X194196Y687061D03*
X200018Y677492D03*
X193332Y678195D03*
X207129Y690027D03*
X203199Y690006D03*
X197086Y686326D03*
X203179Y693626D03*
X207140Y693636D03*
X195735Y696469D03*
X198235Y698969D03*
Y696469D03*
X200735Y698969D03*
Y696469D03*
X207140Y738462D03*
X205220Y736562D03*
X201220Y736662D03*
X203660Y731802D03*
X199720Y732862D03*
X206720Y731862D03*
X199220Y739362D03*
X207602Y756855D03*
X199602D03*
X195602Y756839D03*
X203602Y756855D03*
X208977Y1336383D03*
Y1333783D03*
X194577D03*
Y1336383D03*
X209007Y1339263D03*
X194547D03*
X208977Y1341883D03*
X194577Y1349383D03*
Y1346883D03*
Y1344383D03*
X208977D03*
Y1346883D03*
Y1349383D03*
X194577Y1341883D03*
X203441Y1360790D03*
X198041D03*
X200941D03*
X201071Y1412173D03*
X198001Y1409361D03*
X193941Y1407029D03*
X200797Y1409605D03*
X200492Y1406686D03*
X193941Y1409750D03*
X195966Y1542863D03*
X207229Y1631181D03*
X203120Y1624782D03*
X208115Y1624217D03*
X193410Y1711606D03*
X205582Y1700867D03*
X195590Y1714517D03*
X196010Y1709017D03*
X208295Y1703362D03*
X196443Y1722197D03*
X199050Y1726431D03*
X204600Y1733022D03*
X217889Y17042D03*
Y22034D03*
X222845Y17042D03*
Y22034D03*
X210672Y19538D03*
X215889D03*
X224845D03*
X222067D03*
X218667D03*
X215740Y23978D03*
X210784D03*
X217740Y25974D03*
X223886Y28406D03*
Y37106D03*
X216799Y28406D03*
Y37106D03*
X209713Y28406D03*
Y37106D03*
X214962Y26474D03*
X211562D03*
X223886Y40020D03*
Y48720D03*
X216799Y40020D03*
Y48720D03*
X209713Y40020D03*
Y48720D03*
X215717Y66844D03*
Y71836D03*
X220673Y66844D03*
Y71836D03*
X213717Y69340D03*
X222673D03*
X219895D03*
X216495D03*
X209673Y72844D03*
Y77836D03*
X211673Y75340D03*
X224717D03*
X225407Y321831D03*
X223330Y426467D03*
X220843Y430004D03*
X209530Y426192D03*
X217770Y428262D03*
X224210Y431501D03*
X224305Y422977D03*
X219995Y426267D03*
X220874Y442079D03*
X224210Y436619D03*
X218140Y440735D03*
X218010Y432735D03*
X223664Y443125D03*
X220000Y448735D03*
X209579Y457222D03*
Y462235D03*
X224064Y568113D03*
X221464D03*
X212891Y566632D03*
X210391Y567981D03*
X224064Y602113D03*
X221464D03*
X223403Y596820D03*
Y594220D03*
X212891Y601981D03*
X210391D03*
X223403Y630820D03*
Y628220D03*
X224064Y636113D03*
X221464D03*
X210391Y635981D03*
X212891D03*
X223403Y664820D03*
X217510Y668712D03*
X225167Y672006D03*
X222567D03*
X219967D03*
X217367D03*
X210320Y671262D03*
X211348Y688087D03*
Y685287D03*
X214100Y687376D03*
Y690376D03*
Y684376D03*
Y681376D03*
Y678376D03*
X211348Y690787D03*
Y693587D03*
X214100Y693576D03*
X224506Y698138D03*
Y700738D03*
X221906Y698138D03*
Y700738D03*
X219306D03*
Y698138D03*
X224900Y713293D03*
X209720Y731862D03*
X211220Y740362D03*
X220033Y756844D03*
X211602Y756855D03*
X216842Y756865D03*
X214177Y1336383D03*
X211577D03*
X214177Y1333783D03*
X211577D03*
X214207Y1339263D03*
X211607D03*
X214177Y1341883D03*
X211577D03*
X214177Y1349383D03*
Y1346883D03*
Y1344383D03*
X211577D03*
Y1346883D03*
Y1349383D03*
X215824Y1361199D03*
X211350Y1360797D03*
X218960Y1388312D03*
X213075Y1381558D03*
X217133Y1384055D03*
X214425Y1384058D03*
X215675Y1381558D03*
X218175D03*
X213075Y1378958D03*
X215675D03*
X218175D03*
X219752Y1405499D03*
Y1401999D03*
Y1398599D03*
X214201Y1404169D03*
X212035Y1402899D03*
X214101Y1401169D03*
X216554Y1399264D03*
Y1402164D03*
Y1405064D03*
X212035Y1405799D03*
X224137Y1414345D03*
X224077Y1416975D03*
X224350Y1432032D03*
X219587Y1435402D03*
X217469Y1454725D03*
X219587Y1443402D03*
Y1439402D03*
X220869Y1454725D03*
X209820Y1631142D03*
X210593Y1714017D03*
X212120Y1703062D03*
X214120Y1713462D03*
X212684Y1720307D03*
X212895Y1737108D03*
X229058Y3010D03*
X233339Y17662D03*
X235701Y21582D03*
X241310Y20322D03*
X238063Y37162D03*
X230972Y28406D03*
Y37106D03*
X229135Y26474D03*
X225735D03*
X238063Y26232D03*
X235701Y39570D03*
X230972Y48720D03*
Y40020D03*
X229131Y50646D03*
X225731D03*
X239820Y54362D03*
X239720Y71862D03*
X226717Y72844D03*
Y77836D03*
X231673Y72844D03*
Y77836D03*
X233673Y75340D03*
X227495D03*
X230895D03*
X239010Y78542D03*
X238297Y129703D03*
X242215Y151788D03*
X233800Y162692D03*
X237539Y174266D03*
X234902Y174047D03*
X226800Y359464D03*
X228550Y420412D03*
X230359Y461683D03*
X231864Y568113D03*
X229264D03*
X226664D03*
X238393Y570490D03*
X240993D03*
X229264Y602113D03*
X226664D03*
X226003Y594220D03*
Y596820D03*
X228603Y594220D03*
Y596820D03*
X231864Y602113D03*
X233803Y594220D03*
Y596820D03*
X231203Y594220D03*
Y596820D03*
X238393Y604490D03*
X240993D03*
Y596820D03*
X238393D03*
X240993Y594220D03*
X238393D03*
X226003Y628220D03*
Y630820D03*
X228603Y628220D03*
Y630820D03*
X231864Y636113D03*
X233803Y628220D03*
Y630820D03*
X231203Y628220D03*
Y630820D03*
X229264Y636113D03*
X226664D03*
X238393Y638490D03*
X240993D03*
Y630820D03*
X238393D03*
X240993Y628220D03*
X238393D03*
X228603Y664820D03*
X233803D03*
X231203D03*
X226003D03*
X230367Y672006D03*
X227767D03*
X227106Y698138D03*
Y700738D03*
X227430Y719772D03*
X238940Y716652D03*
X230864Y1254295D03*
X249058Y3010D03*
X243490Y23002D03*
X246510Y20362D03*
X253000Y28362D03*
X256500D03*
X249500D03*
X242220Y39362D03*
X246220D03*
X250220D03*
X254050Y39422D03*
X246360Y26852D03*
X248820Y48962D03*
X252320D03*
X255820D03*
X257520Y51562D03*
X254020D03*
X250520D03*
X247720Y71862D03*
X244300Y59762D03*
X249885Y69623D03*
X245220Y67862D03*
X247720Y75862D03*
X251797Y100843D03*
X248097Y92143D03*
X247897Y100543D03*
X244822Y115543D03*
Y111543D03*
X253910Y115722D03*
X253878Y111771D03*
X252195Y144320D03*
X249735Y152694D03*
X243892Y140912D03*
X259933Y141122D03*
X242255Y162512D03*
X257256Y156727D03*
X245490Y159702D03*
X252000Y395400D03*
X255810Y405582D03*
X252500Y415862D03*
X257434Y415896D03*
X258066Y426735D03*
X259845Y461117D03*
X256695D03*
X257750Y450842D03*
X249300Y510362D03*
X253800Y515362D03*
X249860Y518222D03*
X254713Y518465D03*
X245700Y513262D03*
X250100Y521783D03*
X246400Y563162D03*
X256885Y574805D03*
X254385D03*
X256855Y571995D03*
X251885Y574805D03*
X249800Y563262D03*
X254355Y589235D03*
X256855D03*
X251855D03*
X256855Y605995D03*
X251885Y608805D03*
X257643Y594220D03*
X255043D03*
Y596820D03*
X257643D03*
X256885Y608805D03*
X254385D03*
X256855Y603495D03*
X251855Y623265D03*
X254355D03*
X256855D03*
Y639995D03*
Y637495D03*
X257643Y628220D03*
X255043D03*
Y630820D03*
X257643D03*
X256885Y642805D03*
X254385D03*
X251855Y657265D03*
X251885Y642805D03*
X254355Y657265D03*
X256855D03*
X257643Y662220D03*
X255043D03*
Y664820D03*
X257643D03*
X253819Y675567D03*
X253849Y678077D03*
X256419Y675567D03*
X256449Y678077D03*
X251219Y675567D03*
X251249Y678077D03*
X248649D03*
X248989Y698827D03*
X249019Y693767D03*
X251589Y698827D03*
X251649Y696277D03*
X254189Y698827D03*
X251619Y693767D03*
X256849Y696277D03*
X256789Y698827D03*
X256819Y693767D03*
X254249Y696277D03*
X254219Y693767D03*
X248300Y703862D03*
X242460Y716652D03*
X253057Y755345D03*
X245487Y755435D03*
X259510Y757822D03*
X251187Y1255025D03*
X252895Y1737108D03*
X269058Y3010D03*
X260000Y28362D03*
X263280Y35312D03*
X272600Y27182D03*
X263240Y38122D03*
X266990Y41832D03*
X275120Y28562D03*
X271600Y40162D03*
X275900Y48872D03*
X259320Y48962D03*
X261020Y51562D03*
X263520D03*
X261820Y48962D03*
X264740Y49182D03*
X266497Y69536D03*
Y72036D03*
X264720Y56362D03*
Y60362D03*
Y64362D03*
X266597Y77526D03*
Y80026D03*
X263320Y87662D03*
X261420Y100662D03*
X264920D03*
X268420D03*
X262920Y97962D03*
X266420D03*
X269920D03*
X273620Y96662D03*
X272361Y120243D03*
X270364Y118415D03*
X263550Y120922D03*
X269191Y121092D03*
X275797Y120245D03*
X261387Y133783D03*
X258257D03*
X265910Y125492D03*
X266975Y140107D03*
X260600Y151062D03*
X272800Y140162D03*
X264578Y151203D03*
Y155203D03*
Y159203D03*
X260100Y159562D03*
X260700Y218662D03*
X268940Y217982D03*
X263580Y218627D03*
X270745Y207562D03*
X265500Y227862D03*
X263000D03*
X260500Y227362D03*
Y224862D03*
X265343Y244460D03*
X270240Y245332D03*
X271821Y251962D03*
X267759D03*
X258746Y407842D03*
X260807Y424403D03*
X259224Y419532D03*
X263430Y422235D03*
X272029Y443735D03*
X259869Y431039D03*
X262963Y443735D03*
X272500Y447735D03*
X263040Y448752D03*
X272500Y452862D03*
X264055Y574505D03*
X264025Y571995D03*
X261555Y574505D03*
X261525Y571995D03*
X264055Y566935D03*
X263995Y569485D03*
X261495D03*
X261555Y566935D03*
X266555Y574505D03*
X266525Y571995D03*
X266495Y569485D03*
X266555Y566935D03*
X269055Y574505D03*
X269025Y571995D03*
X268995Y569485D03*
X269055Y566935D03*
X261465Y592115D03*
X261525Y589565D03*
X264025D03*
X263965Y592115D03*
X266525Y589565D03*
X266465Y592115D03*
X269025Y589565D03*
X268965Y592115D03*
X264025Y605995D03*
X261525D03*
X264055Y608505D03*
X261555D03*
X261435Y597175D03*
X261495Y594625D03*
X263995D03*
X263935Y597175D03*
X266525Y605995D03*
X266555Y608505D03*
X266435Y597175D03*
X266495Y594625D03*
X261525Y603495D03*
X264025D03*
X266525D03*
X269025Y605995D03*
X269055Y608505D03*
X268935Y597175D03*
X268995Y594625D03*
X269025Y603495D03*
X261495Y621055D03*
X263995D03*
X261525Y623565D03*
X264025D03*
X263995Y611055D03*
X261495D03*
X266495Y621055D03*
X266525Y623565D03*
X266495Y611055D03*
X268995Y621055D03*
X269025Y623565D03*
X268995Y611055D03*
X261525Y639995D03*
X264025D03*
X261525Y637495D03*
X266525Y639995D03*
X269025D03*
X264025Y637495D03*
X266525D03*
X269025D03*
X263965Y626115D03*
X261465D03*
X266465D03*
X268965D03*
X261495Y655055D03*
X263995D03*
X261525Y657565D03*
X264025D03*
X263995Y645055D03*
X264055Y642505D03*
X261495Y645055D03*
X261555Y642505D03*
X266495Y655055D03*
X266525Y657565D03*
X266495Y645055D03*
X266555Y642505D03*
X268995Y655055D03*
X269025Y657565D03*
X268995Y645055D03*
X269055Y642505D03*
X261465Y660115D03*
X263965D03*
X266465D03*
X268965D03*
X259049Y678077D03*
X259019Y675567D03*
X259419Y693767D03*
X259389Y698827D03*
X259449Y696277D03*
X269600Y715792D03*
X274247Y727165D03*
X268331Y738029D03*
X273046Y735662D03*
X270100Y727262D03*
X264000Y726262D03*
X266700Y730962D03*
X270322Y740207D03*
X274270Y746602D03*
X271570Y746422D03*
X265997Y747535D03*
X271057Y765525D03*
Y762425D03*
X272895Y1737108D03*
X289058Y3010D03*
X287000Y20862D03*
X285900Y23962D03*
X286071Y28406D03*
X278984D03*
X284233Y26474D03*
X280833D03*
X290799Y28362D03*
X287952Y39984D03*
X286071Y48720D03*
X286500Y52462D03*
X278984Y48720D03*
X284230Y50646D03*
X280830D03*
X289400Y54222D03*
X287800Y60062D03*
X279277Y99183D03*
X285357Y105003D03*
X288557D03*
X280857Y107303D03*
X285857Y115603D03*
X282857D03*
X280857Y109903D03*
X289557Y121803D03*
X275797Y129592D03*
X283953Y152503D03*
X280687Y140746D03*
X287000Y139862D03*
X283053Y139728D03*
X276825Y140462D03*
X288520Y157062D03*
X290685Y165447D03*
X282640Y214102D03*
X279740Y205962D03*
X276890Y249022D03*
X289920Y248652D03*
X286920D03*
X282420D03*
X286481Y251962D03*
X281077D03*
X276491D03*
X289274Y290662D03*
X284515D03*
X276500Y444862D03*
X274850Y442562D03*
X279500Y455362D03*
X277578Y509039D03*
X284482Y569548D03*
Y566022D03*
X286582Y630757D03*
Y637809D03*
Y634283D03*
X287819Y691097D03*
X284287Y716015D03*
X277046Y725709D03*
X284358Y732562D03*
X287820Y727962D03*
X278520Y738072D03*
X289137Y735275D03*
X279507Y727025D03*
X281046Y737938D03*
X275210Y738102D03*
X290077Y739735D03*
X287607Y754962D03*
X277046Y746702D03*
X281046D03*
X285046D03*
X289047Y760245D03*
X291520Y12762D03*
X291660Y21642D03*
X299500Y22862D03*
X295520Y12762D03*
X302610Y26362D03*
X292060Y24472D03*
X295520Y26362D03*
X300248Y28362D03*
X304927Y24654D03*
X304972Y28362D03*
X302720Y38182D03*
X298720Y40017D03*
X306720Y39982D03*
X292590Y53982D03*
X293161Y50522D03*
X306570Y50222D03*
X290720Y40017D03*
X294720D03*
X295524Y52092D03*
X301310Y52482D03*
X298550Y51602D03*
X303715Y50857D03*
X292942Y67513D03*
Y71499D03*
X305747Y64013D03*
Y61113D03*
X305247Y71567D03*
X293447Y78573D03*
X293452Y82483D03*
Y85983D03*
X303047Y79373D03*
X299947Y79273D03*
X301600Y82457D03*
X302310Y75673D03*
X295357Y88903D03*
X299657Y92503D03*
X307820Y95724D03*
X301183Y107103D03*
Y110003D03*
Y112803D03*
X301751Y127466D03*
Y124466D03*
Y121466D03*
X305025Y144202D03*
X299628Y149203D03*
X302891Y141811D03*
X296478Y149203D03*
X296800Y139762D03*
X299628Y158703D03*
X294553Y153819D03*
X306000Y165662D03*
X295685Y165447D03*
X296478Y158703D03*
X306730Y173842D03*
X304651Y251962D03*
X291759D03*
X306736Y290662D03*
X302765D03*
X298184D03*
X293763D03*
X298587Y508074D03*
X300520Y552262D03*
X306087Y569718D03*
X307987Y577658D03*
X293805Y569397D03*
Y565997D03*
X298000Y587890D03*
X308417Y585158D03*
X308447Y592255D03*
X306144Y602225D03*
X305612Y622530D03*
Y625030D03*
X294658Y637809D03*
X305612Y627530D03*
X296405Y630732D03*
Y634132D03*
X295962Y679374D03*
X294679Y688446D03*
Y685046D03*
X291600Y705162D03*
X298273Y715400D03*
X297087Y721249D03*
X304602Y727968D03*
X290680Y745312D03*
X299427Y768265D03*
X303647Y1307981D03*
X303831Y1318566D03*
X303807Y1342225D03*
X303831Y1344866D03*
X303723Y1353316D03*
Y1355853D03*
X304047Y1368565D03*
X304051Y1365453D03*
X306667Y1361597D03*
X302805Y1379941D03*
Y1376541D03*
X296170Y1622852D03*
X292895Y1737108D03*
X309058Y3010D03*
X318651Y22921D03*
X310400Y50362D03*
X314657Y71803D03*
Y68903D03*
X323040Y73122D03*
X320057Y85803D03*
X323117Y81168D03*
Y76938D03*
X322875Y84318D03*
X316364Y89212D03*
X310459Y75892D03*
X320430Y78002D03*
X320057Y88803D03*
X313357Y89503D03*
X313457Y96803D03*
X311057Y107103D03*
Y110003D03*
Y112803D03*
X311758Y124469D03*
Y121469D03*
Y127469D03*
X324733Y148598D03*
X308175Y144202D03*
X320825Y159062D03*
X308500Y165662D03*
X311200Y165562D03*
X309230Y173842D03*
X309756Y177449D03*
Y181449D03*
X310970Y195362D03*
X308790Y197622D03*
X320270Y200462D03*
X319370Y214492D03*
X316370D03*
X319370Y217492D03*
X316370D03*
X323314Y210645D03*
X306910Y228162D03*
X309910D03*
X306910Y225162D03*
X309910D03*
X322658Y229254D03*
X319718Y223750D03*
X313995Y237724D03*
X317981D03*
X320940Y238372D03*
X317129Y251962D03*
X316463Y290662D03*
X316444Y559125D03*
X317860Y572322D03*
X319520Y577658D03*
X314200Y585282D03*
X316080Y578262D03*
X312007Y588675D03*
X319520Y582658D03*
X316127Y592785D03*
X318560Y587632D03*
X320691Y602448D03*
X311820Y598762D03*
X321276Y599298D03*
X317386Y623207D03*
X308605Y629525D03*
Y627025D03*
X319557Y736225D03*
X317967Y746985D03*
Y771875D03*
X316397Y776125D03*
X320578Y1290197D03*
X323028Y1297967D03*
X320428D03*
Y1295467D03*
X323028D03*
Y1292967D03*
X320428D03*
X321119Y1313108D03*
X317119D03*
X313119D03*
X317979Y1371248D03*
X315221Y1372445D03*
X313841Y1365553D03*
X309841Y1364815D03*
X318051Y1367043D03*
X316579Y1364585D03*
X309841Y1367871D03*
X329535Y49388D03*
X336240Y150738D03*
X332500D03*
X326216Y138787D03*
X326900Y162287D03*
X335285Y210609D03*
X332285D03*
X323420Y207549D03*
X326168Y207580D03*
X334485Y216809D03*
X337000Y216862D03*
X335575Y214170D03*
X328588Y209677D03*
X325755Y230719D03*
X338985Y229509D03*
X325855Y227619D03*
X334500Y219362D03*
X337000D03*
X328939Y229139D03*
X335385Y235309D03*
X335412Y222176D03*
X325055Y237219D03*
X328965Y237214D03*
X332465D03*
X329648Y252202D03*
X341295Y290239D03*
X329002Y290662D03*
X330417Y380482D03*
X330674Y368261D03*
Y365702D03*
X328167Y379073D03*
X336370Y406302D03*
X336270Y402992D03*
X329050Y607402D03*
X331760Y705882D03*
X331339Y709313D03*
X328120Y710862D03*
X335677Y715215D03*
X327107Y732665D03*
X335467Y725335D03*
X338097Y736235D03*
X335126Y728323D03*
X327096Y736005D03*
X336446Y746486D03*
X338667Y772452D03*
X341527Y778362D03*
X339148Y1269717D03*
X339088Y1272287D03*
X339028Y1274887D03*
X325688Y1290167D03*
X325718Y1287587D03*
X328078Y1288747D03*
X323178Y1290197D03*
X323208Y1287617D03*
X328168Y1280967D03*
X325748Y1284987D03*
X328108Y1286147D03*
X328138Y1283567D03*
X328018Y1291317D03*
X339035Y1280218D03*
X339040Y1277594D03*
X328065Y1299248D03*
X325538Y1297937D03*
Y1292937D03*
Y1295437D03*
X328058Y1293917D03*
X328070Y1296624D03*
X325119Y1313108D03*
X328915Y1337104D03*
X331515D03*
X328915Y1331904D03*
X331515D03*
X328915Y1329304D03*
X331515D03*
X328915Y1334504D03*
X331515D03*
X328915Y1326704D03*
X331515D03*
X328915Y1339704D03*
X335679Y1330518D03*
X334973Y1333353D03*
X338795Y1338799D03*
X338917Y1349488D03*
X336347Y1348353D03*
X336179Y1342753D03*
X332475Y1357945D03*
X327875Y1363945D03*
Y1361045D03*
X330041Y1362315D03*
X329941Y1359315D03*
X332475Y1363345D03*
Y1360445D03*
X332895Y1737108D03*
X349535Y49388D03*
X343040Y122522D03*
X340440Y120552D03*
X343450Y131167D03*
X344776Y148462D03*
X342700Y139662D03*
X355189Y144267D03*
X351100Y150412D03*
X348100Y185162D03*
X345869Y192716D03*
X345600Y188162D03*
X356295Y219362D03*
X353145Y228362D03*
Y219362D03*
X342000Y252612D03*
X354672Y252693D03*
X354145Y290591D03*
X345164Y314234D03*
X343411Y363143D03*
X345411Y364702D03*
X343411Y375364D03*
X345411Y376923D03*
X343354Y387988D03*
Y391643D03*
X343720Y400628D03*
X347340Y407462D03*
X348880Y703442D03*
X349187Y715485D03*
X352879Y728657D03*
X348037Y728735D03*
X348730Y735098D03*
Y731698D03*
X344446Y739434D03*
X348000Y755362D03*
X344264Y1272455D03*
X341754Y1272485D03*
X344252Y1269948D03*
X341742Y1269978D03*
X344258Y1267117D03*
X341748Y1267147D03*
X341754Y1274985D03*
X344264Y1274955D03*
X355036Y1272433D03*
Y1269933D03*
X355378Y1262027D03*
X355318Y1264597D03*
X355258Y1267197D03*
X355036Y1274933D03*
X341605Y1280248D03*
X344115Y1280218D03*
X344264Y1277455D03*
X341754Y1277485D03*
X355048Y1277440D03*
X355025Y1280248D03*
X339769Y1299868D03*
X342769D03*
X348804Y1346877D03*
X350470Y1349030D03*
X345969Y1342755D03*
X341969Y1342017D03*
X350179Y1344245D03*
X348707Y1341787D03*
X341969Y1345073D03*
X354850Y1371908D03*
X351850D03*
X349260Y1373418D03*
X351850Y1375408D03*
X354850D03*
X351850Y1378408D03*
X354850D03*
X351850Y1381408D03*
X354850D03*
X349260Y1376918D03*
Y1379918D03*
X349636Y1399601D03*
X352713Y1399336D03*
X355513Y1402306D03*
X352513D03*
X349513D03*
X355325Y1405386D03*
X349463Y1405286D03*
X352463D03*
X355325Y1408386D03*
X346426Y1414401D03*
X352401Y1414432D03*
X355325Y1414386D03*
Y1417386D03*
X352401Y1411432D03*
X355325Y1411386D03*
X352401Y1408432D03*
X349123Y1411376D03*
X349323Y1408406D03*
X349073Y1414356D03*
X346256Y1417301D03*
X352231Y1417332D03*
X348903Y1417256D03*
X352895Y1737108D03*
X366775Y127662D03*
X363625D03*
X361800Y122522D03*
X366060Y133912D03*
X366675Y158702D03*
X363525D03*
X356250Y216342D03*
X358209Y208169D03*
X361190Y210762D03*
X357303Y213159D03*
X371551Y224862D03*
X367306Y252811D03*
X366498Y290264D03*
X357764Y314234D03*
X357660Y318850D03*
X364014Y366391D03*
X363750Y369362D03*
X371370Y373622D03*
X364014Y378649D03*
Y382304D03*
X364179Y394596D03*
Y392037D03*
X371066Y400628D03*
X370200Y409582D03*
X373720Y431362D03*
X369690Y431812D03*
X365970Y444662D03*
X365720Y440562D03*
X365771Y449480D03*
X359639Y690114D03*
X360470Y705965D03*
X363101Y697348D03*
Y693948D03*
X360990Y726862D03*
X359930Y732985D03*
X358902Y736225D03*
X355946Y728800D03*
X359790Y729835D03*
X358902Y739755D03*
Y743035D03*
Y754945D03*
Y746405D03*
X360927Y757665D03*
X358902Y773352D03*
X371578Y1248967D03*
X371458Y1254137D03*
X371330Y1256687D03*
X371518Y1251537D03*
X371278Y1259257D03*
X360198Y1269777D03*
X357546Y1272403D03*
Y1269903D03*
X360138Y1272347D03*
X357828Y1264567D03*
X357888Y1261997D03*
X360378Y1264627D03*
X360438Y1262057D03*
X357768Y1267167D03*
X360318Y1267227D03*
X357546Y1274903D03*
X360128Y1274957D03*
X371218Y1261857D03*
X371225Y1267188D03*
X371230Y1264564D03*
X357558Y1277410D03*
X357535Y1280218D03*
X360120Y1277654D03*
X361043Y1306506D03*
X361769Y1300008D03*
X363643Y1306506D03*
X364769Y1300008D03*
X367939Y1303319D03*
Y1305919D03*
Y1308519D03*
X361043Y1314306D03*
Y1316906D03*
X362393Y1319406D03*
X361043Y1309106D03*
Y1311706D03*
X363643Y1316906D03*
Y1314306D03*
Y1309106D03*
Y1311706D03*
X367694Y1317092D03*
X367807Y1319592D03*
X370874Y1335876D03*
X367490Y1332568D03*
X368391Y1328161D03*
X370923Y1325373D03*
X362147Y1336553D03*
X360003Y1338247D03*
X364269Y1338017D03*
X364073Y1334903D03*
X360003Y1341147D03*
X362147Y1339653D03*
X364347Y1340853D03*
X364647Y1371990D03*
X361647D03*
X358647D03*
X367647D03*
X370552Y1372073D03*
X364647Y1375490D03*
X361647D03*
X358647D03*
Y1378490D03*
X370552Y1375573D03*
X367647Y1375490D03*
X355713Y1399336D03*
X361703Y1399386D03*
X364703D03*
X367703D03*
X370703D03*
X358703Y1402386D03*
X361703D03*
X364703D03*
X367703D03*
X370703D03*
X358713Y1399336D03*
X358573Y1405336D03*
X361573D03*
X364573D03*
X367573D03*
X370573D03*
X358703Y1414606D03*
X361703D03*
X364703D03*
X361703Y1417386D03*
X358703D03*
X364703D03*
X367703D03*
Y1414606D03*
X358217Y1411405D03*
X370517Y1414615D03*
X370717Y1417405D03*
X357917Y1408205D03*
X367948Y1531529D03*
X368600Y1543200D03*
X367140Y1645390D03*
X366700Y1649000D03*
X370500Y1654362D03*
X370635Y1675820D03*
X369300Y1680400D03*
Y1682900D03*
X383140Y119822D03*
X380930Y122022D03*
X375330Y121182D03*
X374981Y131433D03*
X383160Y124322D03*
X383060Y128491D03*
X372530Y122972D03*
X373200Y126052D03*
X379295Y131002D03*
X376245Y212862D03*
Y217362D03*
Y221362D03*
Y225362D03*
X386120Y220322D03*
X379860Y252162D03*
X379112Y290386D03*
X385720Y323761D03*
Y320902D03*
X376500Y362736D03*
Y366391D03*
Y378649D03*
X376770Y387272D03*
X377136Y390307D03*
X390220Y392062D03*
X383060Y403542D03*
X385520Y429262D03*
X373190Y438342D03*
X384510Y438662D03*
X379220Y436362D03*
X376220D03*
X382220D03*
X385730Y460922D03*
X389920Y461362D03*
X382860Y471122D03*
X379220Y470962D03*
X387500Y495362D03*
X389020Y522862D03*
X371970Y683892D03*
X381010Y734732D03*
X376638Y1248997D03*
X374088Y1248937D03*
X374028Y1251507D03*
X373823Y1256896D03*
X376333Y1256866D03*
X376518Y1254167D03*
X376578Y1251567D03*
X373968Y1254107D03*
X373835Y1259403D03*
X376345Y1259373D03*
X387478Y1248967D03*
X387358Y1254137D03*
X387117Y1256851D03*
X387418Y1251537D03*
X387117Y1259351D03*
X373835Y1261903D03*
Y1264403D03*
X376345Y1261873D03*
Y1264373D03*
X376285Y1267218D03*
X373735Y1267158D03*
X387117Y1261851D03*
X387129Y1264358D03*
X387125Y1267188D03*
X383239Y1286578D03*
X378069Y1286568D03*
X375069D03*
X386239Y1286578D03*
X380842Y1334095D03*
X383549Y1333998D03*
X378097Y1329329D03*
X374097Y1328591D03*
X382307Y1330819D03*
X380835Y1328361D03*
X374097Y1331647D03*
X373552Y1372073D03*
X377025Y1371990D03*
X380025D03*
X373532Y1378598D03*
X373552Y1375573D03*
X380025Y1378490D03*
X377025D03*
X380025Y1375490D03*
X377025D03*
Y1381490D03*
X380025D03*
X383127Y1395610D03*
X376825Y1399386D03*
X379825D03*
X373703D03*
X379825Y1402386D03*
X376825D03*
X373703D03*
X376825Y1405386D03*
X379825D03*
X373573Y1405336D03*
X374027Y1411365D03*
X373703Y1414606D03*
X376825Y1414386D03*
X379825D03*
X376825Y1417386D03*
Y1411386D03*
X379825D03*
X373703Y1417386D03*
X376825Y1408386D03*
X379825D03*
X374307Y1408135D03*
X381060Y1433622D03*
X382489Y1428478D03*
X385667Y1433425D03*
X386827Y1429525D03*
X377830Y1534342D03*
X374900Y1534102D03*
X381120D03*
X377720Y1539862D03*
X374720D03*
X374800Y1546400D03*
X385100Y1539700D03*
X381800Y1539600D03*
X381000Y1546500D03*
X384000D03*
X378000Y1546400D03*
X387152Y1582659D03*
X387930Y1585155D03*
X382220Y1591870D03*
X374690Y1631700D03*
X374391Y1648476D03*
X385123Y1639732D03*
X378547D03*
X375550Y1662052D03*
X380170Y1660002D03*
X372640Y1662112D03*
X380077Y1654049D03*
X381068Y1674824D03*
X386824Y1682866D03*
X387760Y1671092D03*
X372009Y1682584D03*
X375430Y1676462D03*
X373320Y1688202D03*
X376610Y1688252D03*
X372895Y1737108D03*
X393830Y62062D03*
X399800Y59662D03*
X403800D03*
X396380Y62742D03*
X402100Y62632D03*
X399240Y62722D03*
X404910Y62562D03*
X388735Y117322D03*
X395980Y148272D03*
X390830Y155833D03*
X388965Y215067D03*
Y209949D03*
X388720Y218362D03*
X394720Y206362D03*
X402700Y234167D03*
X392616Y252162D03*
X396294Y281585D03*
X392083Y290954D03*
X404215Y291140D03*
X398720Y318643D03*
Y321202D03*
X398661Y323761D03*
X403675Y363081D03*
X390876Y365640D03*
X391195Y368199D03*
X391101Y380939D03*
X403581Y375880D03*
X390843Y378439D03*
X403875Y365640D03*
X404120Y378439D03*
X390730Y394852D03*
X403570Y388874D03*
X404291Y391433D03*
X403700Y402422D03*
X390892Y406863D03*
X391149Y404304D03*
X403720Y405552D03*
X403260Y439352D03*
X391150Y445302D03*
X388720Y430862D03*
X403220Y436362D03*
X395520Y448362D03*
X396570Y472602D03*
X400080Y472652D03*
X402500Y495362D03*
X391360Y495712D03*
X402780Y499372D03*
X394860Y518812D03*
X394500Y522862D03*
X400589Y575236D03*
X403200Y572622D03*
X398796Y1161570D03*
Y1153070D03*
Y1170070D03*
X403738Y1249027D03*
X403618Y1254197D03*
X403498Y1256747D03*
X403678Y1251597D03*
X392538Y1248997D03*
X389928Y1251507D03*
X389988Y1248937D03*
X389868Y1254107D03*
X392298Y1256717D03*
X392418Y1254167D03*
X389627Y1256821D03*
X392478Y1251567D03*
X392238Y1259287D03*
X389627Y1259321D03*
X403438Y1259317D03*
X392220Y1264594D03*
X392228Y1261897D03*
X389627Y1261821D03*
X389639Y1264328D03*
X389635Y1267158D03*
X392185Y1267218D03*
X403385Y1267248D03*
X403378Y1261917D03*
X403390Y1264624D03*
X396139Y1286708D03*
X399139D03*
X395771Y1303480D03*
X393171D03*
X395771Y1300880D03*
X393171D03*
X395771Y1295680D03*
X393171D03*
X395771Y1298280D03*
X393171D03*
X394521Y1305980D03*
X400067Y1303319D03*
Y1300719D03*
Y1295519D03*
Y1298119D03*
Y1305919D03*
Y1308519D03*
X399935Y1317092D03*
Y1319592D03*
X392131Y1324821D03*
X396397Y1324591D03*
X394197Y1323091D03*
X396397Y1321691D03*
X399673Y1332653D03*
X403130Y1335963D03*
X400073Y1327653D03*
X403051Y1325373D03*
X394297Y1326091D03*
X392131Y1327721D03*
X396397Y1327491D03*
X400888Y1395508D03*
X400926Y1402207D03*
X391249Y1401048D03*
X392947Y1397827D03*
X390934Y1404085D03*
X401079Y1399208D03*
X400924Y1408227D03*
X400926Y1404707D03*
X400919Y1411231D03*
X392517Y1419015D03*
X400991Y1417264D03*
X390934Y1407605D03*
X390914Y1412991D03*
X391370Y1424782D03*
X403125Y1425008D03*
X390687Y1431713D03*
X390777Y1435152D03*
X394067Y1435323D03*
X401244Y1440773D03*
X396822Y1439340D03*
X396946Y1537632D03*
X396921Y1549810D03*
X396768Y1541810D03*
X404920Y1539362D03*
X396946Y1560810D03*
Y1556810D03*
X392108Y1582659D03*
X391330Y1585155D03*
X404030Y1595390D03*
Y1591990D03*
X401812Y1616456D03*
X394360Y1616380D03*
X388220Y1631404D03*
X394910Y1632364D03*
X392550Y1618650D03*
X397406Y1633142D03*
X402590Y1618952D03*
X394910Y1637320D03*
X401740Y1648082D03*
X404240D03*
X404320Y1645452D03*
X401820D03*
X391563Y1640244D03*
X397406Y1636542D03*
X397400Y1641000D03*
X402246Y1671745D03*
X390180Y1668212D03*
X396824Y1673662D03*
X409535Y49388D03*
X412930Y62572D03*
X407970Y59612D03*
X407790Y62652D03*
X415800Y62665D03*
Y67465D03*
X419901Y117491D03*
X413459Y129061D03*
X411434Y163662D03*
X408284D03*
X407490Y216912D03*
X420865Y215067D03*
X410996Y218834D03*
X412820Y231922D03*
X420752Y239562D03*
X405478Y236726D03*
X410090Y241932D03*
X420710Y242482D03*
X405139Y239908D03*
X417765Y252162D03*
X404985D03*
X417218Y291274D03*
X419920Y338162D03*
X416220Y364062D03*
X419012Y368762D03*
X418704Y379201D03*
X416762Y367353D03*
X418602Y394722D03*
X419023Y381760D03*
X418540Y392163D03*
X418982Y407847D03*
X416514Y407028D03*
X417010Y439352D03*
X412720Y439362D03*
X417880Y461942D03*
X418520Y473562D03*
X415130Y480202D03*
X410532Y1153341D03*
X407948Y1153370D03*
Y1161570D03*
X410532Y1161541D03*
X419460Y1161570D03*
Y1153370D03*
X407948Y1169597D03*
X410532D03*
X419460D03*
X406248Y1248997D03*
X408798Y1249057D03*
X408511Y1256866D03*
X406001Y1256896D03*
X406128Y1254167D03*
X408678Y1254227D03*
X406188Y1251567D03*
X419638Y1248967D03*
X419295Y1256851D03*
X419518Y1254137D03*
X419578Y1251537D03*
X419295Y1259351D03*
X408738Y1251627D03*
X408523Y1259373D03*
X406013Y1259403D03*
X419295Y1261851D03*
X419307Y1264358D03*
X419285Y1267188D03*
X408523Y1264373D03*
X406013Y1264403D03*
Y1261903D03*
X408523Y1261873D03*
X405895Y1267218D03*
X408445Y1267278D03*
X416099Y1335568D03*
X414617Y1333473D03*
X410225Y1329329D03*
X406225Y1328591D03*
X414435Y1330819D03*
X412963Y1328361D03*
X406225Y1331647D03*
X418320Y1383862D03*
X422320D03*
X410933Y1384648D03*
X412465Y1393878D03*
X419974Y1405289D03*
X414909Y1395658D03*
X408915Y1402606D03*
X411150Y1408163D03*
X419974Y1412789D03*
X420474Y1420289D03*
X410912Y1418177D03*
X408968Y1410427D03*
X407125Y1424978D03*
X416926Y1426471D03*
X412416Y1431645D03*
X419861Y1429718D03*
X419302Y1434700D03*
X410074Y1424993D03*
X413599Y1441908D03*
X404475Y1552452D03*
X407625Y1552572D03*
X419820Y1555862D03*
X409140Y1566892D03*
X405000Y1566670D03*
X419002Y1600306D03*
X406526Y1591212D03*
Y1596168D03*
X412600Y1601000D03*
X406768Y1616456D03*
X408700Y1603500D03*
Y1614300D03*
X408600Y1607400D03*
X419780Y1602802D03*
X411910Y1629170D03*
Y1624214D03*
X414406Y1624992D03*
Y1628392D03*
X405990Y1618952D03*
X416020Y1620862D03*
X412456Y1649838D03*
X417960Y1650072D03*
X410700Y1658460D03*
Y1655310D03*
X410232Y1670244D03*
X409857Y1682767D03*
X421320Y1671699D03*
X410249Y1673082D03*
X429535Y49388D03*
X430655Y58677D03*
X427120Y59862D03*
X428500Y65016D03*
Y70016D03*
X429050Y117491D03*
X435340Y125346D03*
X430980Y132672D03*
X435340Y122196D03*
X428889Y121515D03*
X428883Y131015D03*
X429780Y153477D03*
Y157466D03*
Y161466D03*
X433695Y214862D03*
Y209862D03*
X429395Y232562D03*
X426295Y227862D03*
X422210Y221452D03*
X429395Y236562D03*
X421200Y232562D03*
X423145Y227862D03*
X429395Y240562D03*
X426490Y244262D03*
X429702Y290763D03*
X425720Y319492D03*
X425249Y338061D03*
X432380Y346522D03*
X422420Y338162D03*
X432006Y363644D03*
X431503Y376642D03*
X431781Y379201D03*
X434006Y365203D03*
X431596Y389604D03*
X433596Y391163D03*
X431920Y405288D03*
X431462Y402729D03*
X424980Y439462D03*
X428720Y439362D03*
X437720Y435362D03*
X431570Y435512D03*
X437520Y476337D03*
X431220Y496362D03*
X427790Y500862D03*
X427880Y506442D03*
X434343Y504233D03*
Y509733D03*
Y498733D03*
X431220Y507143D03*
Y512623D03*
Y501643D03*
X428510Y515842D03*
X434343Y515233D03*
Y526233D03*
Y520733D03*
X431220Y518133D03*
Y523362D03*
X434620Y535762D03*
X434343Y542733D03*
X434320Y540153D03*
X434343Y547769D03*
Y552769D03*
X436822Y1161570D03*
Y1153370D03*
X431722D03*
Y1161570D03*
X434272Y1153370D03*
Y1161570D03*
X421960D03*
Y1153370D03*
X436822Y1170070D03*
X431722D03*
X434272D03*
X421960Y1169597D03*
X422148Y1248937D03*
X424698Y1248997D03*
X422088Y1251507D03*
X421805Y1256821D03*
X422028Y1254107D03*
X424458Y1256717D03*
X424578Y1254167D03*
X424638Y1251567D03*
X421805Y1259321D03*
X424398Y1259287D03*
X436068Y1248967D03*
X435828Y1256687D03*
X435948Y1254137D03*
X436008Y1251537D03*
X435768Y1259257D03*
X421805Y1261821D03*
X421817Y1264328D03*
X421795Y1267158D03*
X424345Y1267218D03*
X424380Y1264594D03*
X424388Y1261897D03*
X435715Y1267188D03*
X435720Y1264564D03*
X435708Y1261857D03*
X430999Y1286758D03*
X423229D03*
X426229D03*
X433999D03*
X432195Y1303319D03*
Y1305919D03*
X425299Y1303480D03*
X426649Y1305980D03*
X427899Y1303480D03*
X425299Y1295680D03*
X427899D03*
X432195Y1295519D03*
Y1298119D03*
X427899Y1298280D03*
X425299D03*
X432195Y1300719D03*
X427899Y1300880D03*
X425299D03*
X432195Y1308519D03*
X432063Y1317092D03*
Y1319592D03*
X428525Y1321691D03*
X426325Y1323091D03*
X424259Y1324821D03*
X428525Y1324591D03*
X434983Y1335924D03*
X431578Y1332560D03*
X432628Y1327845D03*
X435179Y1325373D03*
X424259Y1327721D03*
X426425Y1326091D03*
X428525Y1327491D03*
X426320Y1383862D03*
X439030Y1383692D03*
X436780Y1387387D03*
X436467Y1391687D03*
X427474Y1405289D03*
X434974D03*
X438458Y1402169D03*
X434974Y1412789D03*
X427474Y1420289D03*
X434974D03*
X438645Y1426890D03*
X437299Y1436774D03*
X433539Y1430613D03*
X425030Y1434292D03*
X427546Y1443411D03*
X433954Y1439029D03*
X424146Y1443411D03*
X436920Y1541562D03*
X422566Y1550046D03*
X435396Y1551810D03*
X424820Y1552605D03*
X431620Y1541362D03*
X432996Y1558322D03*
X434430Y1567562D03*
X424570Y1579466D03*
X433350Y1579509D03*
X423958Y1600306D03*
X428099Y1586282D03*
X435240Y1609200D03*
X433383Y1602629D03*
X428941Y1606441D03*
X424800Y1616600D03*
X432200Y1607060D03*
X423180Y1602802D03*
X432500Y1613822D03*
X436840Y1632682D03*
X436880Y1622442D03*
X430015Y1626608D03*
X433670Y1639562D03*
X432895Y1737108D03*
X449535Y49388D03*
X451418Y78782D03*
X446640Y104552D03*
X450380Y104647D03*
X443678Y145710D03*
X446746Y152662D03*
X453028Y154864D03*
X452500Y213362D03*
Y222362D03*
X452071Y254862D03*
X442265Y290939D03*
X445964Y314234D03*
X439120Y314562D03*
X442220Y323362D03*
X448220Y323582D03*
Y319862D03*
X446000Y339362D03*
X450400Y338812D03*
X445944Y359053D03*
X450500Y358862D03*
X446730Y382432D03*
X443770Y371042D03*
X451062Y397262D03*
X447490Y409052D03*
X443300Y410962D03*
X447750Y414112D03*
X453020Y414262D03*
X443744Y429553D03*
X451421D03*
X449420Y424162D03*
X443744Y452462D03*
X451520Y475837D03*
X442520Y476337D03*
X437520Y484837D03*
X447520D03*
X442520D03*
X451520D03*
X453680Y515072D03*
X442853Y542519D03*
X451320Y533562D03*
X442853Y547519D03*
X448276Y1161570D03*
X445776D03*
X443276D03*
X445776Y1153370D03*
X448276D03*
X443276D03*
X448276Y1170069D03*
X445776D03*
X443276D03*
X441128Y1248997D03*
X438578Y1248937D03*
X438518Y1251507D03*
X440858Y1256866D03*
X438348Y1256896D03*
X441008Y1254167D03*
X438458Y1254107D03*
X441068Y1251567D03*
X440870Y1259373D03*
X438360Y1259403D03*
X451642Y1256851D03*
X451878Y1254107D03*
X451642Y1259351D03*
X451938Y1251507D03*
X451998Y1248937D03*
X438360Y1261903D03*
X440870Y1261873D03*
Y1264373D03*
X438360Y1264403D03*
X438225Y1267158D03*
X440775Y1267218D03*
X451642Y1261851D03*
X451654Y1264358D03*
X451645Y1267158D03*
X446944Y1335928D03*
X445153Y1334095D03*
X442353Y1329329D03*
X438353Y1328591D03*
X446563Y1330819D03*
X445091Y1328361D03*
X438353Y1331647D03*
X443842Y1389106D03*
X448020Y1391862D03*
X443424Y1397869D03*
X439391Y1398266D03*
X441369Y1394260D03*
X451048Y1404914D03*
X447110Y1403812D03*
X448114Y1396812D03*
X446230Y1407722D03*
X445230Y1411719D03*
X445723Y1419730D03*
X451080Y1433740D03*
X440164Y1433982D03*
X443715Y1436052D03*
X446258Y1441606D03*
X449778D03*
X448079Y1562177D03*
X443910Y1555602D03*
X452520Y1564862D03*
X440019Y1576809D03*
X442128Y1574879D03*
X450020Y1570412D03*
X448328Y1582476D03*
X446020Y1570412D03*
X452020Y1580412D03*
X448740Y1574862D03*
X441308Y1602654D03*
X444458D03*
X437383Y1602629D03*
X454661Y1609235D03*
X442974Y1615615D03*
X448181Y1614401D03*
X443800Y1610712D03*
X447100Y1622562D03*
X447020Y1632632D03*
X451910Y1643282D03*
X437562Y1649770D03*
X442518D03*
X449940Y1647412D03*
X447090Y1647472D03*
X444940Y1641842D03*
X438340Y1652266D03*
X441740D03*
X452895Y1737108D03*
X469535Y49388D03*
X454568Y78782D03*
X462620Y120948D03*
X462320Y115948D03*
X466992Y145888D03*
X453346Y149864D03*
X461900Y215244D03*
X466300Y217803D03*
X461900Y222921D03*
X466300Y225480D03*
X458264Y254862D03*
X468323Y254562D03*
X465236Y293823D03*
Y296973D03*
X461736Y301098D03*
Y306098D03*
X467736Y312938D03*
X460300Y303662D03*
X463198Y311587D03*
X468490Y340572D03*
X453621Y359053D03*
X469830Y366158D03*
X456660Y359172D03*
X460800Y358962D03*
X467211Y371902D03*
X459220Y393762D03*
X463500Y383562D03*
X462720Y404762D03*
X455720D03*
X458600Y414262D03*
X465421Y424928D03*
Y428078D03*
X466520Y475812D03*
X456520Y476337D03*
X461520D03*
X456520Y484837D03*
X461520D03*
X460323Y510183D03*
X455326Y520389D03*
X453727Y518036D03*
X457456Y522516D03*
X470880Y572692D03*
X467130Y600122D03*
X457196Y1161570D03*
X459696D03*
X462196D03*
X459696Y1153370D03*
X457196D03*
X462196D03*
X459696Y1170070D03*
X462196D03*
X457196D03*
X456818Y1256687D03*
X454388Y1254077D03*
X454152Y1256821D03*
X456998Y1251537D03*
X456758Y1259257D03*
X454152Y1259321D03*
X468258Y1249107D03*
X468018Y1256827D03*
X468138Y1254277D03*
X468198Y1251677D03*
X467958Y1259397D03*
X457058Y1248967D03*
X454508Y1248907D03*
X454448Y1251477D03*
X456938Y1254137D03*
X456705Y1267188D03*
X454155Y1267128D03*
X456748Y1261867D03*
X456740Y1264564D03*
X454152Y1261821D03*
X454164Y1264328D03*
X467905Y1267328D03*
X467910Y1264704D03*
X467898Y1261997D03*
X460049Y1286978D03*
X463049D03*
X469019Y1286718D03*
X458327Y1303980D03*
X460927D03*
X464427Y1305380D03*
X460927Y1306580D03*
X458327D03*
Y1301380D03*
X460927D03*
X464427Y1300180D03*
Y1302780D03*
X458327Y1296180D03*
X460927D03*
X464427D03*
X458327Y1298780D03*
X460927D03*
X464423Y1308519D03*
X464191Y1317092D03*
Y1319592D03*
X458453Y1323091D03*
X460653Y1321691D03*
Y1324591D03*
X456387Y1324821D03*
X464738Y1333085D03*
X467644Y1335981D03*
X464191Y1327793D03*
X467307Y1325373D03*
X458553Y1326091D03*
X460653Y1327491D03*
X456387Y1327721D03*
X465749Y1401238D03*
X459550Y1401348D03*
X465947Y1398355D03*
X459321Y1393009D03*
Y1396409D03*
X455576Y1409125D03*
Y1417125D03*
X455602Y1412334D03*
X455576Y1420625D03*
X458441Y1414893D03*
X468880Y1418400D03*
X455576Y1427632D03*
Y1424125D03*
X454450Y1433580D03*
X456619Y1431189D03*
X463140Y1451562D03*
X463207Y1547543D03*
X453595Y1551470D03*
X459520Y1546962D03*
X466905Y1567847D03*
X456961Y1559697D03*
X467400Y1556700D03*
X456020Y1580412D03*
X464020D03*
X462079Y1572177D03*
X460020Y1580412D03*
X457220Y1584020D03*
X466520Y1574862D03*
X454661Y1596755D03*
X464160Y1587122D03*
X457220Y1603562D03*
X460200Y1589900D03*
X459779Y1609235D03*
X456510Y1614472D03*
X469488Y1607362D03*
X458414Y1624994D03*
Y1629950D03*
X460910Y1629172D03*
Y1625772D03*
X455681Y1622492D03*
X458978Y1634481D03*
X463344Y1637622D03*
X469580Y1640272D03*
X468040Y1654807D03*
Y1651657D03*
X466460Y1672332D03*
X466180Y1678392D03*
X478240Y55935D03*
Y66575D03*
Y61129D03*
X481880Y147069D03*
X484396Y161364D03*
X481246D03*
X476220Y158772D03*
X475500Y212685D03*
X470900Y234787D03*
X486800Y259162D03*
X478500Y258862D03*
X472800Y299462D03*
X474736Y302098D03*
X478995Y293787D03*
X484800Y307362D03*
X476740Y309272D03*
X479740Y300202D03*
X479736Y303598D03*
Y308598D03*
X486720Y360862D03*
X482720D03*
X475508Y359266D03*
X476585Y370727D03*
X482920Y398060D03*
X472720Y391362D03*
X485020Y414162D03*
X480393Y429412D03*
X471920Y416687D03*
X479379Y452445D03*
X474169Y476196D03*
X479169D03*
Y484696D03*
X474169D03*
X484169D03*
X474044Y503725D03*
X473870Y506622D03*
X474220Y572782D03*
X471940Y597532D03*
X478510Y602942D03*
X472960Y602152D03*
X482780Y607012D03*
X483030Y1153370D03*
Y1161570D03*
X473698D03*
X471198D03*
X473698Y1153370D03*
X471198D03*
X483030Y1170070D03*
X473698D03*
X471198D03*
X473318Y1249137D03*
X470768Y1249077D03*
X473035Y1256866D03*
X470525Y1256896D03*
X473198Y1254307D03*
X470648Y1254247D03*
X473258Y1251707D03*
X470708Y1251647D03*
X473047Y1259373D03*
X470537Y1259403D03*
X484098Y1248997D03*
X483819Y1256851D03*
X483978Y1254167D03*
X484038Y1251567D03*
X483819Y1259351D03*
X472965Y1267358D03*
X470415Y1267298D03*
X470537Y1261903D03*
X473047Y1261873D03*
Y1264373D03*
X470537Y1264403D03*
X483819Y1261851D03*
X483831Y1264358D03*
X483745Y1267218D03*
X474509Y1286848D03*
X481509D03*
X477509D03*
X484509D03*
X477162Y1334095D03*
X478909Y1336038D03*
X474481Y1329329D03*
X470481Y1328591D03*
X478691Y1330819D03*
X477219Y1328361D03*
X470481Y1331647D03*
X483560Y1401712D03*
X475285Y1395402D03*
X474983Y1400385D03*
X485141Y1405430D03*
X485236Y1417844D03*
X481997Y1409955D03*
X470987Y1409965D03*
X484921Y1413246D03*
X470890Y1435838D03*
X482741Y1438698D03*
X478308Y1439986D03*
X482742Y1441312D03*
X478449Y1448158D03*
X482633Y1449091D03*
Y1446091D03*
X470111Y1548269D03*
X483348Y1548062D03*
X475110Y1548112D03*
X477968Y1548122D03*
X480848Y1548120D03*
X486210Y1547960D03*
X482400Y1558320D03*
X472220Y1626732D03*
X472210Y1618626D03*
X485150Y1624942D03*
X472210Y1622735D03*
X477905Y1663242D03*
Y1659242D03*
X475150Y1654302D03*
X477835Y1673462D03*
X477905Y1667242D03*
X477835Y1677462D03*
Y1685462D03*
X472895Y1737108D03*
X489535Y49347D03*
X488748Y72264D03*
X497002Y88167D03*
X499580Y78442D03*
X489730Y76132D03*
X498330Y96112D03*
X501540Y105152D03*
X498730Y128592D03*
X498630Y140492D03*
X498700Y212685D03*
Y220362D03*
X503100Y215244D03*
X500925Y231262D03*
X503100Y222921D03*
X489980Y250512D03*
X496028Y258590D03*
X499096Y252462D03*
X498636Y293123D03*
X489091Y293787D03*
X498636Y296273D03*
X495136Y300398D03*
Y305398D03*
X501136Y312238D03*
X486861Y309398D03*
X492074Y300306D03*
X486861Y305398D03*
X495036Y310398D03*
X486710Y313582D03*
X492150Y336810D03*
X498720Y360862D03*
X490720D03*
Y368862D03*
X497568Y397632D03*
X489520Y411862D03*
X494020Y414262D03*
X502070Y424787D03*
X488070Y429412D03*
X502070Y427937D03*
X488169Y475696D03*
X493169Y476196D03*
X498169D03*
Y484696D03*
X493169D03*
X488169D03*
X494193Y550447D03*
X486500Y556212D03*
X491043Y550447D03*
X486608Y1248967D03*
X489158Y1249027D03*
X486329Y1256821D03*
X486488Y1254137D03*
X488918Y1256747D03*
X489038Y1254197D03*
X486548Y1251537D03*
X489098Y1251597D03*
X486329Y1259321D03*
X488858Y1259317D03*
X500228Y1259237D03*
X486329Y1261821D03*
X486341Y1264328D03*
X488840Y1264624D03*
X488848Y1261927D03*
X488805Y1267248D03*
X486255Y1267188D03*
X500138Y1269637D03*
X500150Y1272344D03*
X500198Y1267037D03*
Y1264467D03*
X500168Y1261807D03*
X500150Y1275224D03*
X490759Y1291978D03*
X500150Y1278104D03*
X496451Y1306345D03*
X489555Y1303480D03*
X492155D03*
X490905Y1305980D03*
X492155Y1300880D03*
X489555D03*
X495309Y1300058D03*
X498309D03*
X496220Y1322440D03*
X496451Y1316745D03*
Y1308945D03*
Y1314145D03*
Y1311545D03*
X492878Y1322618D03*
X490678Y1324018D03*
X496319Y1330493D03*
Y1333043D03*
X499435Y1338799D03*
X488539Y1325772D03*
X492878Y1325518D03*
X488539Y1328672D03*
X490778Y1327018D03*
X492878Y1328418D03*
X499458Y1349468D03*
X496319Y1341264D03*
X499818Y1385027D03*
X499859Y1393027D03*
X490307Y1421499D03*
X491156Y1438713D03*
X499541Y1438698D03*
X491142Y1441312D03*
X499542D03*
X491089Y1446091D03*
Y1449091D03*
X499489D03*
Y1446091D03*
X487340Y1641352D03*
X489230Y1643592D03*
X492895Y1737108D03*
X517914Y42257D03*
X517902Y49194D03*
X510815D03*
X517902Y69508D03*
X510815D03*
X503100Y78402D03*
X510030Y78412D03*
X504980Y101752D03*
X516236Y92948D03*
X513586Y92799D03*
X510600Y92782D03*
X517290Y104252D03*
X513700Y117862D03*
X510900Y111962D03*
X503270Y128592D03*
X507320D03*
X503290Y140492D03*
X507360D03*
X515690Y147852D03*
X519010Y147912D03*
X518186Y139821D03*
X514850Y168443D03*
X519236Y202404D03*
X518670Y219192D03*
X512500Y209862D03*
X504075Y231262D03*
X512500Y223362D03*
X508500Y232862D03*
X508000Y237862D03*
Y241862D03*
X508502Y298813D03*
X503040Y287928D03*
X505900Y311562D03*
X508500Y303362D03*
X508136Y309398D03*
X502239Y315404D03*
X510740Y332592D03*
X507160Y332452D03*
X510720Y360862D03*
X514720D03*
X502720D03*
X506720Y368862D03*
X509720Y390362D03*
X513720D03*
X513173Y408740D03*
X505720Y398362D03*
X502260Y397742D03*
X511320Y437962D03*
X513444Y457522D03*
Y473281D03*
X503169Y475671D03*
X514425Y489112D03*
Y495112D03*
X509493Y539819D03*
X516970Y592942D03*
X513025Y615742D03*
X504135Y615612D03*
X505398Y1259377D03*
X502858Y1259257D03*
X502718Y1271417D03*
X505218Y1271447D03*
X505290Y1267254D03*
X505338Y1261947D03*
X505278Y1264547D03*
X502750Y1267134D03*
X502798Y1261827D03*
X502738Y1264427D03*
X502718Y1274114D03*
X505218Y1274144D03*
X515898Y1271447D03*
X515950Y1274144D03*
X505220Y1280054D03*
X502718Y1276994D03*
X505218Y1277024D03*
X502680Y1280054D03*
X515960D03*
X515950Y1277024D03*
X517989Y1300108D03*
X514989D03*
X509382Y1347521D03*
X511149Y1349468D03*
X506609Y1342755D03*
X502609Y1342017D03*
X510819Y1344245D03*
X509347Y1341787D03*
X502609Y1345073D03*
X505055Y1387601D03*
Y1382301D03*
X505018Y1385027D03*
X502418D03*
X505055Y1396001D03*
Y1398601D03*
Y1390201D03*
X508881Y1404880D03*
X506181D03*
X505059Y1393027D03*
X502459D03*
X503559Y1405025D03*
X508775Y1409889D03*
X508828Y1407385D03*
X508802Y1412420D03*
X506075Y1409889D03*
X506128Y1407385D03*
X503572Y1407539D03*
Y1415039D03*
Y1412539D03*
X506102Y1412420D03*
X503572Y1410039D03*
X509246Y1420002D03*
X508001Y1438669D03*
X505777Y1425579D03*
X507942Y1441312D03*
X507964Y1448979D03*
Y1445979D03*
X512895Y1737108D03*
X518606Y23797D03*
X529720Y30792D03*
X525000Y42257D03*
X524988Y49194D03*
X519764Y40328D03*
X523164D03*
X529720Y43054D03*
X534720Y42922D03*
X532075Y69508D03*
Y57894D03*
X524988Y69508D03*
X533915Y59822D03*
X519742Y71436D03*
X523142D03*
X523978Y59074D03*
X529078Y59282D03*
X527520Y69633D03*
X528590Y72922D03*
X529239Y99997D03*
Y92911D03*
X528400Y104225D03*
X518450Y101602D03*
X527310Y98147D03*
Y94747D03*
X528400Y114275D03*
X527823Y131802D03*
X527160Y129243D03*
X527823Y149802D03*
X527278Y164726D03*
X523220Y170362D03*
X534765Y161067D03*
X526920Y161362D03*
X529480Y183921D03*
X529507Y202448D03*
X522337Y202404D03*
X536127Y247652D03*
X531298Y284280D03*
X532533Y299500D03*
X529533D03*
X536420Y309422D03*
X523682Y307541D03*
Y304541D03*
X523660Y323222D03*
X526980Y322582D03*
X521820Y336762D03*
X531720Y360862D03*
X527720D03*
X535220Y383552D03*
X523670Y368892D03*
X525720Y390362D03*
X529720D03*
X528145Y408705D03*
X521720Y398362D03*
X526941Y447802D03*
X532650Y446396D03*
Y442376D03*
X518735Y452442D03*
X521885D03*
X532650Y450330D03*
Y454270D03*
X533410Y475932D03*
X525820Y473662D03*
X524425Y489112D03*
Y495112D03*
X519520Y484027D03*
X522805Y482155D03*
X531258Y505473D03*
X526852Y511331D03*
X527042Y505830D03*
X521561Y505969D03*
Y500469D03*
Y511469D03*
X524220Y505862D03*
Y500362D03*
Y511362D03*
X526853Y516817D03*
X521561Y516969D03*
Y522469D03*
X536000Y520362D03*
X524220Y516862D03*
X524720Y525293D03*
Y519743D03*
X521561Y527969D03*
Y539819D03*
X524920D03*
X524820Y545319D03*
X521561Y550819D03*
X523699Y571545D03*
X526280Y569122D03*
X528500Y566722D03*
X523890Y592387D03*
X520710Y592552D03*
X531472Y579750D03*
X521118Y1273097D03*
X518488Y1271477D03*
X521058Y1275667D03*
X518490Y1274144D03*
X521058Y1278277D03*
X521020Y1280974D03*
X518500Y1280054D03*
X518490Y1277024D03*
X530398Y1288557D03*
X530548Y1283377D03*
X530428Y1285947D03*
X530410Y1291254D03*
X532558Y1289967D03*
X532618Y1287367D03*
X532678Y1284797D03*
X530450Y1297014D03*
Y1294134D03*
X532570Y1295554D03*
Y1298434D03*
Y1292674D03*
X523033Y1319406D03*
X527645Y1326076D03*
X528579Y1329143D03*
X528377Y1335982D03*
X525008Y1336287D03*
X520643Y1338247D03*
X522809Y1339517D03*
X522783Y1334882D03*
X520643Y1341147D03*
X528579Y1342143D03*
Y1344743D03*
X528447Y1353316D03*
Y1355816D03*
X524892Y1341462D03*
X522818Y1342930D03*
X528975Y1369724D03*
X528929Y1364212D03*
X531563Y1361597D03*
X532895Y1737108D03*
X548609Y32500D03*
X539720Y30792D03*
X534720D03*
X542050Y47452D03*
X539720Y42862D03*
X550971Y42902D03*
X544720Y42892D03*
X548609Y48082D03*
X546248Y69508D03*
X539161D03*
Y57894D03*
X537315Y59822D03*
X541002Y71436D03*
X544402D03*
X546234Y77443D03*
X548070Y79372D03*
X542620Y103352D03*
X542460Y99172D03*
X549610Y120682D03*
X537360Y120522D03*
X539475Y118772D03*
X550545Y147302D03*
X547395D03*
X543083Y146338D03*
X540460Y200392D03*
X542798Y202646D03*
X548390Y236512D03*
X546390Y231742D03*
X539639Y271972D03*
X539830Y274912D03*
X535630Y306602D03*
X547420Y306862D03*
X544920D03*
X549220Y339687D03*
X535720Y360862D03*
X546758Y360502D03*
X550024Y369123D03*
Y401023D03*
X547810Y414472D03*
X549670Y419892D03*
X543035Y441005D03*
X542870Y438320D03*
X548464Y456534D03*
X548780Y475932D03*
X538120Y463137D03*
X548550Y480382D03*
X546210Y519642D03*
X535290Y572932D03*
X541820Y575130D03*
X541722Y568054D03*
X543450Y590262D03*
X537730Y577440D03*
X547020Y590332D03*
X550320Y583362D03*
X536626Y590500D03*
X537560Y598102D03*
X537648Y1290037D03*
X535058Y1290007D03*
X535148Y1287397D03*
X543660Y1302934D03*
X541100D03*
X538560D03*
X535110Y1292704D03*
Y1295584D03*
Y1298464D03*
X537650Y1292704D03*
X540210D03*
X537650Y1298464D03*
Y1295584D03*
X540210Y1298464D03*
Y1295584D03*
X536020Y1302904D03*
X544813Y1322668D03*
X542213D03*
X538293D03*
X535693D03*
X542256Y1369935D03*
X538737Y1365553D03*
X534737Y1364815D03*
X542947Y1367043D03*
X541475Y1364585D03*
X534737Y1367871D03*
X562780Y32842D03*
X563482Y40826D03*
X554720Y32862D03*
X565184Y47982D03*
X564430Y45132D03*
X558058Y46352D03*
X554983Y45312D03*
X553650Y48842D03*
X560421Y69508D03*
X553335D03*
X555175Y71436D03*
X558575D03*
X553320Y77443D03*
X551470Y79372D03*
X567865Y92656D03*
X559000Y102862D03*
X561000Y98862D03*
X564988Y118670D03*
X555545Y134340D03*
X552395D03*
X566500Y125097D03*
X551231Y122671D03*
X565500Y145252D03*
X564890Y142173D03*
X555220Y167937D03*
Y164787D03*
X555545Y156462D03*
X555195Y184862D03*
Y171862D03*
X553657Y193862D03*
X554872Y196635D03*
X559400Y201162D03*
X557248Y198909D03*
X564600Y202662D03*
X552489Y212022D03*
X553402Y231292D03*
X564944Y252173D03*
X552089Y253202D03*
Y257202D03*
X562461Y272161D03*
X561324Y301149D03*
X553536Y307527D03*
X566730Y300992D03*
X555520Y309827D03*
X563790Y331846D03*
X561290D03*
X558790D03*
X557701Y369123D03*
X569080Y414002D03*
X559300Y422732D03*
X562200Y419412D03*
X559300Y414112D03*
X559730Y434772D03*
X557829Y454479D03*
X558220Y459362D03*
X563281Y543113D03*
X563700Y538477D03*
X560640Y540613D03*
X566140Y554972D03*
Y551472D03*
X559927Y548457D03*
X556820Y570462D03*
X557430Y583572D03*
X558933Y1323658D03*
X563634Y1334315D03*
X561034D03*
X558933Y1326258D03*
X556563Y1337918D03*
X553963D03*
X558933Y1328938D03*
X556563Y1335318D03*
Y1332718D03*
X558933Y1331538D03*
X553963Y1335318D03*
Y1332718D03*
X555313Y1340418D03*
X555372Y1343037D03*
X561070Y1346174D03*
X565849Y1346968D03*
X566510Y1352217D03*
X554837Y1359315D03*
X557037Y1363715D03*
Y1357915D03*
Y1360815D03*
X554937Y1362315D03*
X552771Y1361045D03*
Y1363945D03*
X555057Y1449395D03*
X552895Y1737108D03*
X572500Y32862D03*
X568500D03*
X578620Y45112D03*
X581500Y41862D03*
X573190Y42912D03*
X567507Y45869D03*
X575330Y47672D03*
X570208Y47982D03*
X579930Y72052D03*
X577300Y66682D03*
X577880Y75442D03*
X570150Y102862D03*
X579080Y119402D03*
X567673Y130542D03*
X573360Y140532D03*
X581175Y164717D03*
X569965Y161232D03*
X573115D03*
X569470Y171702D03*
X581120Y155062D03*
X568245Y167112D03*
X579481Y202378D03*
Y198378D03*
X579170Y190092D03*
X579481Y194378D03*
Y210378D03*
X568149Y217916D03*
X580712Y215877D03*
X579481Y206378D03*
X578450Y218562D03*
X581645Y233362D03*
X569668Y229812D03*
X578711Y230109D03*
X579245Y221362D03*
X567730Y225362D03*
X578390D03*
X567730Y221362D03*
X581755Y236978D03*
X578509Y265132D03*
X575359D03*
X582510Y296657D03*
X577676Y300268D03*
X569880Y300992D03*
X580400Y302402D03*
X577480Y303822D03*
X582510Y304052D03*
Y311571D03*
X570440Y331930D03*
X567630Y331958D03*
X574800Y322462D03*
X571830Y348772D03*
X582436Y361032D03*
X572360Y351962D03*
X570200Y372229D03*
X571720Y381862D03*
X577720D03*
X574491Y376549D03*
X580370Y383670D03*
X581090Y426970D03*
X571930Y421232D03*
X571110Y442656D03*
X569490Y437600D03*
X571110Y446706D03*
X570760Y451710D03*
X567320Y454962D03*
Y459962D03*
Y457462D03*
X577220Y449462D03*
X578920Y466462D03*
X583045Y488212D03*
X583220Y493212D03*
X571990Y501046D03*
X568840D03*
X584173Y498422D03*
X568520Y504162D03*
Y506662D03*
X577470Y505592D03*
X578925Y516846D03*
X571700Y552200D03*
X571627Y548124D03*
X569050Y578292D03*
X572057Y577242D03*
X573849Y1346968D03*
X569849D03*
X571555Y1352487D03*
X570645Y1361358D03*
X576220Y1423862D03*
X571620Y1424492D03*
X572895Y1737108D03*
X584950Y54842D03*
X596840Y45152D03*
X593925Y49193D03*
X586260Y52222D03*
X599800Y43152D03*
X597955Y48047D03*
X593369Y45682D03*
X586600Y60602D03*
X590680Y83591D03*
X592307Y94262D03*
X597287D03*
X594720Y97220D03*
X591395Y132142D03*
X588245D03*
X598410Y124102D03*
X598390Y126802D03*
X595220Y140922D03*
X588000D03*
X592710Y156342D03*
X593248Y159480D03*
X598295Y171862D03*
X589690Y161732D03*
X596581Y184849D03*
X590337Y177604D03*
X592220Y173862D03*
X596795Y179287D03*
X590281Y180698D03*
X599720Y184887D03*
X593220D03*
X598760Y203712D03*
X593966Y229965D03*
X584795Y233362D03*
X591310Y219582D03*
X592220Y249362D03*
X595415Y246515D03*
X592039Y252202D03*
X588577Y285862D03*
X590350Y294402D03*
X591727Y285862D03*
X593763Y293999D03*
X588850Y291622D03*
X586820Y314662D03*
X599620Y314762D03*
X595520Y314862D03*
X583820Y314662D03*
X597820Y317062D03*
X592920Y326362D03*
X590820Y330962D03*
X590720Y327862D03*
Y324582D03*
X590470Y319192D03*
X593120Y342782D03*
X583685Y363271D03*
X586185D03*
X586070Y352302D03*
X591720Y430787D03*
X591839Y426112D03*
X595380Y416660D03*
X599220Y444362D03*
X591720Y433937D03*
X595520Y439762D03*
X597220Y458688D03*
X599080Y448062D03*
X584100Y477952D03*
X592520Y467662D03*
X590210Y484132D03*
X593545Y488212D03*
X599645Y479862D03*
X598661Y486922D03*
X587100Y493842D03*
X592400Y479162D03*
X591070Y504900D03*
X594090Y505107D03*
Y501957D03*
X587100Y496342D03*
X589260Y519421D03*
X594240Y511953D03*
X591425Y522337D03*
X591500Y516862D03*
X593675Y534702D03*
X596880Y534812D03*
X589989Y745475D03*
X592340Y744624D03*
X598693Y742072D03*
X607890Y34389D03*
X611810Y34400D03*
X615420Y42342D03*
X605060Y42402D03*
X615185Y49193D03*
X612822Y43232D03*
X606880Y44682D03*
X614400Y46012D03*
X603063Y48023D03*
X615185Y69508D03*
X603374D03*
X606020Y84562D03*
X615220Y76862D03*
X615170Y73812D03*
X601220Y73862D03*
Y76862D03*
X601050Y100008D03*
X603720Y98362D03*
X608620Y94162D03*
X617409D03*
X600220Y96862D03*
X610104Y119342D03*
X614384D03*
X602306Y143077D03*
X612670Y142872D03*
X606040Y153432D03*
X606190Y144002D03*
X602580Y151052D03*
X603019Y146399D03*
X602430Y153862D03*
X612520Y154812D03*
X606260Y161652D03*
X615572Y173942D03*
X615573Y181984D03*
Y179484D03*
X615572Y176442D03*
X614531Y200378D03*
X611030Y188372D03*
X611381Y200378D03*
X613970Y188752D03*
X603340Y208142D03*
X614531Y209878D03*
X609456Y204994D03*
X611381Y209878D03*
X606719Y254966D03*
X611310Y266272D03*
X614200Y265792D03*
X605350Y293092D03*
X605870Y298172D03*
X605560Y303372D03*
X607590Y314732D03*
X609844Y330407D03*
X609040Y317282D03*
X615635Y317637D03*
X614130Y328762D03*
X605305Y331162D03*
X615180Y336812D03*
X608830Y374302D03*
X605898Y372984D03*
X605830Y402782D03*
X609690Y402812D03*
X604779Y423862D03*
X605220Y416362D03*
X610720Y436362D03*
X600800Y430900D03*
X614220Y436362D03*
X610720Y442862D03*
X614220D03*
X600351Y461862D03*
X614220Y452862D03*
Y447862D03*
X602910Y461862D03*
X610720Y457862D03*
X614220D03*
X610720Y452862D03*
X604360Y452120D03*
X614220Y467862D03*
Y472862D03*
Y477862D03*
X610820Y472862D03*
X605469Y467562D03*
X610720Y462862D03*
X614220D03*
X603779Y486922D03*
X601220D03*
X600645Y504362D03*
X606200Y510862D03*
Y514862D03*
X609520Y515162D03*
X611870Y512560D03*
X606220Y517762D03*
X614086Y537624D03*
X607328Y537481D03*
X610797Y537528D03*
X614000Y550800D03*
X607720Y550862D03*
X610720D03*
X613220Y654662D03*
X603317Y738415D03*
X603276Y741375D03*
X614660Y739553D03*
X600460Y744912D03*
X613047Y741492D03*
X602027Y761445D03*
X612407Y769485D03*
X602768Y758385D03*
X612895Y1737108D03*
X616675Y31777D03*
X624633Y49193D03*
X629820Y42562D03*
Y45062D03*
X619562Y49193D03*
X624140Y46672D03*
X622271Y44782D03*
X629000Y67362D03*
X628590Y58622D03*
X622271Y57952D03*
X631546Y85024D03*
X623300Y95762D03*
X620540Y100112D03*
X632300Y104472D03*
X618460Y119342D03*
X626699Y119182D03*
X630951D03*
X624610Y142842D03*
X624520Y154622D03*
X631300Y167872D03*
X631290Y153702D03*
X615970Y161522D03*
X628195Y178414D03*
X628194Y170372D03*
X628195Y175914D03*
X628194Y172872D03*
X630818Y191248D03*
X625862D03*
X620030Y188782D03*
X617370Y188752D03*
X630040D03*
X626640D03*
X628730Y216472D03*
X631730D03*
X627645Y236862D03*
X628730Y220472D03*
Y224472D03*
X631730Y220472D03*
Y224472D03*
X622730Y230362D03*
X630795Y236862D03*
X629564Y256277D03*
X621740Y265952D03*
X618470Y265732D03*
X629564Y253127D03*
X623150Y273172D03*
X621060Y271066D03*
X633150Y301457D03*
X627950Y298897D03*
X625800Y311912D03*
X627600Y309134D03*
X632143Y306575D03*
X630220Y314362D03*
X628294Y317007D03*
X623365Y316742D03*
X631146Y317768D03*
X619474Y331162D03*
X623580Y336429D03*
X619100Y374638D03*
X621720Y373362D03*
X622490Y402162D03*
X628500Y402362D03*
X624220Y411362D03*
X629220D03*
X623220Y426362D03*
X625500Y421362D03*
X629220D03*
Y426362D03*
X629248Y436972D03*
X628900Y431050D03*
X625620Y447862D03*
X625900Y431050D03*
X625620Y442862D03*
X629220D03*
X622220D03*
X617220Y436362D03*
X622220Y452862D03*
Y447862D03*
X629220Y457862D03*
X626400Y462812D03*
X625620Y457862D03*
X622220D03*
X629220Y452862D03*
X625620D03*
X629220Y447862D03*
X626390Y467882D03*
X626210Y478002D03*
X626310Y472902D03*
X629220Y472862D03*
Y477862D03*
Y467862D03*
Y462862D03*
X622220D03*
X622520Y467862D03*
X629220Y487310D03*
Y482862D03*
X622860Y487310D03*
X626720Y482880D03*
X623670Y507862D03*
X629480Y508862D03*
X633000Y508700D03*
X629920Y516652D03*
X623000Y546900D03*
X629220Y643462D03*
X626720D03*
X617252Y739354D03*
X626207Y747585D03*
X623497Y748235D03*
X626017Y745083D03*
X620870Y762072D03*
X617940Y763552D03*
X630417Y757135D03*
X618114Y1258470D03*
X628970Y1670880D03*
X637220Y31462D03*
X646440Y43632D03*
X632463Y43302D03*
X643880Y42142D03*
X647447Y46322D03*
X641200Y46762D03*
X645150Y69508D03*
X645350Y60612D03*
X638500Y57362D03*
X635000D03*
X637000Y68142D03*
X634500Y73422D03*
X645330Y77132D03*
Y72972D03*
X640220Y85542D03*
X634690D03*
X647220Y96929D03*
X639901Y103462D03*
X632640Y107532D03*
X637500Y110362D03*
X640000Y108542D03*
X639970Y113892D03*
X640130Y166362D03*
X642480Y184862D03*
X643170Y171362D03*
X649870Y181942D03*
X645263Y235689D03*
X640295Y234237D03*
X645109Y249202D03*
Y260202D03*
X645876Y296231D03*
X633138Y296766D03*
X643800Y294327D03*
Y298297D03*
X645528Y308623D03*
X645807Y304291D03*
X643800Y306547D03*
Y302247D03*
X645990Y314482D03*
X643800Y310962D03*
X633350Y314362D03*
X647200Y354300D03*
X647100Y357372D03*
X636075Y389862D03*
X649075Y389937D03*
X632620Y389862D03*
X645925Y389937D03*
X638700Y400962D03*
X647700Y399162D03*
X643500Y400962D03*
X643940Y411482D03*
X637220Y411362D03*
X644220Y426362D03*
X640720Y418862D03*
X644220Y421362D03*
X637220Y416362D03*
Y426362D03*
X637195Y421362D03*
X647420Y434162D03*
X640720Y431362D03*
X644000Y438862D03*
X644220Y431362D03*
X638250Y439250D03*
X637220Y431362D03*
X643736Y457214D03*
X644220Y452862D03*
X640820Y457902D03*
X637220Y452862D03*
X640720D03*
X640920Y447862D03*
X644220D03*
X637195Y457862D03*
X637220Y467862D03*
Y472862D03*
Y477862D03*
X644245Y472862D03*
X644220Y467862D03*
Y477862D03*
Y462862D03*
X641235Y477377D03*
X640798Y472934D03*
X637220Y462862D03*
X640820Y467862D03*
X644245Y482862D03*
X640620Y483422D03*
X649218Y504277D03*
X642580Y508172D03*
X645220Y504362D03*
X636960Y516002D03*
X646815Y517974D03*
X648296Y528255D03*
X637020Y522362D03*
X642630Y517870D03*
X640130D03*
X633147Y758595D03*
X641057Y1648659D03*
X647725Y1643719D03*
X643725Y1643467D03*
X645407Y1660425D03*
X648225Y1658482D03*
X642725Y1658562D03*
X635410Y1664220D03*
X637540Y1669480D03*
X636702Y1677610D03*
X641386Y1687283D03*
X645725Y1691182D03*
X640725Y1691452D03*
X650725Y1690682D03*
X639745Y1714362D03*
X646225Y1708169D03*
X642225Y1708457D03*
X648220Y1716912D03*
X636160Y1710662D03*
X648290Y1720052D03*
X639745Y1726362D03*
Y1722362D03*
Y1718362D03*
X648220Y1722921D03*
X632895Y1737108D03*
X651943Y33535D03*
X661534Y41748D03*
X661550Y45133D03*
X654464D03*
X661681Y49193D03*
X654595D03*
X656439Y47264D03*
X659839D03*
X663543Y43328D03*
X656950Y59012D03*
X651680Y73812D03*
X656500Y69662D03*
X661587D03*
X661600Y75562D03*
X656426Y75431D03*
X652153Y98105D03*
X652680Y89712D03*
X651579Y102703D03*
X659000Y89262D03*
X652320Y123362D03*
X651980Y133822D03*
X662498Y124960D03*
X650790Y144982D03*
Y149871D03*
Y140699D03*
X662880Y149912D03*
Y146912D03*
X651730Y177212D03*
X662560Y214152D03*
X662780Y210362D03*
Y205362D03*
Y207862D03*
X659880Y210762D03*
Y205762D03*
Y208262D03*
X650705Y270947D03*
X662891Y357442D03*
X662680Y354362D03*
X651520Y378662D03*
X660690Y408162D03*
X660720Y404362D03*
X658720Y399862D03*
X652000Y402362D03*
X653100Y407862D03*
X655820Y452662D03*
X655800Y461432D03*
X652195Y457862D03*
X655820Y467662D03*
X663000Y489500D03*
X663014Y493860D03*
X655220Y486862D03*
X661865Y505334D03*
X653800Y498740D03*
X663720Y523806D03*
X656877Y514716D03*
X661743Y521166D03*
X665990Y517131D03*
X661220Y526862D03*
X650794Y515039D03*
X657734Y528255D03*
X652577Y1000775D03*
X662282Y1386432D03*
X653690Y1392362D03*
X653761Y1396300D03*
X663187Y1395170D03*
Y1397720D03*
X666303Y1403476D03*
X663687Y1407279D03*
X654540Y1427605D03*
Y1424205D03*
X661100Y1451012D03*
X662660Y1548120D03*
X663410Y1553982D03*
X664590Y1631620D03*
X663043Y1647557D03*
X655307Y1647436D03*
X663097Y1642667D03*
X651725Y1643397D03*
X663118Y1659557D03*
X663145Y1664862D03*
X656725Y1657619D03*
Y1660769D03*
X663118Y1655557D03*
X663043Y1651557D03*
X663145Y1676862D03*
Y1672862D03*
Y1668862D03*
X656973Y1698727D03*
X652712Y1686275D03*
X653420Y1698662D03*
X663645Y1722862D03*
X652895Y1737108D03*
X680200Y39062D03*
X677560Y40572D03*
X672250Y40812D03*
X675854Y49193D03*
X672005Y44119D03*
X669004Y41698D03*
X668800Y45262D03*
X668768Y49193D03*
X666943Y43328D03*
X682290Y46822D03*
X670612Y47264D03*
X674012D03*
X666406Y69508D03*
X675225Y58108D03*
X674035Y74522D03*
X678050Y58157D03*
X673750Y77692D03*
X677820Y89462D03*
X680578Y75992D03*
X674540Y80652D03*
X670800Y85932D03*
X667940Y80142D03*
X671320Y91192D03*
X677790Y104880D03*
X673720Y110362D03*
X674145Y113487D03*
X677978Y119668D03*
Y115668D03*
X675560Y117120D03*
X668300Y132400D03*
X665650Y147692D03*
X673690Y200672D03*
X673300Y211332D03*
X667020Y225762D03*
X673713Y237725D03*
X674731Y359924D03*
X680600Y364282D03*
Y375462D03*
X683100Y369550D03*
X673220Y388362D03*
X677295Y404362D03*
X677195Y408262D03*
X675295Y399862D03*
X670720D03*
X668695Y408362D03*
Y404262D03*
X665870Y433942D03*
X675220Y508862D03*
X680220Y495887D03*
X670220Y503837D03*
X675220D03*
X680220D03*
Y508862D03*
X675220Y521862D03*
Y516852D03*
X670720Y521862D03*
Y516862D03*
X680220Y530362D03*
X673340Y530922D03*
X671607Y742835D03*
X673617Y744735D03*
X669700Y746626D03*
X677887Y742121D03*
X669778Y759929D03*
X670037Y1336396D03*
X664987D03*
X667487D03*
X664987Y1338896D03*
X667487D03*
X670037D03*
Y1333896D03*
X664987D03*
X667487D03*
X664987Y1348896D03*
X667487D03*
X664987Y1346396D03*
X667487D03*
X664987Y1343896D03*
Y1341396D03*
X667487D03*
Y1343896D03*
X670037Y1341396D03*
Y1343896D03*
Y1346396D03*
Y1348896D03*
X673517Y1360815D03*
X676017D03*
X668096Y1360822D03*
X678517Y1360815D03*
X664782Y1383832D03*
Y1381232D03*
Y1378632D03*
Y1386432D03*
X666425Y1414200D03*
X676312Y1411554D03*
X673477Y1409386D03*
X669477Y1406694D03*
X677619Y1408887D03*
X675876Y1406619D03*
X669477Y1409415D03*
X674149Y1434149D03*
X671149D03*
X668649D03*
X674149Y1426149D03*
Y1431149D03*
Y1428649D03*
X671149Y1426149D03*
X668649D03*
X671149Y1431149D03*
X668649Y1428649D03*
Y1431149D03*
X671149Y1428649D03*
X677319Y1428359D03*
Y1433359D03*
Y1430859D03*
X667926Y1547018D03*
X682160Y1548040D03*
X665410Y1548180D03*
X679192Y1564252D03*
X679207Y1560482D03*
X678877Y1566798D03*
X678621Y1571072D03*
X678610Y1582154D03*
X666560Y1581000D03*
X678515Y1573910D03*
X678619Y1579070D03*
X666600Y1584900D03*
X678900Y1595400D03*
X678771Y1585945D03*
X666700Y1595500D03*
X678900Y1589800D03*
X666700Y1591900D03*
X678900Y1592600D03*
X666700Y1588500D03*
X679640Y1617520D03*
Y1614000D03*
X679270Y1604040D03*
X675710Y1620320D03*
X671112Y1639962D03*
X673420Y1650057D03*
X671290Y1646320D03*
X676648Y1657380D03*
X668695Y1662235D03*
X671620Y1670862D03*
X671610Y1673792D03*
X671620Y1668303D03*
X677940Y1670110D03*
X678490Y1695660D03*
X674195Y1708362D03*
Y1712362D03*
X675120Y1716242D03*
X669120Y1718862D03*
X674195Y1728362D03*
X672270Y1721612D03*
X672895Y1737108D03*
X674195Y1732362D03*
X687120Y39632D03*
X692289Y40633D03*
X689940Y38952D03*
X696838Y45112D03*
X686854Y43701D03*
X692380Y43532D03*
X696800Y42108D03*
X696838Y47940D03*
X683440Y42832D03*
X687344Y46940D03*
X692389Y46439D03*
X694751Y70212D03*
X690027Y70142D03*
X685780Y70022D03*
X682941Y69982D03*
X699475D03*
X685968Y58157D03*
X694400D03*
X681980D03*
X690510Y59132D03*
X696700Y72462D03*
X692389Y72692D03*
X687664Y73202D03*
X687050Y79212D03*
X685230Y76952D03*
X683820Y79192D03*
X682890Y72642D03*
X696370Y78512D03*
X696727Y81552D03*
Y84052D03*
X681053Y104668D03*
X695720Y102162D03*
X694220Y104862D03*
X684953Y104968D03*
X688019Y109845D03*
X687030Y113090D03*
X687034Y115896D03*
X694390Y133682D03*
X697615Y123697D03*
X684520Y152482D03*
X688520D03*
X692520D03*
X687238Y171071D03*
X686760Y222912D03*
X685600Y364282D03*
X690600D03*
X695600D03*
X685600Y375462D03*
X690600D03*
X695600D03*
X688220Y388362D03*
X685210Y388852D03*
X694920Y388797D03*
X692330Y388751D03*
X685220Y391652D03*
X692402Y391250D03*
X697220Y404362D03*
X697120Y408262D03*
X695220Y399862D03*
X685270Y408362D03*
Y404262D03*
X692400Y404682D03*
X694720Y491962D03*
X690720D03*
X683320Y490662D03*
X685220Y495887D03*
X690580Y482992D03*
X694510Y482942D03*
X686120Y481862D03*
X695220Y495887D03*
X690220D03*
X695220Y508862D03*
X685220D03*
X690220Y506362D03*
X685220Y503837D03*
X690220Y508882D03*
X690330Y503530D03*
X695257Y503847D03*
X695220Y516852D03*
X690220D03*
X685220D03*
X690220Y519662D03*
X695220D03*
X689720Y530862D03*
X695220Y530662D03*
X684357Y742345D03*
X683457Y745175D03*
X692784Y1298845D03*
X696810Y1300162D03*
X692280Y1302532D03*
X684555Y1338896D03*
X689605Y1336396D03*
Y1338896D03*
X687105Y1336396D03*
X684555D03*
X687105Y1338896D03*
X689605Y1333896D03*
X687105D03*
X684555D03*
X689605Y1348896D03*
X687105D03*
X689605Y1346396D03*
X687105D03*
X684555Y1341396D03*
Y1343896D03*
Y1346396D03*
Y1348896D03*
X689605Y1341396D03*
Y1343896D03*
X687105Y1341396D03*
Y1343896D03*
X686426Y1360822D03*
X695022Y1361990D03*
X696462Y1386122D03*
X691351Y1380922D03*
X688751D03*
X691240Y1383522D03*
X693851D03*
Y1378322D03*
Y1380922D03*
X691351Y1378322D03*
X688751D03*
X693851Y1386122D03*
X696462Y1378322D03*
Y1383522D03*
Y1380922D03*
X696272Y1404560D03*
X691777Y1405594D03*
Y1399794D03*
X689577Y1401194D03*
X687511Y1402924D03*
X691777Y1402694D03*
X689677Y1404194D03*
X687511Y1405824D03*
X694596Y1396198D03*
X694129Y1420283D03*
X696754Y1419809D03*
X691129Y1420283D03*
X685015Y1438475D03*
X696940Y1437955D03*
X681899Y1434049D03*
Y1426049D03*
Y1431049D03*
Y1428549D03*
X694129Y1423303D03*
X691129D03*
X696694Y1427949D03*
Y1425449D03*
Y1430449D03*
X696784Y1422614D03*
X683930Y1552562D03*
Y1555062D03*
Y1557562D03*
X692100Y1567190D03*
X689875Y1577913D03*
X692026Y1580490D03*
X697122Y1632667D03*
X683592Y1634844D03*
X697197Y1644667D03*
Y1640667D03*
X697122Y1636667D03*
X689200Y1648843D03*
X686220Y1640667D03*
X689128Y1652262D03*
X697595Y1666862D03*
X692595Y1670862D03*
X687045Y1673362D03*
X701838Y45112D03*
X706370Y46782D03*
X701838Y42202D03*
Y47940D03*
X703900Y72112D03*
X701400D03*
X700610Y57782D03*
X713000Y69662D03*
X697720Y58162D03*
X710200Y69662D03*
X706867Y58197D03*
X703100Y58157D03*
X700741Y83050D03*
X712500Y79862D03*
X700500Y74862D03*
X698710Y86035D03*
X705390Y85792D03*
X703000Y84862D03*
X712433Y103308D03*
X706720Y100462D03*
X699220Y102162D03*
X702720D03*
X701220Y104862D03*
X697720D03*
X712733Y117488D03*
Y114588D03*
X712290Y106722D03*
X706673Y122762D03*
X703520Y122540D03*
X704880Y133643D03*
X712340Y128093D03*
X700600Y125309D03*
X707008Y125804D03*
X705800Y167788D03*
X701926Y166535D03*
X705800Y171188D03*
X701926Y178346D03*
Y184252D03*
Y172441D03*
X704770Y182999D03*
Y179599D03*
X701926Y190157D03*
Y196063D03*
Y201968D03*
X704770Y194810D03*
Y191410D03*
X701926Y207874D03*
Y213779D03*
X704770Y218432D03*
Y206621D03*
Y215032D03*
Y203221D03*
X701926Y219685D03*
X700600Y364282D03*
X705600D03*
X710600D03*
X709000Y354000D03*
X715600Y363900D03*
X705700Y361400D03*
X700600Y375462D03*
X705600D03*
X709400Y378200D03*
X713220Y378362D03*
X711200Y396500D03*
X709160Y386730D03*
X713220Y388362D03*
X707400Y396200D03*
X713220Y399862D03*
X705195Y408362D03*
Y404262D03*
X705780Y411022D03*
X712770Y406822D03*
X705720Y488862D03*
X703220Y490362D03*
X705720Y484862D03*
X711220Y503842D03*
X705220D03*
Y508862D03*
X711220Y508882D03*
X710720Y521362D03*
X705220D03*
X701757Y521324D03*
X711220Y516852D03*
X705220D03*
Y530362D03*
X698600Y530700D03*
X710940Y591172D03*
X698602Y580536D03*
X705240Y594020D03*
X702740D03*
X712060Y638542D03*
X708680Y638812D03*
X708310Y646032D03*
X704320Y645262D03*
X701917Y742865D03*
X704000Y740862D03*
X700500Y745862D03*
X703545Y745907D03*
X703755Y1290545D03*
X711720Y1286162D03*
X707720Y1290162D03*
X705720Y1286662D03*
X708795Y1303701D03*
X704795Y1294559D03*
X707320Y1301162D03*
X708137Y1336396D03*
Y1338896D03*
X703087Y1336396D03*
X705587D03*
Y1338896D03*
X703087D03*
X708137Y1333896D03*
X705587D03*
X703087D03*
Y1346396D03*
X705587D03*
X703087Y1348896D03*
X705587D03*
X708137Y1341396D03*
Y1343896D03*
X705587Y1341396D03*
X703087D03*
Y1343896D03*
X705587D03*
X708137Y1348896D03*
Y1346396D03*
X698094Y1361947D03*
X706239Y1360822D03*
X712060Y1360815D03*
X699062Y1380922D03*
Y1383522D03*
Y1378322D03*
X701662Y1380922D03*
Y1383522D03*
Y1378322D03*
X699062Y1386122D03*
X701662D03*
X701330Y1395195D03*
Y1397695D03*
X704446Y1403476D03*
X699262Y1413970D03*
X704568Y1414119D03*
X701830Y1407326D03*
X711620Y1409386D03*
X707620Y1406694D03*
Y1409660D03*
X699754Y1419809D03*
X706680Y1437535D03*
X701730Y1437855D03*
X711440Y1436905D03*
X699694Y1427949D03*
Y1425449D03*
Y1430449D03*
X699784Y1422614D03*
X712222Y1570703D03*
X702112Y1583683D03*
Y1571683D03*
Y1575683D03*
Y1579683D03*
X711102Y1575683D03*
X712582Y1584843D03*
X704497Y1598927D03*
X702112Y1587683D03*
Y1591683D03*
X715775Y1599024D03*
X702112Y1595683D03*
X711350Y1590720D03*
X711780Y1614590D03*
X704370Y1604580D03*
X706103Y1617107D03*
X708857Y1613462D03*
X709111Y1618842D03*
X710570Y1629890D03*
X708830Y1623115D03*
X705516Y1620296D03*
X710540Y1636070D03*
X708999Y1646762D03*
X703719Y1646768D03*
X697595Y1658862D03*
X704433Y1657964D03*
X697595Y1662862D03*
X700460Y1660918D03*
X709678Y1658485D03*
X697770Y1680810D03*
X702462Y1673258D03*
X697730Y1677460D03*
X704759Y1677001D03*
X717313Y-27626D03*
X714015Y-27612D03*
X720308Y-26403D03*
X723041Y-13200D03*
Y-9800D03*
X725537Y-23978D03*
Y-19022D03*
Y-13978D03*
Y-9022D03*
X714015Y-21457D03*
X717313Y-21471D03*
Y-17597D03*
X717298Y-15082D03*
X714015Y-17583D03*
X714030Y-15068D03*
X714015Y-11428D03*
X717313Y-11442D03*
X717298Y-25111D03*
X714030Y-25097D03*
X720308Y-16374D03*
X717313Y-7568D03*
X717298Y-5053D03*
X714015Y-7554D03*
X714030Y-5039D03*
X720308Y-6345D03*
X724620Y40062D03*
X722580Y49182D03*
X728980Y39872D03*
X728720Y43562D03*
X719820Y45862D03*
X717320Y44062D03*
X729293Y58062D03*
X724644Y58362D03*
X719949Y58862D03*
X715990Y69662D03*
X725740Y69580D03*
X721990Y69762D03*
X718900Y69662D03*
X727700Y60562D03*
X728591Y71960D03*
X722415Y77862D03*
X718425Y77882D03*
X728090Y75132D03*
X719100Y85262D03*
X728028Y101968D03*
X728023Y98058D03*
X727518Y90984D03*
X728028Y105468D03*
X715933Y117488D03*
Y114588D03*
X729933Y108388D03*
X728733Y132088D03*
Y129288D03*
X720433Y135088D03*
X717433D03*
X728733Y126388D03*
X719933Y124488D03*
X723133D03*
X724133Y141288D03*
X715940Y157362D03*
X718213Y159241D03*
X720633Y160788D03*
X719194Y172909D03*
X714202D03*
X719194Y177865D03*
X714202D03*
X719194Y184909D03*
X714202D03*
X716698Y185687D03*
Y173687D03*
Y177087D03*
X719194Y189865D03*
X714202D03*
X719194Y196409D03*
X714202D03*
X719194Y201365D03*
X714202D03*
X716698Y197187D03*
Y200587D03*
Y189087D03*
X719194Y208243D03*
X714202D03*
X719194Y213199D03*
X714202D03*
X716698Y209021D03*
Y212421D03*
X717020Y220862D03*
X719720Y220142D03*
X727720Y356362D03*
X722500Y365500D03*
X724897Y353887D03*
X721989Y351234D03*
X727000Y365500D03*
X731400D03*
X725220Y380787D03*
X715600Y375462D03*
X722500Y374100D03*
X727000D03*
X731400Y375000D03*
X718220Y388362D03*
X718720Y381892D03*
X728220Y388362D03*
X715220Y404362D03*
X715120Y408262D03*
X723195Y408362D03*
Y404262D03*
X725220Y399862D03*
X713820Y488762D03*
Y484662D03*
X723220Y508882D03*
X717220D03*
X729220D03*
Y503842D03*
X723220D03*
X717220D03*
X714000Y496132D03*
X723120Y525362D03*
X728220Y521362D03*
X717220D03*
X722720D03*
X717296Y525407D03*
X723220Y516852D03*
X729220D03*
X717220D03*
X729212Y531700D03*
X729200Y588952D03*
X729328Y583076D03*
X729295Y586113D03*
X725207Y579371D03*
X722707D03*
X715860Y585540D03*
X714320Y597462D03*
X720240Y598292D03*
X715420Y639162D03*
X719190Y646642D03*
X717720Y643262D03*
X715220D03*
X723340Y642922D03*
X714087Y745865D03*
X720697Y765862D03*
X723460Y1245632D03*
X713836Y1283689D03*
X714720Y1286162D03*
X723054Y1333896D03*
X725604D03*
X728104D03*
X725604Y1338896D03*
X723054Y1336396D03*
X725604D03*
X728104Y1338896D03*
Y1336396D03*
X723054Y1338896D03*
X725604Y1346396D03*
X728104D03*
X725604Y1348896D03*
X728104D03*
X725604Y1343896D03*
Y1341396D03*
X728104Y1343896D03*
Y1341396D03*
X723054Y1348896D03*
Y1346396D03*
Y1343896D03*
Y1341396D03*
X724969Y1360822D03*
X714560Y1360815D03*
X717060D03*
X729443Y1361224D03*
X726694Y1381583D03*
Y1378983D03*
X728044Y1384083D03*
X729294Y1381583D03*
Y1378983D03*
X725654Y1405824D03*
Y1402924D03*
X727720Y1401194D03*
X727820Y1404194D03*
X714455Y1411554D03*
X715762Y1408887D03*
X714019Y1406619D03*
X717300Y1547370D03*
X715792Y1567461D03*
X720370Y1566910D03*
X723520Y1561604D03*
X724712Y1566820D03*
X716612Y1584635D03*
X717152Y1570093D03*
X728977Y1574453D03*
X717402Y1574433D03*
X724465Y1580092D03*
X722465Y1582092D03*
X726465D03*
X723942Y1574123D03*
X718230Y1600372D03*
X724465Y1590950D03*
X722465Y1588950D03*
X726465D03*
X729052Y1602518D03*
X726092Y1598483D03*
X720987Y1599568D03*
X725378Y1614503D03*
X719770Y1614590D03*
X715780D03*
X723542Y1612702D03*
X721488Y1610945D03*
X725910Y1611900D03*
X716688Y1610055D03*
X719168Y1612016D03*
X722040Y1623970D03*
X713791Y1629816D03*
X714203Y1639776D03*
X721345Y1647300D03*
X716140Y1649895D03*
X718195Y1647300D03*
X714203Y1642926D03*
X729150Y1641690D03*
X726810Y1652430D03*
X726830Y1655380D03*
X714071Y1663842D03*
X722630Y1655740D03*
X724500Y1676500D03*
Y1680400D03*
X718758Y1673800D03*
X745900Y40362D03*
X733314Y40862D03*
X740100Y41162D03*
X744987Y49062D03*
X742840Y39832D03*
X736790D03*
X746100Y46262D03*
X736620Y45262D03*
X745130Y69508D03*
X738043D03*
X730957D03*
X731330Y60712D03*
X745474Y57932D03*
X733642Y58062D03*
X741377Y57932D03*
X737595D03*
X732793Y71436D03*
X736193D03*
X742620Y71762D03*
X735880Y60662D03*
X730820Y84062D03*
X740819Y82362D03*
X737623Y98858D03*
X734523Y98758D03*
X736720Y101662D03*
X745035Y94632D03*
X735770Y94988D03*
X739823Y91052D03*
X735733Y111988D03*
X741308Y108742D03*
X738600Y136600D03*
X736060Y145532D03*
X740220Y145362D03*
X745725Y167537D03*
X732720Y231362D03*
X734220Y238362D03*
X745685Y265322D03*
Y269322D03*
X744247Y312598D03*
X741800Y363200D03*
X742090Y356082D03*
X735600Y351400D03*
X735800Y365500D03*
X732700Y351500D03*
X740200Y375100D03*
X736220Y380787D03*
X742720Y380262D03*
X735800Y375000D03*
X733220Y388362D03*
X738220D03*
X742160Y396452D03*
X738220Y383862D03*
X743720Y404362D03*
X743820Y408262D03*
X745720Y399862D03*
X735220Y410842D03*
X735745Y408362D03*
Y404262D03*
X733720Y399862D03*
X743980Y443482D03*
X740740Y473822D03*
X741420Y494162D03*
X747600Y506592D03*
X735220Y508862D03*
X745220Y503842D03*
X730070Y506212D03*
X744630Y506529D03*
X735220Y503842D03*
X735430Y516862D03*
X745220Y522362D03*
Y516852D03*
X730220Y523362D03*
X740840Y521982D03*
X735173Y521362D03*
X745220Y530362D03*
X736480Y531722D03*
X738980D03*
X733922Y531712D03*
X733117Y580071D03*
Y582571D03*
X733134Y585672D03*
X736710Y603842D03*
Y607242D03*
X739206Y608020D03*
Y603064D03*
X735620Y613862D03*
X730690Y655532D03*
X744538Y746524D03*
X737609Y744282D03*
X730889Y746834D03*
X740820Y741762D03*
X737299Y766887D03*
X737784Y1360017D03*
X730752Y1384080D03*
X731794Y1381583D03*
Y1378983D03*
X732238Y1388343D03*
X738810Y1396665D03*
X741540Y1396585D03*
X739170Y1405655D03*
X741670Y1405675D03*
X729920Y1405594D03*
X732226Y1396212D03*
X729920Y1399794D03*
Y1402694D03*
X738170Y1414185D03*
X740760Y1414165D03*
X733336Y1568341D03*
Y1565341D03*
Y1559341D03*
Y1562341D03*
X730336Y1559341D03*
Y1562341D03*
X745336D03*
Y1559341D03*
Y1565341D03*
Y1568341D03*
X742336Y1562341D03*
Y1559341D03*
Y1565341D03*
Y1568341D03*
X739336Y1562341D03*
Y1559341D03*
Y1565341D03*
Y1568341D03*
X736336D03*
Y1565341D03*
Y1559341D03*
Y1562341D03*
X733336Y1574341D03*
Y1571341D03*
X745336Y1574341D03*
Y1571341D03*
X742336Y1574341D03*
Y1571341D03*
X739336Y1574341D03*
Y1571341D03*
X736336D03*
Y1574341D03*
X730282Y1580391D03*
X741382Y1585251D03*
Y1580121D03*
X735882Y1580391D03*
X730282Y1590651D03*
Y1585521D03*
X735882Y1590651D03*
X741382Y1590691D03*
X732504Y1600321D03*
Y1597321D03*
X744504D03*
Y1600321D03*
X741504Y1597321D03*
Y1600321D03*
X735504Y1597321D03*
Y1600321D03*
X738504Y1597321D03*
Y1600321D03*
X744504Y1609521D03*
Y1612521D03*
X741504Y1609521D03*
X738504D03*
X735504D03*
X741504Y1612521D03*
X738504D03*
X735504D03*
X732504Y1603321D03*
Y1606321D03*
X744504Y1603321D03*
Y1606321D03*
X741504Y1603321D03*
Y1606321D03*
X738504Y1603321D03*
X735504D03*
X738504Y1606321D03*
X735504D03*
X735300Y1648760D03*
X744800Y1664840D03*
X737080Y1655820D03*
X735080Y1662980D03*
X740840Y1655590D03*
X742655Y1682362D03*
Y1678362D03*
X732705Y1669450D03*
X732895Y1737108D03*
X758606Y23797D03*
X747487Y49062D03*
X754620Y51602D03*
X758620D03*
X752720Y59002D03*
X749477Y57932D03*
X755700Y59942D03*
Y62442D03*
X758200Y59942D03*
Y62442D03*
X760700Y59942D03*
Y62442D03*
X747487Y71429D03*
X754219Y75707D03*
X757693Y100653D03*
Y96423D03*
X750700Y106642D03*
X754800Y97082D03*
X750033Y92888D03*
Y89988D03*
X757340Y92562D03*
X754633Y108288D03*
Y105288D03*
X748033Y116288D03*
X747230Y108572D03*
X760390Y111810D03*
X762198Y129684D03*
Y126684D03*
X762172Y123898D03*
X751220Y137864D03*
X758110Y172636D03*
X747200Y251500D03*
X761720Y283262D03*
X748085Y278942D03*
X758360Y276122D03*
X757150Y280592D03*
X758720Y283262D03*
X759920Y280562D03*
X754290Y286632D03*
X755200Y296062D03*
X758412Y298790D03*
X755305Y298847D03*
X748820Y284562D03*
X758390Y295450D03*
X748498Y309640D03*
X759637Y311585D03*
X757936Y303908D03*
X760670Y317432D03*
X747554Y384962D03*
X757430Y408212D03*
X760469Y442647D03*
X759940Y438232D03*
X750290Y462162D03*
X758420Y447662D03*
X757365Y459862D03*
X752500Y495762D03*
X757238Y483862D03*
X756642Y496522D03*
Y501744D03*
X751220Y522362D03*
Y516852D03*
X759790Y525522D03*
X755940Y516862D03*
X756650Y526072D03*
X761710Y517651D03*
X751220Y530362D03*
X757020Y530462D03*
X759820D03*
X754220D03*
X753137Y766625D03*
X762345Y1284542D03*
Y1287542D03*
Y1290542D03*
X762205Y1293272D03*
X757720Y1375462D03*
Y1384062D03*
X757779Y1390645D03*
X758020Y1397862D03*
X758420Y1406862D03*
X757542Y1420684D03*
X758120Y1414762D03*
X755420Y1426262D03*
Y1422862D03*
X748336Y1562341D03*
Y1559341D03*
Y1565341D03*
Y1568341D03*
X751336D03*
Y1565341D03*
Y1559341D03*
Y1562341D03*
X748336Y1574341D03*
Y1571341D03*
X760112Y1579183D03*
X749612Y1579023D03*
X749652Y1586407D03*
X760152Y1583183D03*
X760112Y1592183D03*
Y1587183D03*
X747504Y1600321D03*
X749612Y1594683D03*
X758360Y1589661D03*
X747504Y1609521D03*
Y1612521D03*
X750504D03*
Y1609521D03*
X747504Y1603321D03*
Y1606321D03*
X761716Y1661194D03*
X758830Y1674823D03*
X751620Y1674312D03*
X761770Y1695347D03*
X755859Y1686090D03*
X759859D03*
X755183Y1709850D03*
X759359Y1729520D03*
X752875Y1726670D03*
X752895Y1737108D03*
X765606Y44894D03*
X774059Y68912D03*
X769474Y75360D03*
X765858Y87340D03*
X762368Y84088D03*
X769284Y103895D03*
X767061Y99959D03*
X767045Y95960D03*
X767028Y91490D03*
X776730Y117479D03*
X773943Y114633D03*
X771131Y111788D03*
X769775Y107977D03*
X766769Y140138D03*
X773420Y143462D03*
X771774Y167518D03*
X772328Y153728D03*
X771426Y158026D03*
X764850Y249792D03*
X766320Y264892D03*
X763320D03*
X771630Y258102D03*
X762420Y280562D03*
X777420Y277962D03*
X773220Y296262D03*
X769789Y296231D03*
X777467Y296315D03*
X769860Y302462D03*
X772866Y311558D03*
X771377Y314139D03*
X777283Y320892D03*
X768490Y354942D03*
X777420Y354962D03*
X774490Y354942D03*
X771960Y375162D03*
X767960Y369662D03*
X776100Y375100D03*
X776000Y369662D03*
X764000D03*
X766195Y393212D03*
X773245Y398212D03*
X766195Y403212D03*
Y413212D03*
X773245Y403212D03*
Y408212D03*
X768910Y403260D03*
X771050Y416940D03*
X766195Y418212D03*
Y423212D03*
Y428212D03*
X768701Y418662D03*
X774982Y446908D03*
X772365Y454862D03*
X765315D03*
Y459862D03*
X772365D03*
X765360Y475412D03*
X765315Y464862D03*
X765335Y469552D03*
X772364Y475062D03*
X772365Y469862D03*
X765315Y479862D03*
Y488862D03*
X772365D03*
X776170Y493422D03*
X766510Y493452D03*
X765386Y483572D03*
X773530Y507062D03*
X765810Y506342D03*
X769745Y502600D03*
X775378Y502502D03*
X765521Y525364D03*
X769220Y530362D03*
X765720D03*
X772220D03*
X777020D03*
X772020Y746562D03*
X774384Y744088D03*
X762562Y746444D03*
X769921Y742095D03*
X767421D03*
X764921D03*
X775317Y764025D03*
X763747Y764335D03*
X769337Y760775D03*
X762617Y758885D03*
X765345Y1284542D03*
X768335Y1284612D03*
X765345Y1287542D03*
Y1290542D03*
X768335Y1287612D03*
Y1290612D03*
X765205Y1293272D03*
X768195Y1293342D03*
X778005Y1294092D03*
X768520Y1379962D03*
Y1384062D03*
Y1375462D03*
X768620Y1392762D03*
Y1397262D03*
X775375Y1403561D03*
X767820Y1410262D03*
Y1414762D03*
X763152Y1581893D03*
Y1577893D03*
Y1573793D03*
X773952Y1580493D03*
X768714Y1571203D03*
X769452Y1584393D03*
X770252Y1587268D03*
X763152Y1590893D03*
Y1594893D03*
X774052Y1590293D03*
X776922Y1590444D03*
X776052Y1611893D03*
X764920Y1695347D03*
X766880Y1689020D03*
X763359Y1729520D03*
X766603Y1721797D03*
X772208Y1731911D03*
X785095Y49388D03*
X785180Y120947D03*
X792680D03*
X790180D03*
X787680D03*
X783940Y118637D03*
X786440D03*
X788940D03*
X781440D03*
X782553Y150031D03*
Y152531D03*
X779893Y147521D03*
Y150021D03*
X785135Y281822D03*
Y267822D03*
X780820Y278262D03*
X785135Y274822D03*
X785200Y271400D03*
X780617Y296345D03*
X794220Y296062D03*
X785220Y284762D03*
X792943Y312642D03*
X784415Y313734D03*
X779120Y306162D03*
X793820Y304962D03*
X779120Y303410D03*
Y308755D03*
X794600Y360600D03*
X785000Y355000D03*
X779920Y354962D03*
X782420D03*
X790120Y354862D03*
X792620D03*
X787600Y354900D03*
X787925Y387900D03*
X795520Y393462D03*
X791075Y388000D03*
X781195Y393212D03*
X781320Y398212D03*
X787720Y408362D03*
X781195Y413212D03*
Y423212D03*
X785560Y417902D03*
X781195Y418212D03*
X791590Y417050D03*
X788120Y422942D03*
X791040Y422892D03*
X793660Y422842D03*
X785720Y427862D03*
X789230Y414942D03*
X780020Y438287D03*
X781410Y431822D03*
X780020Y441437D03*
Y445287D03*
X787320Y444862D03*
Y439862D03*
X791582Y435352D03*
X781205Y454402D03*
X780315Y459862D03*
X787320Y454862D03*
Y449862D03*
Y459862D03*
X787360Y469862D03*
X780340Y468982D03*
Y474862D03*
X786220Y464862D03*
X796315Y469290D03*
X780315Y464862D03*
X783340Y474802D03*
X782690Y488862D03*
X793220Y493362D03*
X781170Y493422D03*
X785800Y482762D03*
X793875Y483262D03*
X778670Y493422D03*
X783600Y502462D03*
X793673Y512862D03*
X783450Y522462D03*
X783400Y511902D03*
X789720Y589862D03*
X785220Y581362D03*
X789720Y587362D03*
X792720Y589862D03*
X789720Y581862D03*
X791720Y593862D03*
X793720Y595862D03*
X783100Y593582D03*
X791969Y618384D03*
X794720Y617862D03*
X783507Y761875D03*
X794157Y761295D03*
X782515Y766702D03*
X791140Y761693D03*
X792045Y1284542D03*
Y1290542D03*
Y1287542D03*
X791905Y1293272D03*
X788225Y1388683D03*
X791260Y1388662D03*
X790380Y1432132D03*
X784352Y1568293D03*
Y1565293D03*
Y1559293D03*
Y1562293D03*
X781352Y1568293D03*
Y1565293D03*
Y1559293D03*
Y1562293D03*
X793352D03*
Y1559293D03*
Y1565293D03*
Y1568293D03*
X790352Y1562293D03*
Y1559293D03*
Y1565293D03*
Y1568293D03*
X787352D03*
Y1565293D03*
Y1559293D03*
Y1562293D03*
X784352Y1574293D03*
Y1571293D03*
X781352Y1574293D03*
Y1571293D03*
X793352Y1574293D03*
Y1571293D03*
X790352Y1574293D03*
Y1571293D03*
X787352D03*
Y1574293D03*
X788079Y1580393D03*
X782479D03*
X793579D03*
X788079Y1590653D03*
X782479D03*
Y1585523D03*
X793579Y1590653D03*
Y1585523D03*
X785052Y1600693D03*
Y1597693D03*
X782052D03*
Y1600693D03*
X794052D03*
X788052D03*
X791052D03*
X794052Y1597693D03*
X788052D03*
X791052D03*
X785052Y1607793D03*
X782052D03*
X779052D03*
X785052Y1611893D03*
X782052D03*
X779052D03*
X794052Y1607793D03*
X791052D03*
X788052D03*
X797052Y1611893D03*
X794052D03*
X788052D03*
X791052D03*
X785052Y1603693D03*
X782052D03*
X794052D03*
X788052D03*
X791052D03*
X792208Y1731911D03*
X805095Y49388D03*
X797443Y271469D03*
X806300Y279662D03*
X809700Y273562D03*
X808800Y267900D03*
X810920Y280062D03*
X795190Y298572D03*
X797924Y298358D03*
X798620Y312773D03*
X806450Y310362D03*
X803620Y302962D03*
X805870Y304812D03*
X799720Y300462D03*
X795920Y312662D03*
X803280Y354982D03*
X800646Y354921D03*
X809800Y360600D03*
X802200D03*
X806588Y351097D03*
X795220Y354862D03*
X806000Y360600D03*
X798400D03*
X805910Y355012D03*
X797900Y354800D03*
X799800Y368700D03*
X810781Y372615D03*
X802220Y393727D03*
X803150Y408512D03*
X795600Y402500D03*
X795520Y398212D03*
X800352Y408389D03*
X803120Y428762D03*
X797720Y428412D03*
X798370Y439932D03*
X799458Y431217D03*
X802010Y439940D03*
X802790Y433832D03*
X795320Y439862D03*
X805720Y432902D03*
X801750Y444330D03*
X795320Y444862D03*
X810860Y454862D03*
X802810D03*
X795320D03*
Y449862D03*
X802810Y464862D03*
Y449862D03*
X810860Y459862D03*
X802810D03*
X795320D03*
X810860Y449862D03*
X795370Y474862D03*
X798990D03*
X802865D03*
X795320Y464862D03*
X810815Y474862D03*
X810860Y464862D03*
X810815Y469862D03*
X807220Y493362D03*
X801940Y485932D03*
X804510Y486122D03*
X809510D03*
X799230Y485922D03*
X812510Y486422D03*
X801567Y512942D03*
X802790Y495652D03*
X805470Y510522D03*
X807640Y506672D03*
X808100Y509900D03*
X797420Y512503D03*
X805445Y587582D03*
X798720Y585362D03*
X810720Y586862D03*
X811143Y605265D03*
X798220Y597362D03*
X808860Y603802D03*
X807945Y594362D03*
X803220D03*
X797200Y599883D03*
X797720Y617862D03*
X795720Y614862D03*
X796702Y761195D03*
X810850Y770272D03*
X799637Y763625D03*
X799577Y760985D03*
X807000Y757562D03*
X798035Y1284612D03*
X795045Y1284542D03*
X798035Y1290612D03*
Y1287612D03*
X795045Y1290542D03*
Y1287542D03*
X797895Y1293342D03*
X794905Y1293272D03*
X806323Y1343076D03*
X812130Y1343022D03*
X809210Y1343062D03*
X804100Y1435010D03*
X800000Y1431100D03*
X799352Y1562293D03*
Y1559293D03*
Y1565293D03*
Y1568293D03*
X796352Y1562293D03*
Y1559293D03*
Y1565293D03*
Y1568293D03*
X799352Y1574293D03*
Y1571293D03*
X796352Y1574293D03*
Y1571293D03*
X804652Y1581793D03*
Y1573793D03*
X812652Y1577793D03*
X801652Y1584539D03*
X812698Y1587047D03*
X804652Y1597793D03*
Y1585993D03*
X799152Y1586507D03*
X804652Y1589793D03*
X797052Y1607793D03*
X804652Y1609793D03*
X825095Y49388D03*
X819114Y115223D03*
X827114D03*
X823114D03*
X821118Y134632D03*
X825698Y139062D03*
X824498Y145198D03*
X814570Y145952D03*
X814531Y139851D03*
X820900Y147112D03*
X813900Y269698D03*
X816220Y277162D03*
X827403Y286625D03*
X816420Y287062D03*
X813293D03*
X826300Y311962D03*
X823800D03*
X813855Y354008D03*
X820936Y356956D03*
X821164Y372312D03*
X818000Y378800D03*
X813210Y374292D03*
X815710D03*
X825003Y389012D03*
Y397276D03*
X819220Y397664D03*
X824980Y405260D03*
Y409260D03*
Y413260D03*
X819220Y412264D03*
X823600Y421194D03*
X821720Y428437D03*
X815310Y440100D03*
X818500Y451700D03*
X816810Y464862D03*
X816500Y476800D03*
X825100Y468900D03*
X824860Y464862D03*
X816400Y472900D03*
X820720Y493862D03*
X822415Y479600D03*
X821720Y511082D03*
X814305Y499503D03*
X819320Y502347D03*
X821720Y527082D03*
Y519082D03*
X815650Y516807D03*
X821720Y515082D03*
Y523082D03*
X815040Y590772D03*
X820220Y586862D03*
X814220Y582530D03*
X823720Y594862D03*
X820470Y595112D03*
X815120Y593582D03*
X820613Y744641D03*
X823589Y746924D03*
X814800Y760922D03*
X822442Y762369D03*
X822374Y757039D03*
X814770Y763874D03*
X815789Y1008845D03*
X814234Y1340465D03*
X826090Y1334362D03*
Y1339362D03*
Y1329362D03*
Y1344362D03*
X820920Y1344342D03*
X818420D03*
X823352Y1565293D03*
Y1562293D03*
Y1559293D03*
Y1568293D03*
X826352Y1565293D03*
Y1562293D03*
Y1559293D03*
Y1568293D03*
X823352Y1571293D03*
Y1574293D03*
X826352Y1571293D03*
Y1574293D03*
X824479Y1580393D03*
X815652Y1582570D03*
Y1573793D03*
X813352Y1590893D03*
X812652Y1593793D03*
X824479Y1590653D03*
Y1585523D03*
X824052Y1597693D03*
Y1600693D03*
X827052D03*
Y1597693D03*
X815551Y1593793D03*
X818652Y1590444D03*
X812652Y1605793D03*
X824052Y1611893D03*
Y1607793D03*
Y1603693D03*
X827052Y1611893D03*
Y1607793D03*
Y1603693D03*
X821052Y1611893D03*
Y1607793D03*
X818052Y1611893D03*
X812652Y1601793D03*
X812208Y1731911D03*
X842497Y6022D03*
X834273Y2374D03*
X834258Y4889D03*
X830975Y2388D03*
X830990Y4903D03*
X837268Y3597D03*
X840001Y20200D03*
Y16800D03*
X842497Y16022D03*
Y20978D03*
Y10978D03*
X834273Y22432D03*
X830975Y22446D03*
Y8543D03*
X834273Y8529D03*
Y12403D03*
X834258Y14918D03*
X830975Y12417D03*
X830990Y14932D03*
X830975Y18572D03*
X834273Y18558D03*
X837268Y13626D03*
X834258Y24947D03*
X830990Y24961D03*
X837268Y23655D03*
X836779Y68008D03*
X836126Y62681D03*
X828600Y61752D03*
X839898Y87248D03*
X837791Y85186D03*
X841584Y94181D03*
X837250Y93221D03*
X831297Y104206D03*
X842864Y110296D03*
X831114Y115223D03*
X839360Y114862D03*
X835114Y115223D03*
X845220Y135862D03*
Y129362D03*
X829114Y150273D03*
Y147123D03*
X836502Y161553D03*
X828145Y160362D03*
X838220Y163862D03*
X835220D03*
X837320Y175112D03*
X842720Y181360D03*
X837975Y210064D03*
X837160Y218212D03*
Y213207D03*
X844526Y204968D03*
X838820Y206872D03*
X830339Y228143D03*
X837500Y229642D03*
X829680Y264580D03*
X836210Y272452D03*
X829720Y277562D03*
X829800Y271562D03*
X839450Y272662D03*
X835400Y268800D03*
X829620Y280345D03*
X829820Y275045D03*
X829320Y296762D03*
X834400Y283862D03*
X834900Y293462D03*
X829720Y292762D03*
X839860Y294702D03*
X827620Y302962D03*
X830417Y311865D03*
X828222Y359960D03*
X835471Y363003D03*
X843133Y366158D03*
X833300Y386500D03*
X838784Y392880D03*
X836300Y418800D03*
X832400Y427100D03*
X840400Y418900D03*
X839200Y434300D03*
X841300Y446800D03*
X831720Y457700D03*
X839640Y449612D03*
X832700Y446800D03*
X830600Y449200D03*
X838220Y459562D03*
X841200Y456500D03*
X842600Y477200D03*
X842341Y474241D03*
X832720Y494862D03*
X829720D03*
X841795Y492862D03*
X838645D03*
X830870Y480010D03*
X832590Y512888D03*
X829745Y498082D03*
Y502082D03*
X832370Y525849D03*
X843287Y527817D03*
X834635Y515447D03*
X830480Y527817D03*
X841461Y525849D03*
X840990Y529786D03*
X828009Y587913D03*
X831705Y593877D03*
X829230Y582772D03*
X831700Y596962D03*
X831530Y651932D03*
X830587Y741205D03*
X833120Y743392D03*
X838587Y766825D03*
X836847Y762495D03*
X841827Y766795D03*
X837127Y758976D03*
X829420Y758422D03*
X841997Y773085D03*
X838020Y1232432D03*
X832090Y1326862D03*
X828799Y1336870D03*
X828910Y1331756D03*
X832090Y1331862D03*
Y1336862D03*
X828910Y1341725D03*
X832090Y1341862D03*
X829352Y1565293D03*
Y1562293D03*
Y1559293D03*
Y1568293D03*
X832352D03*
Y1565293D03*
Y1559293D03*
Y1562293D03*
X835352Y1568293D03*
Y1565293D03*
Y1559293D03*
Y1562293D03*
X838352Y1568293D03*
Y1565293D03*
Y1559293D03*
Y1562293D03*
X841352Y1568293D03*
Y1565293D03*
Y1559293D03*
Y1562293D03*
X829352Y1574293D03*
Y1571293D03*
X832352D03*
Y1574293D03*
X835352Y1571293D03*
Y1574293D03*
X838352Y1571293D03*
Y1574293D03*
X841352Y1571293D03*
Y1574293D03*
X830079Y1580393D03*
X835579D03*
X843652Y1584539D03*
X833052Y1597693D03*
X836052D03*
X830079Y1590653D03*
X835579D03*
X833052Y1600693D03*
X836052D03*
X835579Y1585523D03*
X830052Y1600693D03*
Y1597693D03*
X841152Y1586507D03*
X833052Y1603693D03*
X836052D03*
X839052Y1611893D03*
X833052Y1607793D03*
Y1611893D03*
X836052Y1607793D03*
Y1611893D03*
X830052D03*
Y1607793D03*
Y1603693D03*
X839052Y1607793D03*
X832208Y1731911D03*
X845095Y49388D03*
X858629Y60293D03*
X850015Y87341D03*
X843855Y87711D03*
X847472Y94754D03*
X854577Y99651D03*
X854107Y91232D03*
X850280Y113852D03*
X847660Y113962D03*
X853100Y113762D03*
X856776Y129268D03*
X846846Y127064D03*
X854100Y132972D03*
X854220Y135862D03*
Y129362D03*
X854200Y138562D03*
X851895Y160262D03*
X848745Y160187D03*
X848709Y156752D03*
X848360Y182872D03*
X845720Y181362D03*
X849710Y212062D03*
X845220Y216532D03*
X855858Y212425D03*
X855933Y215375D03*
X860050Y215310D03*
X854706Y229878D03*
X852206D03*
X847580Y232222D03*
X853828Y265057D03*
X854333Y276117D03*
X854338Y280027D03*
Y283527D03*
X853828Y269043D03*
X850133Y271049D03*
X861865Y273730D03*
X852800Y288562D03*
X853200Y297462D03*
X850093Y286625D03*
X855480Y299692D03*
X856243Y286447D03*
X856700Y304862D03*
X859920Y308852D03*
X848000Y374622D03*
X851396Y369614D03*
X859734Y373032D03*
X859740Y399081D03*
X846040Y399210D03*
X856842Y410760D03*
X846490Y422131D03*
X857560Y417762D03*
X844200Y418800D03*
X850610Y444352D03*
X847830Y443892D03*
X843810Y453322D03*
X851606Y447927D03*
X844210Y455902D03*
X846700Y473000D03*
Y476900D03*
X855200D03*
X857620Y492862D03*
X848710Y505641D03*
X858600Y511130D03*
X848620Y509752D03*
X853070Y515447D03*
X860345Y522162D03*
X857195D03*
X859888Y593970D03*
X859054Y583752D03*
X845523Y582126D03*
X856698Y594011D03*
X856520Y751262D03*
X853200Y751062D03*
X859450Y750462D03*
X854687Y761685D03*
X844957Y763065D03*
X854620Y1242125D03*
X854237Y1250358D03*
X846652Y1581793D03*
Y1573793D03*
X854652Y1577793D03*
X857652Y1582570D03*
Y1573793D03*
X854777Y1586968D03*
X846652Y1597793D03*
X855352Y1590893D03*
X854652Y1593793D03*
X846652Y1585993D03*
X857551Y1593793D03*
X846652Y1589793D03*
X854652Y1605793D03*
Y1601793D03*
X846652Y1609793D03*
X852208Y1731911D03*
X865095Y49388D03*
X862930Y70072D03*
X866330D03*
X876124Y66072D03*
X868187Y72006D03*
X860937Y71877D03*
X861350Y61672D03*
X876124Y86072D03*
Y106072D03*
Y126072D03*
X862452Y151590D03*
X874295Y163862D03*
X867620Y154362D03*
X871145Y163862D03*
X863488Y176332D03*
X871580Y183370D03*
X875169Y185113D03*
X871980Y199500D03*
X864859Y187110D03*
X873200Y194262D03*
X871890Y196740D03*
X877971Y196652D03*
X867528Y231788D03*
X875543Y266447D03*
X867700Y268262D03*
X860833Y276817D03*
X863933Y276917D03*
X875543Y269347D03*
X863747Y280870D03*
X867237Y273325D03*
X868552Y285537D03*
X862043Y290047D03*
X874243Y287047D03*
X877322Y296051D03*
X872320Y304936D03*
X869820D03*
X867320D03*
X864820D03*
X867922Y376450D03*
X875922Y379793D03*
X860531Y375826D03*
X870700Y382415D03*
Y390620D03*
Y394620D03*
Y386476D03*
Y398620D03*
Y402581D03*
X868113Y409372D03*
X871320Y416752D03*
X870513Y414276D03*
X862320Y431462D03*
X863415Y445829D03*
X860574Y445404D03*
X861080Y459742D03*
X870360Y493042D03*
X862620Y503162D03*
Y499062D03*
Y507162D03*
X868110Y499142D03*
X865290Y499032D03*
X865810Y521862D03*
X860345Y513062D03*
X866820Y736562D03*
X864680Y751582D03*
X874155Y756993D03*
X864700Y778300D03*
X868352Y1568293D03*
Y1565293D03*
Y1559293D03*
Y1562293D03*
X865352Y1568293D03*
Y1565293D03*
Y1559293D03*
Y1562293D03*
X874352D03*
Y1559293D03*
Y1565293D03*
Y1568293D03*
X871352D03*
Y1565293D03*
Y1559293D03*
Y1562293D03*
X868352Y1574293D03*
Y1571293D03*
X865352Y1574293D03*
Y1571293D03*
X874352Y1574293D03*
Y1571293D03*
X871352D03*
Y1574293D03*
X866479Y1580393D03*
X872079D03*
X866052Y1597693D03*
X869052D03*
X866479Y1590653D03*
X869052Y1600693D03*
X866052D03*
X872052Y1597693D03*
X872079Y1590653D03*
X872052Y1600693D03*
X866479Y1585523D03*
X875052Y1597693D03*
Y1600693D03*
X860652Y1590444D03*
X869052Y1603693D03*
X866052D03*
X872052D03*
X869052Y1607793D03*
Y1611893D03*
X866052Y1607793D03*
X863052Y1611893D03*
X866052D03*
X872052Y1607793D03*
Y1611893D03*
X875052Y1603693D03*
Y1607793D03*
Y1611893D03*
X863052Y1607793D03*
X860052Y1611893D03*
X872208Y1731911D03*
X892214Y141891D03*
X886280Y174085D03*
X878327Y183169D03*
X876695Y171362D03*
Y176862D03*
X887520Y171362D03*
Y176862D03*
X878220Y192055D03*
X877724Y200837D03*
X878220Y187449D03*
X888929Y209223D03*
X891620Y209662D03*
X888929Y206723D03*
X891620Y207162D03*
X880943Y283347D03*
X884003Y278712D03*
X883870Y275802D03*
X883909Y281862D03*
X879587Y270004D03*
X883870Y272652D03*
X880943Y286347D03*
X887338Y296760D03*
X880473Y329370D03*
X882520Y327562D03*
X885020D03*
X887520D03*
X890422Y333879D03*
X893440Y336232D03*
X887869Y386618D03*
X883472Y382910D03*
X890820Y389362D03*
X890920Y386352D03*
X889453Y458926D03*
X887590Y471552D03*
X889439Y489599D03*
Y492999D03*
X887671Y487831D03*
Y494767D03*
X878931Y509051D03*
X878941Y503813D03*
X881680Y504742D03*
Y508142D03*
X884512Y523800D03*
X882410Y526132D03*
X888130Y532612D03*
X891530D03*
X886362Y534380D03*
X887810Y582442D03*
X886500Y739162D03*
X889000Y737562D03*
X885310Y736442D03*
X886720Y741902D03*
X878152Y876760D03*
X878192Y879910D03*
X884747Y871745D03*
X879100Y912608D03*
X884619Y916477D03*
X892317Y915872D03*
X881372Y920655D03*
X880102Y923235D03*
X889439Y1437938D03*
X891560Y1435510D03*
X883352Y1562293D03*
Y1559293D03*
Y1565293D03*
Y1568293D03*
X880352Y1562293D03*
Y1559293D03*
Y1565293D03*
Y1568293D03*
X877352Y1562293D03*
Y1559293D03*
Y1565293D03*
Y1568293D03*
X883352Y1574293D03*
Y1571293D03*
X880352Y1574293D03*
Y1571293D03*
X877352Y1574293D03*
Y1571293D03*
X888652Y1581793D03*
Y1573793D03*
X877579Y1580393D03*
X885652Y1584539D03*
X888652Y1597793D03*
Y1585993D03*
X877579Y1585523D03*
X878052Y1597693D03*
Y1600693D03*
X877579Y1590653D03*
X883152Y1586507D03*
X888652Y1589793D03*
X878052Y1603693D03*
Y1607793D03*
X881052Y1611893D03*
X878052D03*
X881052Y1607793D03*
X888652Y1609793D03*
X892208Y1731911D03*
X908620Y188899D03*
X903930Y202885D03*
X903980Y210355D03*
X903930Y217059D03*
X896620Y209662D03*
X894120D03*
Y207162D03*
X896620D03*
X902350Y208294D03*
X907470Y211980D03*
X902350Y204894D03*
X907470Y215380D03*
X903980Y224529D03*
X902350Y219068D03*
X907470Y226154D03*
X902350Y222468D03*
X907470Y229554D03*
X906120Y261252D03*
X894770Y283062D03*
X893500Y339062D03*
X896540Y341132D03*
X908675Y455386D03*
X899625Y473856D03*
X902260Y473153D03*
Y475653D03*
X903124Y470797D03*
X900020Y470672D03*
X896060Y481222D03*
Y484622D03*
X893321Y480293D03*
X893311Y485531D03*
X907678Y488177D03*
X895340Y497882D03*
Y501282D03*
X893572Y503050D03*
Y496114D03*
X900061Y510962D03*
X906127Y496343D03*
X901829Y512730D03*
Y516130D03*
X900061Y517898D03*
X893450Y516862D03*
X901230Y531612D03*
X904630D03*
X893298Y534380D03*
X899462Y533380D03*
X906398D03*
X894897Y871745D03*
X897000Y891895D03*
X894375Y913692D03*
X894965Y917422D03*
X898062Y976652D03*
Y969716D03*
X899830Y971484D03*
Y974884D03*
X907770Y1045242D03*
X894830Y1435970D03*
X907352Y1568293D03*
Y1565293D03*
Y1559293D03*
Y1562293D03*
Y1574293D03*
Y1571293D03*
X908479Y1580393D03*
X896652Y1577793D03*
X899652Y1582570D03*
Y1573793D03*
X896672Y1587073D03*
X897352Y1590893D03*
X896652Y1593793D03*
X908479Y1590653D03*
Y1585523D03*
X908052Y1600693D03*
Y1597693D03*
X899551Y1593793D03*
X902652Y1590444D03*
X896652Y1605793D03*
X908052Y1611893D03*
X905052D03*
X902052D03*
X908052Y1607793D03*
X905052D03*
X908052Y1603693D03*
X896652Y1601793D03*
X912214Y141891D03*
X917680Y174999D03*
Y177999D03*
Y171999D03*
X920246Y184138D03*
X922726Y176302D03*
X922100Y181791D03*
X917386Y184114D03*
X909386Y195925D03*
X924920Y196199D03*
X923836Y193563D03*
X909386Y203011D03*
Y210098D03*
Y217185D03*
Y224271D03*
Y231358D03*
X914550Y239924D03*
X927034Y445594D03*
X912984Y458135D03*
X909584D03*
X913913Y455396D03*
X919279Y461244D03*
X924447Y463012D03*
X921047D03*
X909190Y473392D03*
X920682Y494586D03*
X920980Y503393D03*
X913394Y521662D03*
X916794D03*
X909600Y521162D03*
X911720Y511662D03*
X911626Y523430D03*
X918562D03*
X924647Y526808D03*
X922879Y531976D03*
Y528576D03*
X924647Y533744D03*
X918420Y804062D03*
X909720Y798861D03*
Y794862D03*
X913720Y799362D03*
X914152Y803294D03*
X924600Y824262D03*
X921757Y962082D03*
X916974Y962108D03*
X923403Y983327D03*
X923930Y976652D03*
X917980Y974952D03*
X923322Y990227D03*
X924440Y996852D03*
X914838Y985989D03*
X918720Y1009937D03*
X921880Y1525110D03*
X924380D03*
X921880Y1527610D03*
X924380D03*
X910352Y1568293D03*
Y1565293D03*
Y1559293D03*
Y1562293D03*
X922352D03*
Y1559293D03*
Y1565293D03*
Y1568293D03*
X919352Y1562293D03*
Y1559293D03*
Y1565293D03*
Y1568293D03*
X916352Y1562293D03*
Y1559293D03*
Y1565293D03*
Y1568293D03*
X913352D03*
Y1565293D03*
Y1559293D03*
Y1562293D03*
X910352Y1574293D03*
Y1571293D03*
X922352Y1574293D03*
Y1571293D03*
X919352Y1574293D03*
Y1571293D03*
X916352Y1574293D03*
Y1571293D03*
X913352D03*
Y1574293D03*
X919579Y1580393D03*
X914079D03*
X919579Y1590653D03*
X914079D03*
X919579Y1585523D03*
X917052Y1600693D03*
Y1597693D03*
X914052Y1600693D03*
Y1597693D03*
X911052Y1600693D03*
Y1597693D03*
X920052Y1600693D03*
Y1597693D03*
X917052Y1611893D03*
X914052D03*
X911052D03*
X917052Y1607793D03*
X914052D03*
X911052D03*
X920052Y1611893D03*
X923052D03*
Y1607793D03*
X920052D03*
X917052Y1603693D03*
X914052D03*
X911052D03*
X920052D03*
X922320Y1660953D03*
X918020Y1672860D03*
X914500Y1671400D03*
X912208Y1731911D03*
X932214Y141891D03*
X938160Y173389D03*
X935550Y173329D03*
X940720Y173389D03*
X938160Y176389D03*
X935550Y176329D03*
X940720Y176389D03*
X940424Y184190D03*
X936424D03*
X927133Y189386D03*
X935496Y195925D03*
X935770Y191419D03*
X939270D03*
X940410Y188852D03*
X935496Y203012D03*
X925320Y203399D03*
X935496Y210098D03*
Y217185D03*
Y224272D03*
Y231358D03*
X930472Y246093D03*
X938603Y240063D03*
X933122Y246115D03*
X933686Y242922D03*
X935454Y241154D03*
X933217Y380693D03*
Y384693D03*
X941059Y427911D03*
Y424511D03*
X940709Y460438D03*
X938437Y455454D03*
X932724Y455538D03*
X926215Y461244D03*
X937447Y457862D03*
X934047D03*
X928394Y472201D03*
Y474701D03*
X929234Y494915D03*
X938588Y485197D03*
X929698Y503595D03*
X940596Y498648D03*
X939872Y495813D03*
X931720Y524862D03*
X939097Y527257D03*
X940550Y517400D03*
X940140Y514925D03*
X933773Y530479D03*
X930731D03*
X941050Y532252D03*
Y528852D03*
X928231Y530479D03*
X936273Y530478D03*
X939282Y534020D03*
X938742Y803831D03*
X931573Y816109D03*
X927470Y815112D03*
X927200Y811462D03*
X935052Y812630D03*
X934260Y808312D03*
X938371Y809311D03*
X930786Y811785D03*
X925220Y817862D03*
X928237Y824844D03*
X926469Y826612D03*
X931496Y962082D03*
X926823D03*
X940170Y962842D03*
X930233Y983298D03*
X930274Y990237D03*
X939740Y987762D03*
X936998Y985750D03*
X932310Y996812D03*
X929221Y1014664D03*
X927220Y1012362D03*
X931220D03*
X939380Y1525110D03*
X926880D03*
X929380D03*
X931880D03*
X934380D03*
X936880D03*
X926880Y1527610D03*
X929380D03*
X931880D03*
X934380D03*
X936880D03*
X939380D03*
X925352Y1562293D03*
Y1559293D03*
Y1565293D03*
Y1568293D03*
Y1574293D03*
Y1571293D03*
X938652Y1581393D03*
X928152Y1584539D03*
X938652Y1593393D03*
Y1585393D03*
X925152Y1586507D03*
X938652Y1589393D03*
X927122Y1661380D03*
X938220Y1661062D03*
X929979Y1661352D03*
X932208Y1731911D03*
X952214Y141891D03*
X957420Y153699D03*
X945720Y173389D03*
X943220D03*
X945720Y176389D03*
X943220D03*
X948400Y176499D03*
X949120Y184912D03*
X949710Y198289D03*
X941634Y199051D03*
Y193451D03*
X944250Y194489D03*
Y197889D03*
X957020Y193299D03*
X949550Y192819D03*
X951354Y209437D03*
Y203837D03*
X944880Y210959D03*
Y216559D03*
X953970Y208275D03*
X947496Y215397D03*
X953970Y204875D03*
X947496Y211997D03*
X944880Y230697D03*
Y225097D03*
X954874Y232071D03*
X954904Y225741D03*
X957156Y227163D03*
X947496Y226135D03*
X957156Y230563D03*
X947496Y229535D03*
X957020Y264862D03*
X953046Y390103D03*
X951181Y391916D03*
X950660Y399472D03*
X956487Y394831D03*
X942646Y400793D03*
X949920Y404602D03*
X942827Y422743D03*
Y429679D03*
X944032Y437631D03*
Y434231D03*
X945800Y432463D03*
Y439399D03*
X946492Y460410D03*
X945447Y463012D03*
X942047D03*
X946727Y507952D03*
Y504552D03*
X954420Y511252D03*
Y500552D03*
Y497152D03*
X956188Y495384D03*
Y502320D03*
X948495Y502784D03*
X948693Y509497D03*
X956188Y509484D03*
X954420Y514652D03*
X954390Y527596D03*
X956188Y516420D03*
X947190Y527330D03*
X945524Y515483D03*
X944261Y517871D03*
X941740Y512922D03*
X942610Y515350D03*
X952622Y529364D03*
X945100Y534464D03*
X955123Y533642D03*
X948415Y534313D03*
X956518Y531567D03*
X957220Y582862D03*
X953594Y787477D03*
X956700Y786862D03*
X954447Y791735D03*
X951043Y796140D03*
X950190Y791382D03*
X944272Y803410D03*
X943366Y798707D03*
X946786Y795287D03*
X947921Y799761D03*
X941400Y810062D03*
X944170Y962842D03*
X946865Y974077D03*
X953235Y972642D03*
X949560Y981392D03*
X946938Y991162D03*
X943720Y985772D03*
X951560Y997422D03*
X956980Y1536260D03*
X953980D03*
X950980D03*
X947980D03*
X944980D03*
Y1551260D03*
X947980D03*
X950980D03*
X953980D03*
X956980D03*
X944980Y1548260D03*
X947980D03*
X950980D03*
X953980D03*
X956980D03*
X944980Y1545260D03*
X947980D03*
X950980D03*
X953980D03*
X956980D03*
X944980Y1542260D03*
X947980D03*
X950980D03*
X953980D03*
X956980D03*
Y1539260D03*
X953980D03*
X950980D03*
X947980D03*
X944980D03*
Y1554260D03*
X947980D03*
X950980D03*
X953980D03*
X956980D03*
X956022Y1620730D03*
X953022D03*
Y1632730D03*
X956022D03*
Y1629730D03*
X953022D03*
X956022Y1626730D03*
X953022D03*
Y1623730D03*
X956022D03*
X946100Y1661100D03*
X956600Y1666875D03*
X952208Y1731911D03*
X972214Y141891D03*
X960420Y153699D03*
X962604Y165313D03*
X962458Y162398D03*
X965150Y193412D03*
X966720Y198099D03*
X970720D03*
X961120Y193299D03*
X963520Y214699D03*
X960703Y212668D03*
X971471Y242358D03*
X968384Y242051D03*
X965884D03*
X960020Y264862D03*
X963020D03*
X962570Y282812D03*
X962882Y314512D03*
X963854Y320113D03*
X963300Y347962D03*
X965792Y350959D03*
X962623Y350642D03*
X965420Y365719D03*
X970730Y377872D03*
X963856Y394202D03*
X960059Y387004D03*
X972986Y393171D03*
X972220Y386251D03*
Y390239D03*
X975670Y392063D03*
X963856Y398302D03*
X965890Y405967D03*
X963720Y439862D03*
X970054Y478773D03*
X961320Y476242D03*
X970054Y485709D03*
X968286Y483941D03*
Y480541D03*
X966720Y511362D03*
X960620Y509462D03*
X972379Y509303D03*
X964347Y509462D03*
X969351Y512416D03*
X957790Y527596D03*
X963930Y533362D03*
X967330D03*
X959558Y529364D03*
X962162Y535130D03*
X969098D03*
X959351Y533566D03*
X958755Y657078D03*
X960920Y644762D03*
Y649762D03*
Y654762D03*
X963720Y647262D03*
Y657262D03*
Y652262D03*
X963520Y665062D03*
X958866Y662378D03*
X960820Y665062D03*
X960920Y659762D03*
X963720Y662262D03*
X959100Y789862D03*
X963610Y981292D03*
X959535Y990477D03*
X963780Y997496D03*
X967750Y1376460D03*
X969000Y1536262D03*
X971700D03*
X969000Y1548262D03*
X971700D03*
X969000Y1545262D03*
X971700D03*
X969000Y1551262D03*
X971700D03*
Y1542262D03*
X969000D03*
X971700Y1539262D03*
X969000D03*
X965904Y1554364D03*
X960904D03*
X969000Y1554262D03*
X971700D03*
X965622Y1579240D03*
Y1576240D03*
Y1573240D03*
X966852Y1585920D03*
X969852D03*
X960852D03*
X963852D03*
X957852D03*
X965086Y1603984D03*
X962086D03*
X962022Y1620730D03*
X959022D03*
Y1632730D03*
X962022D03*
Y1629730D03*
X959022D03*
X962022Y1626730D03*
X959022D03*
Y1623730D03*
X962022D03*
X968022Y1620730D03*
X965022D03*
X971022D03*
X965022Y1632730D03*
X968022Y1629730D03*
X965022D03*
X968022Y1626730D03*
X965022D03*
Y1623730D03*
X968022D03*
X971022Y1626730D03*
Y1623730D03*
Y1629730D03*
Y1632730D03*
X968022D03*
X972208Y1731911D03*
X989910Y-27961D03*
X989925Y-25446D03*
X986642Y-27947D03*
X986627Y-25432D03*
X983632Y-26655D03*
X980899Y-13200D03*
Y-9800D03*
X978403Y-9022D03*
Y-13978D03*
Y-19022D03*
Y-23978D03*
X986627Y-21558D03*
X989925Y-21572D03*
X983632Y-16626D03*
X989910Y-17932D03*
X989925Y-15417D03*
X986642Y-17918D03*
X986627Y-15403D03*
Y-11529D03*
X989925Y-11543D03*
X978403Y6022D03*
X989910Y-7903D03*
X989925Y-5388D03*
X986642Y-7889D03*
X986627Y-5374D03*
X983632Y-6597D03*
X986627Y4655D03*
X986642Y2140D03*
X989925Y4641D03*
X989910Y2126D03*
X983632Y3432D03*
X980899Y20200D03*
Y16800D03*
X978403Y10978D03*
Y20978D03*
Y16022D03*
X986627Y14684D03*
X989925Y14670D03*
X986642Y12169D03*
X989910Y12155D03*
X989925Y8515D03*
X986627Y8529D03*
X983632Y13461D03*
X986642Y22698D03*
X989910Y22684D03*
X986627Y19058D03*
X989925Y19044D03*
X986627Y25213D03*
X989895Y25199D03*
X983632Y23990D03*
X975688Y152950D03*
Y149950D03*
X990501Y152397D03*
X986369Y155358D03*
X975690Y157220D03*
X983811Y156694D03*
X985499Y168753D03*
X988835Y185443D03*
X981445Y181058D03*
X985431D03*
X990115Y173039D03*
X987320Y194599D03*
Y198099D03*
Y201599D03*
X977220Y201399D03*
X986020Y191099D03*
X981795Y216623D03*
X987259Y276094D03*
X978012Y276436D03*
X975512Y282096D03*
X978012D03*
X975512Y279266D03*
X978012D03*
X981470Y268532D03*
X979940Y292262D03*
Y289762D03*
X975512Y294996D03*
X978012D03*
X979940Y284762D03*
Y287262D03*
X988818Y346372D03*
X985016Y344659D03*
X974791Y339990D03*
X986182Y361062D03*
X978000Y362462D03*
X988723Y369650D03*
X989500Y376362D03*
X979380Y373082D03*
X988908Y373392D03*
X986400Y383123D03*
X983770Y373962D03*
X979766Y377507D03*
X977949Y384205D03*
X980916Y384286D03*
X980856Y392502D03*
X986955Y391939D03*
X983629Y397628D03*
X991369Y408252D03*
X988159Y409068D03*
X979240Y425212D03*
X983760Y424292D03*
X980092Y421289D03*
X984254Y418379D03*
X987440Y431193D03*
X985672Y432961D03*
X980720Y512362D03*
X986400Y503200D03*
X983720Y512362D03*
X976283Y534226D03*
X986273Y532996D03*
X980535Y532643D03*
X986418Y530019D03*
X975900Y1265062D03*
X987920Y1290662D03*
X985320Y1288762D03*
X992306Y1295049D03*
X979373Y1342724D03*
X974700Y1536262D03*
X980400D03*
X977700D03*
X974700Y1548262D03*
Y1545262D03*
Y1551262D03*
X980400Y1548262D03*
X977700D03*
X980400Y1545262D03*
X977700D03*
X980400Y1551262D03*
X977700D03*
Y1542262D03*
X980400D03*
X974700D03*
X977700Y1539262D03*
X980400D03*
X974700D03*
X984270Y1554364D03*
X974700Y1554262D03*
X980400D03*
X977700D03*
X989270Y1554364D03*
X988988Y1579240D03*
Y1573240D03*
Y1576240D03*
X987662Y1620870D03*
Y1629870D03*
Y1626870D03*
Y1623870D03*
Y1632870D03*
X995000Y150883D03*
X1001500D03*
X995180Y153689D03*
X1002735Y153943D03*
X999735D03*
X1006220Y160799D03*
X1002720D03*
X1001101Y165510D03*
X999915Y180548D03*
X996415D03*
X992505Y180553D03*
X993205Y174053D03*
X993305Y170953D03*
X999220Y185299D03*
X1002720D03*
X1006220D03*
X996415Y172579D03*
X1002920Y174799D03*
X990220Y195699D03*
Y199199D03*
X1008120Y198293D03*
X990495Y212923D03*
X990195Y216823D03*
X990220Y202699D03*
X1000610Y211039D03*
X1005640Y210969D03*
X1001195Y219898D03*
X1005120Y230399D03*
X1002500Y266862D03*
X998500Y269862D03*
X1002500D03*
X994743Y289843D03*
X1001065Y304622D03*
Y307122D03*
Y309622D03*
X1006232Y343983D03*
X1001440Y359702D03*
X994553Y365711D03*
X994689Y379348D03*
X1006201Y370004D03*
X999440Y371782D03*
X996922Y367764D03*
X997598Y382952D03*
X997612Y391804D03*
X1006221Y382945D03*
X997900Y400720D03*
X994322Y404090D03*
X1005123Y414662D03*
X997617Y412383D03*
X991770Y418835D03*
X993387Y429827D03*
X993012Y421570D03*
X997225Y419162D03*
X990840Y431193D03*
X992608Y432961D03*
X1005720Y498862D03*
X1005520Y510932D03*
X999720Y512862D03*
X991097Y529902D03*
X991237Y533043D03*
X1008560Y589682D03*
X1002640Y594692D03*
X1005960Y594682D03*
X1005373Y748826D03*
X995120Y773122D03*
X994942Y777055D03*
X996675Y1286985D03*
X996320Y1280683D03*
Y1284062D03*
X997920Y1278762D03*
X994574Y1297318D03*
X995066Y1536262D03*
X992466D03*
X1001066D03*
X1003766D03*
X998066D03*
X995066Y1551262D03*
X992466D03*
X995066Y1545262D03*
X992466D03*
X995066Y1548262D03*
X992466D03*
X1001066Y1551262D03*
X1003766D03*
X1001066Y1545262D03*
X1003766D03*
X1001066Y1548262D03*
X1003766D03*
X998066Y1551262D03*
Y1545262D03*
Y1548262D03*
Y1542262D03*
X1003766D03*
X1001066D03*
X992466D03*
X995066D03*
X998066Y1539262D03*
X1003766D03*
X1001066D03*
X992466D03*
X995066D03*
X1007636Y1554364D03*
X995066Y1554262D03*
X992466D03*
X1001066D03*
X1003766D03*
X998066D03*
X1002782Y1585920D03*
X999782D03*
X996782D03*
X990782D03*
X993782D03*
X996698Y1604000D03*
X993698D03*
X990662Y1620870D03*
X993662D03*
X996662D03*
X999662D03*
X1002662D03*
Y1626870D03*
Y1623870D03*
X996662Y1629870D03*
X999662Y1626870D03*
X996662D03*
Y1623870D03*
X999662D03*
X996662Y1632870D03*
X993662Y1629870D03*
X990662D03*
X993662Y1626870D03*
X990662D03*
Y1623870D03*
X993662D03*
X990662Y1632870D03*
X993662D03*
X1001810Y1662700D03*
Y1665200D03*
X992208Y1731911D03*
X1021908Y60392D03*
Y120392D03*
X1012214Y141826D03*
X1015300Y148736D03*
X1012187Y148749D03*
X1008129Y150948D03*
X1009720Y160799D03*
X1013220D03*
X1012791Y157596D03*
X1006435Y172843D03*
X1012000Y185299D03*
X1014900D03*
X1017800D03*
X1017200Y175699D03*
X1014300D03*
X1019900Y175799D03*
X1009895Y192359D03*
X1008067Y194356D03*
X1020645Y190499D03*
X1011320Y202169D03*
X1019935Y206463D03*
Y203333D03*
X1019355Y218423D03*
X1019802Y214099D03*
X1010005Y208424D03*
X1011720Y229699D03*
X1019355Y222423D03*
X1019530Y226423D03*
X1007820Y229999D03*
X1018000Y263862D03*
X1022000Y264362D03*
X1014500Y263862D03*
X1010500D03*
X1018000Y266862D03*
X1022002Y267342D03*
X1010500Y266862D03*
X1006500D03*
X1014500D03*
Y269862D03*
X1018000D03*
X1022002Y270142D03*
X1006500Y269862D03*
X1010500D03*
X1021118Y294290D03*
X1010828Y304822D03*
Y307322D03*
Y309822D03*
X1021419Y305704D03*
X1020720Y310937D03*
X1015520Y302862D03*
X1013500Y344900D03*
X1009800Y343800D03*
X1021695Y364518D03*
X1006710Y372931D03*
X1015096Y373758D03*
X1009883Y367955D03*
X1015638Y382968D03*
X1015637Y391334D03*
X1006589Y392017D03*
X1010420Y416062D03*
X1006750Y401010D03*
X1015657Y401013D03*
X1015420Y410862D03*
X1021259Y420548D03*
X1007249Y422682D03*
X1011611Y430038D03*
X1017511D03*
X1009009Y419948D03*
X1021239Y416974D03*
X1016261Y432888D03*
X1012861D03*
X1008720Y498362D03*
X1019145Y503823D03*
X1024200Y510362D03*
X1018092Y520212D03*
X1020392Y521826D03*
X1011720Y589362D03*
X1018720Y592362D03*
X1016360Y594682D03*
X1016220Y590862D03*
X1021720Y601862D03*
X1019000Y601042D03*
X1021654Y606302D03*
X1011160Y594682D03*
X1010630Y748741D03*
X1007873Y748826D03*
X1007600Y1298250D03*
X1007610Y1295040D03*
X1021612Y1536262D03*
X1016012D03*
X1018612D03*
Y1551262D03*
X1016012D03*
X1018612Y1545262D03*
X1016012D03*
X1018612Y1548262D03*
X1016012D03*
X1021612Y1551262D03*
Y1545262D03*
Y1548262D03*
X1018612Y1542262D03*
X1016012D03*
X1021612D03*
Y1539262D03*
X1016012D03*
X1018612D03*
Y1554262D03*
X1016012D03*
X1021612D03*
X1012636Y1554364D03*
X1012354Y1579240D03*
Y1573240D03*
Y1576240D03*
X1021942Y1586090D03*
X1019252Y1620870D03*
X1022252D03*
Y1623870D03*
Y1626870D03*
X1019252Y1623870D03*
Y1626870D03*
X1019910Y1662700D03*
Y1665200D03*
X1012208Y1731911D03*
X1034929Y-33989D03*
Y-29033D03*
X1026705Y-27695D03*
X1023407Y-27681D03*
X1029700Y-26472D03*
X1026705Y-38224D03*
X1023437Y-38210D03*
X1026690Y-35709D03*
X1023422Y-35695D03*
X1026705Y-32069D03*
X1023407Y-32055D03*
X1029700Y-37001D03*
X1032433Y-23211D03*
Y-19811D03*
X1034929Y-13989D03*
Y-9033D03*
Y-23989D03*
Y-19033D03*
X1026705Y-17666D03*
X1026690Y-15151D03*
X1023407Y-17652D03*
X1023422Y-15137D03*
X1026705Y-11511D03*
X1023407Y-11497D03*
X1029700Y-16443D03*
X1026690Y-25180D03*
X1023422Y-25166D03*
X1023407Y-21526D03*
X1026705Y-21540D03*
X1032433Y-3211D03*
Y189D03*
X1034929Y-3989D03*
Y967D03*
X1029700Y3615D03*
X1023422Y4921D03*
X1023407Y2406D03*
X1026690Y4907D03*
X1026705Y2392D03*
X1023422Y-5108D03*
X1023407Y-7623D03*
X1026690Y-5122D03*
X1026705Y-7637D03*
Y-1482D03*
X1023407Y-1468D03*
X1029700Y-6414D03*
X1023407Y22464D03*
X1026705Y22450D03*
Y18576D03*
X1023407Y18590D03*
X1026705Y8547D03*
X1023407Y8561D03*
X1023422Y14950D03*
X1023407Y12435D03*
X1026690Y14936D03*
X1026705Y12421D03*
X1029700Y13644D03*
Y23673D03*
X1023422Y24979D03*
X1026690Y24965D03*
X1038609Y49388D03*
X1027520Y122732D03*
X1037650Y128842D03*
X1026620Y125662D03*
X1034229Y128953D03*
X1032894Y155185D03*
X1022800Y175799D03*
X1023220Y187574D03*
X1025000Y264362D03*
X1031502Y267342D03*
X1028202D03*
X1025102D03*
X1037618Y261200D03*
X1031702Y264130D03*
X1033133Y272564D03*
X1031502Y270142D03*
X1029833Y272564D03*
X1026733D03*
X1023633D03*
X1028202Y270142D03*
X1025102D03*
X1036915Y290969D03*
X1025862Y291727D03*
X1032317Y291284D03*
X1036278Y307393D03*
X1033285Y353627D03*
X1029395Y375844D03*
X1025004Y374662D03*
X1031950Y383771D03*
Y387171D03*
X1031153Y390152D03*
X1029094Y383070D03*
Y387872D03*
X1026820Y394362D03*
X1033860Y400802D03*
X1038320Y407062D03*
Y404462D03*
X1026548Y400571D03*
X1035920Y428962D03*
Y420062D03*
Y417462D03*
X1038294Y506504D03*
X1027190Y510672D03*
X1026370Y503562D03*
X1032155Y509737D03*
X1029220Y520032D03*
X1025530Y519627D03*
X1033040Y519852D03*
X1038130Y518417D03*
X1038220Y589862D03*
X1040720Y591862D03*
X1030980Y598722D03*
X1023740Y596152D03*
X1036480Y596272D03*
X1024154Y601152D03*
X1029630Y601252D03*
X1026654Y596152D03*
X1035760Y592952D03*
X1033260Y601272D03*
X1038260D03*
X1033817Y735612D03*
X1036954Y734669D03*
X1030660Y735082D03*
X1027212Y1536262D03*
X1024612D03*
Y1551262D03*
X1027212D03*
X1024612Y1545262D03*
X1027212D03*
X1024612Y1548262D03*
X1027212D03*
X1024612Y1542262D03*
X1027212D03*
Y1539262D03*
X1024612D03*
X1031002Y1554364D03*
X1024612Y1554262D03*
X1027212D03*
X1036002Y1554364D03*
X1035720Y1579240D03*
Y1573240D03*
Y1576240D03*
X1030942Y1586090D03*
X1033942D03*
X1024942D03*
X1027942D03*
X1028298Y1604000D03*
X1025298D03*
X1025252Y1620870D03*
X1034252Y1623870D03*
Y1626870D03*
X1031252Y1623870D03*
Y1626870D03*
X1025252Y1623870D03*
X1028252D03*
Y1626870D03*
X1025252D03*
X1031252Y1620870D03*
X1034252D03*
X1028252D03*
X1023580Y1662700D03*
Y1665200D03*
X1027370Y1662700D03*
Y1665200D03*
X1032208Y1731911D03*
X1040970Y128332D03*
X1053028Y246518D03*
X1053428Y261118D03*
X1040924Y286073D03*
X1043720Y363462D03*
X1043629Y375078D03*
Y372578D03*
X1054820Y370162D03*
X1044120Y366362D03*
X1049100Y390162D03*
X1040120Y393962D03*
X1042720D03*
X1046156Y442699D03*
X1041420Y443962D03*
X1043920D03*
X1050470Y447062D03*
X1041444Y506504D03*
X1053690Y520760D03*
X1043720Y589362D03*
X1050200Y598062D03*
X1050390Y604172D03*
X1043260Y601272D03*
X1045760Y596272D03*
X1048260Y601272D03*
X1053200Y612162D03*
X1051680Y614772D03*
X1053745Y742341D03*
X1053354Y1286714D03*
Y1291714D03*
X1039510Y1296655D03*
X1049510D03*
X1044510D03*
X1039510Y1293155D03*
X1049510D03*
X1044510D03*
X1053354Y1296714D03*
X1041798Y1536262D03*
X1047798D03*
X1050498D03*
X1044798D03*
X1039298D03*
X1041798Y1551262D03*
X1039298D03*
X1041798Y1545262D03*
X1039298D03*
X1041798Y1548262D03*
X1039298D03*
X1047798Y1551262D03*
X1050498D03*
X1047798Y1545262D03*
X1050498D03*
X1047798Y1548262D03*
X1050498D03*
X1044798Y1551262D03*
Y1545262D03*
Y1548262D03*
X1039298Y1542262D03*
X1044798D03*
X1050498D03*
X1047798D03*
X1041798D03*
X1044798Y1539262D03*
X1050498D03*
X1047798D03*
X1039298D03*
X1041798D03*
X1054368Y1554364D03*
X1041798Y1554262D03*
X1039298D03*
X1047798D03*
X1050498D03*
X1044798D03*
X1053612Y1586010D03*
X1056898Y1604000D03*
X1050721Y1633043D03*
X1053721D03*
Y1624043D03*
Y1627043D03*
Y1630043D03*
X1050721Y1624043D03*
Y1627043D03*
Y1630043D03*
X1053721Y1621043D03*
X1050721D03*
X1044850Y1665050D03*
Y1662550D03*
X1052208Y1731911D03*
X1058609Y49388D03*
X1067220Y145362D03*
X1066820Y151632D03*
X1067220Y142862D03*
Y148362D03*
X1058028Y246518D03*
X1055528D03*
X1068093Y265503D03*
X1058428Y261118D03*
X1055928D03*
X1067618Y273800D03*
X1070718Y273700D03*
X1067718Y288500D03*
X1070618D03*
X1067718Y285600D03*
X1070618D03*
X1072310Y364422D03*
X1059943Y435314D03*
X1062120Y477462D03*
X1056190Y520760D03*
X1058220Y585862D03*
X1056280Y601232D03*
X1056220Y605052D03*
X1055205Y744853D03*
X1063354Y1286714D03*
X1058354D03*
X1063354Y1291714D03*
X1058354D03*
X1063354Y1296714D03*
X1058290Y1296302D03*
X1071179Y1294669D03*
X1066462Y1520088D03*
X1065164Y1536262D03*
X1062464D03*
X1071164D03*
X1068164D03*
X1065164Y1551262D03*
X1062464D03*
X1065164Y1545262D03*
X1062464D03*
X1065164Y1548262D03*
X1062464D03*
X1071164Y1551262D03*
Y1545262D03*
Y1548262D03*
X1068164Y1551262D03*
Y1545262D03*
Y1548262D03*
Y1542262D03*
X1071164D03*
X1062464D03*
X1065164D03*
X1068164Y1539262D03*
X1071164D03*
X1062464D03*
X1065164D03*
Y1554262D03*
X1062464D03*
X1071164D03*
X1068164D03*
X1059368Y1554364D03*
X1059086Y1579240D03*
Y1573240D03*
Y1576240D03*
X1062612Y1586010D03*
X1065612D03*
X1056612D03*
X1059612D03*
X1059898Y1604000D03*
X1065721Y1633043D03*
X1068721D03*
Y1624043D03*
Y1627043D03*
Y1630043D03*
X1065721Y1624043D03*
Y1627043D03*
Y1630043D03*
X1062721Y1633043D03*
Y1624043D03*
Y1627043D03*
Y1630043D03*
X1056721Y1633043D03*
X1059721D03*
X1056721Y1624043D03*
X1059721D03*
Y1627043D03*
X1056721D03*
X1059721Y1630043D03*
X1056721D03*
X1068721Y1621043D03*
X1065721D03*
X1062721D03*
X1059721D03*
X1056721D03*
X1078609Y49388D03*
X1075100Y55682D03*
X1071920Y53862D03*
X1084146Y67102D03*
X1079114Y75775D03*
X1080168Y90721D03*
X1078270Y93462D03*
X1081282Y180937D03*
X1086756Y187540D03*
X1077973Y246362D03*
X1083973D03*
X1080973D03*
X1077883Y260842D03*
X1076823Y265438D03*
X1083823D03*
X1083883Y260842D03*
X1080883D03*
X1080323Y265438D03*
X1082853Y269492D03*
X1079853D03*
X1075400Y273762D03*
X1078400D03*
X1081400D03*
X1084400D03*
X1087400D03*
X1076018Y289400D03*
X1079018D03*
X1082018D03*
X1085018D03*
X1084130Y298342D03*
X1086630D03*
X1076353Y363966D03*
X1078853D03*
X1077270Y369061D03*
Y374131D03*
Y379251D03*
X1087330Y369061D03*
Y374131D03*
Y379251D03*
X1075462Y386723D03*
X1078151Y413911D03*
X1078120Y411262D03*
X1084245Y435437D03*
X1078545Y435637D03*
X1081045D03*
X1087280Y435437D03*
X1073724Y476867D03*
X1081906Y472577D03*
X1076598Y477087D03*
X1081930Y477132D03*
X1079320Y473892D03*
X1076820D03*
X1076739Y506461D03*
X1073589D03*
X1077751Y522235D03*
X1082220Y522362D03*
X1085720Y522422D03*
X1073250Y582332D03*
X1084637Y744635D03*
X1083714Y1285144D03*
Y1288144D03*
Y1291144D03*
X1077634Y1294869D03*
X1074387Y1294652D03*
X1074010Y1510650D03*
X1073864Y1536262D03*
X1085830D03*
X1073864Y1551262D03*
Y1545262D03*
Y1548262D03*
X1085830Y1551262D03*
Y1545262D03*
Y1548262D03*
Y1542262D03*
X1073864D03*
X1085830Y1539262D03*
X1073864D03*
X1077734Y1554364D03*
X1073864Y1554262D03*
X1085830D03*
X1082734Y1554364D03*
X1084000Y1647110D03*
X1072208Y1731911D03*
X1098609Y49388D03*
X1097794Y67881D03*
X1094644Y67992D03*
X1102561Y78461D03*
X1102480Y133722D03*
X1090279Y126524D03*
X1105580Y132822D03*
X1100630Y130376D03*
X1099030Y245140D03*
X1088018Y289400D03*
X1089130Y298342D03*
X1091630D03*
X1094130D03*
X1105553Y356475D03*
X1089660Y408560D03*
X1095820Y420762D03*
X1090245Y435437D03*
X1096477Y744385D03*
X1093497Y744655D03*
X1089714Y1285144D03*
X1105480Y1517982D03*
X1088530Y1536262D03*
X1091530D03*
X1088530Y1551262D03*
Y1545262D03*
Y1548262D03*
X1094530Y1551262D03*
X1097230D03*
X1094530Y1545262D03*
X1097230D03*
X1094530Y1548262D03*
X1097230D03*
X1091530Y1551262D03*
Y1545262D03*
Y1548262D03*
Y1542262D03*
X1097230D03*
X1094530D03*
X1088530D03*
X1091530Y1539262D03*
X1094530D03*
X1088530D03*
X1101600Y1554364D03*
X1104750Y1549346D03*
X1088530Y1554262D03*
X1094530D03*
X1097230D03*
X1091530D03*
X1092302Y1585650D03*
X1089302D03*
X1098302D03*
X1095302D03*
X1095436Y1603944D03*
X1092436D03*
X1099901Y1633203D03*
Y1624203D03*
Y1627203D03*
Y1630203D03*
Y1621203D03*
X1093901Y1633203D03*
X1096901D03*
Y1624203D03*
Y1627203D03*
Y1630203D03*
X1093901Y1624203D03*
Y1627203D03*
Y1630203D03*
X1090901Y1633203D03*
X1087901D03*
X1090901Y1624203D03*
X1087901D03*
Y1627203D03*
X1090901D03*
X1087901Y1630203D03*
X1090901D03*
X1096901Y1621203D03*
X1093901D03*
X1087901D03*
X1090901D03*
X1095900Y1646935D03*
X1095649Y1638875D03*
X1099457D03*
X1088790Y1641830D03*
X1102930Y1668690D03*
X1094225Y1671710D03*
X1091880Y1673720D03*
X1092072Y1734244D03*
X1118609Y49388D03*
X1110977Y55505D03*
X1110754Y60028D03*
X1113594Y69862D03*
X1109020Y80592D03*
X1118309Y111687D03*
X1115860Y113883D03*
X1118486Y208942D03*
X1111918Y234718D03*
X1109088Y234668D03*
X1111918Y237718D03*
Y240718D03*
X1109088Y237668D03*
Y240668D03*
X1120190Y255652D03*
X1117820Y456132D03*
X1113207Y744455D03*
X1118110Y1398010D03*
X1115853Y1426342D03*
Y1435532D03*
X1117574Y1448604D03*
X1114400Y1518237D03*
X1110725Y1518046D03*
X1109118Y1526046D03*
X1113725Y1530935D03*
X1115802Y1615010D03*
X1117407Y1628495D03*
X1113990Y1631370D03*
X1113325Y1627975D03*
X1117182Y1625460D03*
X1106480Y1641275D03*
X1113110Y1666460D03*
X1104457Y1675490D03*
X1108320Y1680200D03*
X1116338Y1711380D03*
X1112130Y1711600D03*
X1112252Y1706170D03*
X1112200Y1709000D03*
X1114150Y1715726D03*
X1113055Y1718338D03*
X1110663Y1719189D03*
X1119200Y1730300D03*
Y1727200D03*
X1114300Y1722700D03*
X1119300Y1724100D03*
X1111866Y1737108D03*
X1132856Y52926D03*
X1129948Y66786D03*
X1132547Y64864D03*
X1129997Y69864D03*
X1122278Y107549D03*
X1120420Y109829D03*
X1128485Y198159D03*
X1133041Y194137D03*
X1124360Y259712D03*
X1125409Y305797D03*
X1120544Y312200D03*
X1129995Y301637D03*
X1122059Y305673D03*
X1124985Y302578D03*
X1127402Y456174D03*
X1136051Y503324D03*
X1124120Y643762D03*
X1136720Y641362D03*
X1129420Y644062D03*
X1122980Y741312D03*
X1127972Y747250D03*
X1135750Y1255672D03*
X1127179Y1372700D03*
X1124679D03*
Y1370200D03*
X1127179D03*
X1129729Y1372700D03*
Y1370200D03*
Y1375200D03*
X1127179D03*
X1124679D03*
X1129729Y1377700D03*
Y1380200D03*
Y1385200D03*
Y1382700D03*
X1127179D03*
X1124679D03*
X1127179Y1380200D03*
Y1377700D03*
X1124679D03*
Y1380200D03*
Y1385200D03*
X1127179D03*
X1127788Y1397126D03*
X1135709Y1397119D03*
X1133209D03*
X1123674Y1414936D03*
X1121174D03*
X1123674Y1417536D03*
Y1420136D03*
X1121174Y1417536D03*
Y1420136D03*
X1123674Y1422736D03*
X1121174D03*
X1122879Y1431474D03*
Y1434024D03*
X1125995Y1439780D03*
X1136004Y1447858D03*
X1126117Y1450504D03*
X1123379Y1443583D03*
X1133169Y1445690D03*
X1129169Y1442998D03*
X1135568Y1442923D03*
X1129169Y1445719D03*
X1130841Y1462953D03*
X1128341Y1465453D03*
Y1462953D03*
X1130841Y1465453D03*
X1133841Y1462953D03*
Y1465453D03*
X1128341Y1468453D03*
X1130841D03*
X1133841D03*
X1128341Y1460453D03*
X1130841D03*
X1133841D03*
Y1471453D03*
X1130841D03*
X1128341D03*
X1127008Y1524203D03*
X1135748Y1524187D03*
X1127008Y1550285D03*
X1133780Y1550301D03*
X1132142Y1555301D03*
X1135187Y1582738D03*
X1132187Y1590738D03*
X1135187D03*
X1120472Y1615010D03*
X1124862D03*
X1127377Y1628485D03*
X1131632Y1625969D03*
X1131866Y1737108D03*
X1138609Y49388D03*
X1145603Y73679D03*
X1140242Y101135D03*
X1152720Y180862D03*
X1150914Y197407D03*
X1148795Y213731D03*
X1141957Y227277D03*
X1144457D03*
X1139457D03*
X1148354Y222677D03*
X1146670Y230110D03*
X1147700Y362731D03*
X1140465Y379592D03*
X1142302Y366532D03*
X1137315Y379592D03*
X1147700Y368041D03*
X1148220Y501362D03*
X1138551Y503324D03*
X1144720Y501362D03*
Y498662D03*
X1142967Y592097D03*
X1138500Y586362D03*
X1142127Y586452D03*
X1140697Y608762D03*
X1142790Y611122D03*
X1144810Y613762D03*
X1150272Y638346D03*
X1142674Y1287608D03*
X1144247Y1372700D03*
Y1370200D03*
X1146797Y1372700D03*
X1149297D03*
X1146797Y1370200D03*
X1149297D03*
X1144247Y1375200D03*
X1146797D03*
X1149297D03*
X1144247Y1377700D03*
Y1380200D03*
Y1385200D03*
Y1382700D03*
X1146797D03*
X1149297D03*
X1146797Y1380200D03*
Y1377700D03*
X1149297Y1380200D03*
Y1377700D03*
Y1385200D03*
X1146797D03*
X1146118Y1397126D03*
X1138209Y1397119D03*
X1150843Y1415126D03*
X1148243D03*
X1150843Y1417726D03*
X1148243D03*
X1150732Y1420326D03*
X1149469Y1437098D03*
X1151669Y1435698D03*
Y1438598D03*
X1137311Y1445191D03*
X1147203Y1441968D03*
X1149569Y1440098D03*
X1151669Y1441498D03*
X1147203Y1439068D03*
X1141591Y1462853D03*
Y1465353D03*
Y1468353D03*
Y1471353D03*
Y1460353D03*
X1150821Y1459607D03*
Y1456587D03*
X1145108Y1476732D03*
X1138430Y1524150D03*
X1151497Y1524187D03*
X1153465Y1550301D03*
X1149528D03*
X1145410Y1540640D03*
X1143060Y1538380D03*
X1141654Y1550301D03*
X1137717Y1558020D03*
X1141690Y1552920D03*
X1152187Y1574738D03*
X1142187D03*
X1145187D03*
Y1582738D03*
X1141525Y1597630D03*
X1152187Y1590738D03*
X1142187D03*
X1145187D03*
X1140750Y1604330D03*
X1150380Y1602590D03*
X1139392Y1620851D03*
X1146960Y1618960D03*
X1152257Y1628910D03*
X1158609Y49388D03*
X1155703Y73679D03*
X1160720Y180862D03*
X1165440Y176450D03*
X1168710Y176590D03*
X1165000Y190962D03*
X1162500D03*
X1164300Y197262D03*
X1159460Y194090D03*
X1163732Y204887D03*
X1160732D03*
X1160630Y213870D03*
X1158172Y230157D03*
X1159753Y361281D03*
X1156790Y363231D03*
Y373231D03*
X1161690Y374110D03*
X1164320Y451062D03*
X1156100Y456342D03*
X1167190Y526922D03*
X1153467Y586462D03*
X1153490Y610322D03*
X1159912Y638216D03*
X1166722Y636206D03*
X1156770Y638192D03*
X1153370D03*
X1158762Y642266D03*
X1168402Y642136D03*
X1161860Y642112D03*
X1165260D03*
X1155962Y746193D03*
X1156609Y1286685D03*
X1165279Y1372700D03*
X1162779D03*
X1167829D03*
X1162779Y1370200D03*
X1165279D03*
X1167829D03*
X1162779Y1375200D03*
X1165279D03*
X1167829D03*
Y1377700D03*
Y1380200D03*
Y1385200D03*
Y1382700D03*
X1165279D03*
X1162779D03*
X1165279Y1380200D03*
X1162779D03*
Y1377700D03*
X1165279D03*
X1162779Y1385200D03*
X1165279D03*
X1165931Y1397126D03*
X1154714Y1398295D03*
X1157786Y1398252D03*
X1153913Y1420606D03*
Y1415406D03*
Y1418006D03*
X1159124D03*
Y1420606D03*
Y1415406D03*
X1161724D03*
Y1420606D03*
Y1418006D03*
X1156524Y1415406D03*
Y1420606D03*
Y1418006D03*
X1153913Y1423206D03*
X1159124D03*
X1161724D03*
X1156524D03*
X1161022Y1431499D03*
Y1433999D03*
X1164138Y1439780D03*
X1154288Y1432502D03*
X1155964Y1440864D03*
X1164260Y1450423D03*
X1158954Y1450274D03*
X1161522Y1443630D03*
X1167312Y1442998D03*
Y1445964D03*
X1159386Y1464253D03*
Y1466753D03*
X1156386Y1464253D03*
Y1466753D03*
X1159386Y1469253D03*
X1156386D03*
X1153821Y1459607D03*
Y1456587D03*
X1159386Y1461753D03*
X1159476Y1458918D03*
X1156386Y1461753D03*
X1156476Y1458918D03*
X1159446Y1456113D03*
X1156446D03*
X1167245Y1524187D03*
X1159371D03*
X1163308D03*
X1155433D03*
X1165276Y1550301D03*
X1169213D03*
X1157402D03*
X1161339D03*
X1164595Y1574738D03*
X1155187D03*
X1164595Y1582738D03*
X1155187D03*
X1163079Y1601479D03*
X1161595Y1590738D03*
X1164595D03*
X1155187D03*
X1168192Y1604130D03*
X1152950Y1616470D03*
X1165950Y1617729D03*
X1169460Y1606630D03*
Y1616630D03*
Y1611630D03*
X1152930Y1633880D03*
X1158030Y1619250D03*
X1164830Y1628830D03*
X1159930Y1645632D03*
X1164830D03*
X1169325Y1642600D03*
X1158325D03*
X1162383Y1652505D03*
X1164830Y1654632D03*
X1159930D03*
X1161613Y1669112D03*
X1161076Y1680624D03*
X1157700Y1681100D03*
X1174120Y57111D03*
X1175926Y69151D03*
X1180676Y106858D03*
X1187413Y143132D03*
X1181420Y157962D03*
X1181700Y186962D03*
X1173314Y176452D03*
X1170595Y170056D03*
X1181476Y172247D03*
X1173065Y194174D03*
X1173100Y186962D03*
X1172925Y202174D03*
X1181369Y199234D03*
X1181470Y208802D03*
X1172865Y210174D03*
X1172835Y218174D03*
X1181500Y211962D03*
Y218462D03*
Y215962D03*
Y222162D03*
X1172795Y222174D03*
X1180398Y289814D03*
X1186653Y302242D03*
X1171540Y310902D03*
X1181450Y306052D03*
X1174120Y355362D03*
X1169690Y526922D03*
X1172720Y527862D03*
X1172310Y584562D03*
X1181300Y584762D03*
X1174980Y585632D03*
X1174880Y592652D03*
X1170337Y607327D03*
X1173990Y602192D03*
X1176362Y636076D03*
X1173220Y636052D03*
X1169820D03*
X1180262Y642216D03*
X1183360Y642062D03*
X1183230Y739102D03*
X1173020Y745972D03*
X1175573Y1286765D03*
X1172573D03*
X1182747Y1372700D03*
X1185297D03*
X1182747Y1370200D03*
X1185297D03*
X1182747Y1375200D03*
X1185297D03*
X1182747Y1380200D03*
Y1377700D03*
Y1385200D03*
Y1382700D03*
X1185297D03*
Y1377700D03*
Y1380200D03*
Y1385200D03*
X1184661Y1397126D03*
X1171752Y1397119D03*
X1176752D03*
X1174252D03*
X1174147Y1447858D03*
X1171342Y1445650D03*
X1175454Y1445191D03*
X1173711Y1442923D03*
X1179922Y1524203D03*
X1171182Y1524187D03*
X1179922Y1550285D03*
X1184330Y1573260D03*
X1184290Y1570080D03*
X1171595Y1574738D03*
X1174595D03*
Y1582738D03*
X1183410Y1594450D03*
X1183440Y1591640D03*
X1171595Y1590738D03*
X1178140Y1601100D03*
X1184200Y1599900D03*
X1183320Y1597080D03*
X1184501Y1606521D03*
X1169968Y1602370D03*
X1174550Y1615630D03*
X1178250Y1609100D03*
X1184200Y1602700D03*
X1185030Y1633010D03*
X1182470Y1618914D03*
X1172530Y1623020D03*
X1176900Y1627510D03*
X1185030Y1624660D03*
X1181930Y1645632D03*
X1186830D03*
X1175830D03*
X1170930D03*
X1180325Y1642600D03*
X1173383Y1652505D03*
X1184383D03*
X1181930Y1654632D03*
X1175830D03*
X1170930D03*
X1183613Y1669112D03*
X1172613D03*
X1183076Y1680624D03*
X1172076D03*
X1198609Y49388D03*
X1194478Y56986D03*
X1188720Y56755D03*
X1191700Y56822D03*
X1197520Y56962D03*
X1201158Y57130D03*
X1189393Y60183D03*
X1185500Y101400D03*
X1190700Y99000D03*
X1188700Y100700D03*
X1185400Y104000D03*
X1197627Y132859D03*
X1193532Y132644D03*
X1194800Y143112D03*
X1197414Y161592D03*
X1191020Y170862D03*
X1185420Y153762D03*
X1200720Y184862D03*
X1196100Y188962D03*
X1193500D03*
X1188300Y189062D03*
X1200720Y187862D03*
X1200963Y212648D03*
X1192600Y217662D03*
X1193000Y204486D03*
X1195500D03*
X1195100Y217662D03*
X1200830Y206002D03*
X1186340Y204492D03*
X1187300Y217862D03*
X1188500Y205772D03*
X1188600Y225962D03*
X1194840Y240672D03*
X1187013Y238972D03*
X1194840Y236592D03*
X1199720Y252362D03*
X1196720D03*
X1186280Y298972D03*
X1199027Y588714D03*
X1193198Y586172D03*
X1195698D03*
X1198198D03*
X1200698D03*
X1189902Y642086D03*
X1186760Y642062D03*
X1185687Y744475D03*
X1187797Y1372700D03*
Y1370200D03*
Y1375200D03*
Y1382700D03*
Y1377700D03*
Y1380200D03*
Y1385200D03*
X1189135Y1397529D03*
X1187736Y1420387D03*
X1188986Y1415287D03*
Y1417887D03*
X1186386Y1415287D03*
Y1417887D03*
X1191486Y1415287D03*
Y1417887D03*
X1190444Y1420384D03*
X1194750Y1424672D03*
X1191930Y1424647D03*
X1187412Y1437498D03*
X1189612Y1436098D03*
X1191918Y1432516D03*
X1185346Y1442128D03*
X1187512Y1440498D03*
X1189612Y1441898D03*
X1185346Y1439228D03*
X1189612Y1438998D03*
X1187720Y1517688D03*
X1187830Y1522188D03*
X1198546Y1520188D03*
X1187830Y1526688D03*
X1198546Y1524688D03*
X1187720Y1536362D03*
X1198485Y1534313D03*
X1198436Y1529362D03*
X1187720Y1531862D03*
Y1553692D03*
X1198497Y1539667D03*
X1187720Y1548772D03*
Y1544292D03*
X1198436Y1551192D03*
X1197181Y1563587D03*
X1198436Y1561062D03*
X1187720Y1563182D03*
X1194510Y1563076D03*
X1187600Y1622064D03*
X1201600Y1633790D03*
X1199400Y1627800D03*
X1192500Y1645942D03*
X1197400D03*
X1190895Y1642910D03*
X1186000Y1640000D03*
X1197400Y1654942D03*
X1192500D03*
X1186830Y1654632D03*
X1194183Y1669422D03*
X1201110Y1681767D03*
X1193646Y1680934D03*
X1201106Y1677873D03*
X1192340Y1691422D03*
X1197240D03*
X1190735Y1688390D03*
X1194793Y1698295D03*
X1201505Y1688435D03*
X1194023Y1714902D03*
X1192340Y1700422D03*
X1197240D03*
X1193174Y1726414D03*
X1191866Y1737108D03*
X1213026Y56742D03*
X1216176D03*
X1201800Y94600D03*
X1202860Y120392D03*
X1215763Y114363D03*
X1206093Y120362D03*
X1204800Y108900D03*
X1206900Y115900D03*
X1215800Y111300D03*
X1201700Y110000D03*
X1202920Y117162D03*
X1210910Y129502D03*
X1206114Y132962D03*
X1206434Y129492D03*
X1206694Y139512D03*
X1214573Y148909D03*
X1214415Y153962D03*
X1206664Y158952D03*
X1214091Y164962D03*
X1214593Y168962D03*
X1214534Y157462D03*
X1214054Y186092D03*
X1208518Y174162D03*
X1203858Y185451D03*
X1214693Y174962D03*
X1214134Y180972D03*
X1213720Y200309D03*
X1204420Y195362D03*
X1213720Y189362D03*
X1204220D03*
X1213720Y195362D03*
X1215720Y204862D03*
X1203200Y202514D03*
X1219060Y213312D03*
X1210084Y224362D03*
X1206660Y224742D03*
X1213540Y224792D03*
X1207220Y247148D03*
X1217720Y249862D03*
X1207220Y243998D03*
X1210900Y265300D03*
X1208365Y271151D03*
X1204475Y350684D03*
X1205165Y380962D03*
X1218870Y418082D03*
X1214000Y599262D03*
X1208980Y598462D03*
X1207100Y600882D03*
X1204880Y754032D03*
X1211277Y744265D03*
X1206757Y744455D03*
X1210288Y754081D03*
X1202300Y753962D03*
X1207607Y754095D03*
X1202600Y759662D03*
X1215896Y756942D03*
X1206432Y758995D03*
X1202307Y757082D03*
X1210457Y1658415D03*
X1205820Y1652910D03*
X1213980Y1676500D03*
X1210830D03*
X1217210Y1684520D03*
X1218810Y1691732D03*
X1213910D03*
X1203110Y1691467D03*
X1208010D03*
X1212305Y1688700D03*
X1216363Y1698605D03*
X1205563Y1698340D03*
X1207180Y1685680D03*
X1215593Y1715212D03*
X1204793Y1714947D03*
X1208010Y1700467D03*
X1213910Y1700732D03*
X1203110Y1700467D03*
X1203939Y1726459D03*
X1214834Y1726724D03*
X1211866Y1737108D03*
X1218609Y49388D03*
X1228420Y58862D03*
X1230250Y89450D03*
X1228425Y91500D03*
X1222100Y91600D03*
X1225100Y91500D03*
X1228704Y112122D03*
X1232182Y110659D03*
X1224614Y116962D03*
X1219534Y116492D03*
X1223500Y111162D03*
X1223100Y127300D03*
X1226400Y125200D03*
X1226093Y134262D03*
X1229500Y125100D03*
X1223100Y130700D03*
X1226093Y152792D03*
X1234093Y144962D03*
X1226093Y140962D03*
X1222593D03*
X1222920Y144909D03*
Y148909D03*
X1222593Y168962D03*
X1222890Y157002D03*
X1226093Y156962D03*
X1222594Y154242D03*
X1226093Y168162D03*
X1225874Y163462D03*
X1222720Y163362D03*
X1226093Y177962D03*
X1222724Y176102D03*
X1226093Y172962D03*
X1223134Y190802D03*
X1225574Y188662D03*
X1228520Y202162D03*
X1226093Y193462D03*
X1225320Y200162D03*
X1223720Y217862D03*
Y205862D03*
X1223180Y210552D03*
X1233780Y214572D03*
X1232000Y244332D03*
Y248332D03*
X1219220Y243862D03*
Y247148D03*
X1230720Y380362D03*
X1227500Y380400D03*
X1221220Y380362D03*
X1224300Y380400D03*
X1223650Y520672D03*
X1230650D03*
X1227150D03*
X1219060Y757272D03*
X1223327Y757615D03*
X1228320Y758598D03*
X1218810Y1700732D03*
X1231866Y1737108D03*
X1238609Y49388D03*
X1236620Y58862D03*
X1239907Y95008D03*
X1241010Y110782D03*
X1243808Y116832D03*
X1250010Y117121D03*
X1244200Y112862D03*
X1249362Y111600D03*
X1241035Y114399D03*
X1247333Y121999D03*
X1234746Y136040D03*
X1240728Y136198D03*
X1240904Y151592D03*
X1238604Y150062D03*
X1241100Y145842D03*
X1242520Y165362D03*
X1244120Y167462D03*
X1246272Y164889D03*
X1243100Y160181D03*
X1243184Y182422D03*
X1239874Y182322D03*
X1236410Y201462D03*
X1236220Y189362D03*
X1236593Y197462D03*
X1236584Y205762D03*
X1236593Y209562D03*
X1236584Y217462D03*
X1236520Y213462D03*
X1245486Y203000D03*
X1245593Y211762D03*
X1236620Y221562D03*
X1245614Y227462D03*
X1245574Y234042D03*
X1244720Y230362D03*
X1245514Y224302D03*
X1245593Y219662D03*
X1239045Y224062D03*
X1245593Y241462D03*
Y237462D03*
X1246878Y248615D03*
X1240500Y248332D03*
Y244332D03*
X1246444Y256098D03*
X1236720Y257362D03*
X1252040Y306480D03*
X1243589Y379595D03*
X1236720Y377862D03*
X1234720Y380362D03*
X1248150Y520672D03*
X1244650D03*
X1241150D03*
X1237650D03*
X1234150D03*
X1242260Y757602D03*
X1258609Y49388D03*
X1261227Y52061D03*
X1258727D03*
X1263454Y83060D03*
X1266464Y83090D03*
X1264098Y88787D03*
X1262320Y96012D03*
X1262800Y101100D03*
X1264620Y92724D03*
X1258539Y100900D03*
X1252520Y92022D03*
X1258539Y109263D03*
X1260641Y114399D03*
X1252961Y111903D03*
X1264220Y110462D03*
X1250424Y108943D03*
X1257581Y114579D03*
X1266093Y129962D03*
X1256093Y143462D03*
Y149462D03*
X1264663Y158946D03*
X1254994Y157382D03*
X1265010Y162222D03*
X1264685Y175506D03*
X1261899Y174648D03*
X1253624Y201362D03*
X1267315Y220701D03*
X1264874Y217462D03*
X1256504D03*
X1255613Y209568D03*
X1265207Y208442D03*
X1259703Y209808D03*
X1253440Y230552D03*
X1253860Y235622D03*
X1256070Y229512D03*
X1264584Y226592D03*
X1256593Y221462D03*
Y233972D03*
Y225972D03*
X1253950Y246692D03*
X1266715Y244692D03*
X1254370Y241302D03*
X1265065Y249982D03*
X1256494Y243177D03*
X1256574Y238662D03*
X1266518Y237042D03*
X1256584Y248002D03*
X1256454Y252122D03*
X1264854Y253996D03*
Y256496D03*
X1258250Y292986D03*
X1263150Y294726D03*
X1267150Y305998D03*
X1255150Y306211D03*
X1256220Y434362D03*
X1261220Y454362D03*
X1253220Y451362D03*
X1267220D03*
X1260220Y477362D03*
X1255920Y511362D03*
X1251650Y520672D03*
X1255150D03*
X1256787Y749605D03*
X1258667Y751405D03*
X1255520Y747362D03*
X1263486Y739949D03*
X1253586Y1334649D03*
X1257586D03*
X1257672Y1351008D03*
X1251866Y1737108D03*
X1276820Y58142D03*
X1282360Y58132D03*
X1279580D03*
X1278300Y81232D03*
X1279390Y87697D03*
X1275820Y87962D03*
X1270329Y101011D03*
X1266722Y101005D03*
X1278456Y96187D03*
X1279415Y90847D03*
X1281704Y95402D03*
X1279485Y105752D03*
X1282824Y108872D03*
X1271284Y108971D03*
X1278949Y123567D03*
X1282764Y135398D03*
X1277820Y140682D03*
X1281093Y144516D03*
X1271954Y159143D03*
X1271593Y165962D03*
X1278093Y184462D03*
X1278993Y193262D03*
X1273093Y200038D03*
X1278183Y201262D03*
X1275493Y193962D03*
X1267289Y192167D03*
X1269904Y192692D03*
X1272893Y191262D03*
X1271315Y220701D03*
X1267773Y208373D03*
X1273093Y213962D03*
X1275727Y209597D03*
X1267618Y225382D03*
X1277661Y225685D03*
X1267593Y229462D03*
X1278783Y221386D03*
X1282176Y221436D03*
X1278320Y239292D03*
X1282293Y248962D03*
X1279493Y248662D03*
X1282645Y255671D03*
Y252271D03*
X1280223Y256841D03*
X1279841Y253052D03*
X1277771Y255173D03*
X1273754Y256504D03*
X1275557Y269477D03*
Y272436D03*
X1282653Y269446D03*
X1278557Y272436D03*
Y269477D03*
X1272557Y272436D03*
X1276800Y276562D03*
X1269960Y294536D03*
X1271150Y305792D03*
X1272530Y429362D03*
X1284220D03*
X1280270Y434362D03*
X1272220D03*
X1278380Y463362D03*
X1276220Y477362D03*
X1283220D03*
X1269220D03*
X1274420Y463362D03*
X1275576Y730879D03*
X1266727Y752955D03*
X1279788Y1304042D03*
X1280135Y1340002D03*
Y1337402D03*
X1272707Y1334865D03*
X1280135Y1345202D03*
Y1342602D03*
X1279812Y1353552D03*
X1279334Y1356089D03*
X1280312Y1365689D03*
X1275856Y1358098D03*
X1271990Y1358079D03*
X1276891Y1362891D03*
X1282928Y1361833D03*
X1269012Y1371693D03*
Y1368293D03*
X1271866Y1737108D03*
X1287795Y-29033D03*
Y-33989D03*
X1296019Y-35472D03*
Y-31598D03*
X1293024Y-36695D03*
X1296034Y-37987D03*
Y-27958D03*
X1296019Y-25443D03*
X1293024Y-26666D03*
X1290291Y-23211D03*
Y-19811D03*
X1287795Y-9033D03*
Y-13989D03*
Y-19033D03*
Y-23989D03*
X1296019Y-21569D03*
X1293024Y-16637D03*
X1296034Y-17929D03*
X1296019Y-15414D03*
Y-11540D03*
X1290291Y-3211D03*
Y189D03*
X1287795Y967D03*
Y-3989D03*
X1296034Y-7900D03*
X1296019Y-5385D03*
X1293024Y-6608D03*
X1296019Y4644D03*
X1296034Y2129D03*
X1296019Y-1511D03*
X1293024Y3421D03*
X1296019Y14673D03*
X1296034Y12158D03*
X1296019Y8518D03*
X1293024Y13450D03*
X1296034Y22687D03*
X1296019Y19047D03*
Y25202D03*
X1293024Y23979D03*
X1291280Y58262D03*
X1293860Y58312D03*
X1285201Y58121D03*
X1293430Y84072D03*
X1293454Y81232D03*
X1289210D03*
X1298640Y93062D03*
X1292880Y93162D03*
X1292899Y98519D03*
X1294354Y103166D03*
Y105912D03*
X1291704Y109427D03*
X1288093Y125962D03*
X1291478Y137745D03*
X1286150Y131092D03*
X1295053Y140181D03*
X1292293Y143162D03*
X1283425Y179272D03*
X1287943Y233748D03*
X1284437Y230280D03*
X1293893Y237962D03*
X1285710Y249182D03*
X1290293Y247562D03*
X1288637Y240448D03*
X1292630Y240462D03*
X1286611Y260908D03*
X1291071Y275543D03*
Y278543D03*
X1290005Y293768D03*
X1295278Y297056D03*
X1290322D03*
X1290005Y290268D03*
X1294500Y299692D03*
X1291100D03*
X1295887Y315571D03*
X1291500Y312862D03*
Y315362D03*
X1291420Y320662D03*
Y318162D03*
X1295540Y440902D03*
X1301310Y440862D03*
X1291220Y463362D03*
X1294440Y477267D03*
X1296630Y463462D03*
X1300220Y477362D03*
X1284220Y463362D03*
X1289936Y732539D03*
X1294937Y746965D03*
X1290520Y746562D03*
X1292904Y782048D03*
X1292572Y785575D03*
X1292614Y789910D03*
X1297298Y790982D03*
X1296719Y1290197D03*
X1299169Y1295467D03*
Y1297967D03*
X1296569D03*
Y1295467D03*
Y1292967D03*
X1299169D03*
X1296581Y1300474D03*
X1299181D03*
X1296576Y1303298D03*
X1299176D03*
X1295150Y1323217D03*
X1298150D03*
X1291010Y1323307D03*
X1288010D03*
X1283280Y1372301D03*
X1293887Y1370043D03*
X1294477Y1372651D03*
X1290102Y1365789D03*
X1286102Y1365051D03*
X1294312Y1367279D03*
X1292840Y1364821D03*
X1286102Y1368107D03*
X1291866Y1737108D03*
X1299317Y-35486D03*
Y-31612D03*
X1299302Y-38001D03*
Y-27972D03*
X1299317Y-25457D03*
Y-21583D03*
X1299302Y-17943D03*
X1299317Y-15428D03*
Y-11554D03*
X1299302Y-7914D03*
X1299317Y-5399D03*
Y4630D03*
X1299302Y2115D03*
X1299317Y-1525D03*
Y14659D03*
X1299302Y12144D03*
X1299317Y8504D03*
X1299302Y22673D03*
X1299317Y19033D03*
X1299287Y25188D03*
X1311960Y49672D03*
X1301820Y58672D03*
X1314741Y68652D03*
X1311424D03*
X1308174D03*
X1311960Y58152D03*
X1311260Y83032D03*
X1310857Y78542D03*
X1307120Y78562D03*
X1310906Y97807D03*
X1314406Y97756D03*
X1300454Y95302D03*
X1308274Y104162D03*
X1314059Y93877D03*
X1307244Y118452D03*
X1306836Y108242D03*
X1302080Y117032D03*
X1302964Y124633D03*
X1300990Y121812D03*
X1315156Y130656D03*
X1314920Y135361D03*
X1301993Y140462D03*
X1313117Y250605D03*
X1314685Y248651D03*
X1313950Y261612D03*
X1307431Y256099D03*
X1309283Y254162D03*
X1311275Y252297D03*
X1305552Y257974D03*
X1308736Y284948D03*
X1312136D03*
X1308790Y290172D03*
X1302450Y290072D03*
X1307798Y287561D03*
X1313246Y287631D03*
X1307042Y292636D03*
X1303642D03*
X1307442Y306998D03*
X1304042D03*
X1308220Y304262D03*
X1303120Y304162D03*
X1314450Y319841D03*
X1312845Y324764D03*
X1305909D03*
X1317100Y553900D03*
X1308600Y653500D03*
X1303576Y659671D03*
X1311420Y738262D03*
X1305187Y735630D03*
X1315020Y739862D03*
X1307469Y787772D03*
X1303017Y785837D03*
X1301034Y784165D03*
X1304260Y788265D03*
X1309930Y789852D03*
X1306701Y794779D03*
X1305117Y797125D03*
X1309210Y792802D03*
X1315169Y1274887D03*
X1315289Y1269717D03*
X1315229Y1272287D03*
X1304149Y1291317D03*
X1301889Y1284987D03*
X1301829Y1290167D03*
X1301859Y1287587D03*
X1304299Y1280967D03*
X1304269Y1283567D03*
X1304239Y1286147D03*
X1304209Y1288747D03*
X1315176Y1280218D03*
X1315181Y1277594D03*
X1299319Y1290197D03*
X1299349Y1287617D03*
X1301686Y1303268D03*
X1304196Y1299248D03*
X1304189Y1293917D03*
X1304201Y1296624D03*
X1301679Y1292937D03*
Y1295437D03*
Y1297937D03*
X1301691Y1300444D03*
X1311952Y1321945D03*
X1304066Y1323578D03*
X1307656Y1337104D03*
X1305056D03*
X1307656Y1326704D03*
X1305056D03*
X1307656Y1334504D03*
Y1329304D03*
Y1331904D03*
X1305056Y1334504D03*
Y1329304D03*
Y1331904D03*
Y1339704D03*
X1311820Y1330518D03*
Y1333018D03*
X1314936Y1338799D03*
X1312488Y1348353D03*
X1315058Y1349488D03*
X1312650Y1342572D03*
X1308616Y1363345D03*
Y1360445D03*
X1306082Y1359315D03*
X1306182Y1362315D03*
X1304016Y1363945D03*
Y1361045D03*
X1308616Y1357945D03*
X1311866Y1737108D03*
X1318609Y49388D03*
X1316459Y58697D03*
X1330102Y59025D03*
X1322248Y68487D03*
X1321279Y58767D03*
X1317831Y68652D03*
X1322415Y75480D03*
X1322906Y94212D03*
X1319968Y98266D03*
X1316478Y92970D03*
X1329891Y99455D03*
X1329646Y104954D03*
X1322906Y109733D03*
X1330273Y128373D03*
X1326493Y249562D03*
X1323912Y245111D03*
X1317893Y257462D03*
X1328393Y264262D03*
X1320387Y258901D03*
X1325769Y259001D03*
X1325414Y293556D03*
X1328814D03*
X1319903Y299176D03*
X1323303D03*
X1319125Y296540D03*
X1324081D03*
X1324636Y290920D03*
X1329592D03*
X1330248Y325670D03*
X1323312D03*
X1321386Y319841D03*
X1329977Y334384D03*
X1330101Y540049D03*
X1327601D03*
X1328530Y747702D03*
X1325210Y744322D03*
X1331519Y1262027D03*
X1331459Y1264597D03*
X1331399Y1267197D03*
X1317889Y1267147D03*
X1320399Y1267117D03*
X1317883Y1269978D03*
X1317895Y1272485D03*
X1320393Y1269948D03*
X1320405Y1272455D03*
X1331177Y1269933D03*
Y1272433D03*
X1317895Y1274985D03*
X1320405Y1274955D03*
X1331177Y1274933D03*
X1331166Y1280248D03*
X1317746D03*
X1320256Y1280218D03*
X1317895Y1277485D03*
X1320405Y1277455D03*
X1331189Y1277440D03*
X1324945Y1346877D03*
X1327196Y1349068D03*
X1322110Y1342755D03*
X1318110Y1342017D03*
X1326320Y1344245D03*
X1324848Y1341787D03*
X1318110Y1345073D03*
X1331288Y1372440D03*
X1327491Y1372358D03*
X1324491Y1372658D03*
X1327491Y1375858D03*
X1331288Y1375940D03*
X1324491Y1375858D03*
X1327491Y1381478D03*
Y1378478D03*
X1331288Y1378560D03*
X1324491Y1381478D03*
Y1378478D03*
X1331304Y1401986D03*
Y1404986D03*
X1327926D03*
X1322228Y1419890D03*
X1322186Y1411326D03*
Y1414326D03*
Y1417326D03*
X1322270Y1422454D03*
X1325084Y1420066D03*
X1325042Y1408502D03*
Y1411502D03*
Y1417502D03*
Y1414502D03*
X1331344Y1414456D03*
X1330804Y1411536D03*
Y1408536D03*
X1331386Y1420020D03*
X1328008D03*
X1331344Y1417456D03*
X1327966Y1408456D03*
Y1411456D03*
Y1417456D03*
Y1414456D03*
X1331428Y1422584D03*
X1328050D03*
X1322312Y1425018D03*
X1325126Y1422630D03*
X1325168Y1425194D03*
X1328092Y1425148D03*
X1331470D03*
X1344248Y-33989D03*
Y-29033D03*
X1332726Y-27681D03*
X1336024Y-27695D03*
X1339019Y-26472D03*
X1332726Y-32055D03*
X1336024Y-32069D03*
X1332741Y-35695D03*
X1336009Y-35709D03*
X1332756Y-38210D03*
X1336024Y-38224D03*
X1339019Y-37001D03*
X1341752Y-19811D03*
Y-23211D03*
X1344248Y-13989D03*
Y-9033D03*
Y-23989D03*
Y-19033D03*
X1332726Y-11497D03*
X1336024Y-11511D03*
X1339019Y-16443D03*
X1332741Y-15137D03*
X1332726Y-17652D03*
X1336009Y-15151D03*
X1336024Y-17666D03*
Y-21540D03*
X1332726Y-21526D03*
X1332741Y-25166D03*
X1336009Y-25180D03*
X1341752Y189D03*
Y-3211D03*
X1344248Y-3989D03*
Y967D03*
X1336024Y2392D03*
X1336009Y4907D03*
X1332726Y2406D03*
X1332741Y4921D03*
X1339019Y3615D03*
X1332726Y-1468D03*
X1336024Y-1482D03*
X1339019Y-6414D03*
X1336024Y-7637D03*
X1336009Y-5122D03*
X1332726Y-7623D03*
X1332741Y-5108D03*
X1332726Y18590D03*
X1336024Y18576D03*
Y22450D03*
X1332726Y22464D03*
X1339019Y13644D03*
X1336024Y12421D03*
X1336009Y14936D03*
X1332726Y12435D03*
X1332741Y14950D03*
X1332726Y8561D03*
X1336024Y8547D03*
X1336009Y24965D03*
X1332741Y24979D03*
X1339019Y23673D03*
X1338609Y49388D03*
X1333190Y58825D03*
X1346720Y82912D03*
X1347640Y101950D03*
X1345583Y91307D03*
X1336549Y105970D03*
X1339280Y126175D03*
X1344631Y127244D03*
X1332497Y133931D03*
X1343034Y141698D03*
X1344684Y280259D03*
X1343362Y283155D03*
X1336761Y293404D03*
X1340161D03*
X1335947Y290755D03*
X1340903D03*
X1343656Y330749D03*
X1343199Y324461D03*
X1336263D03*
X1336913Y334384D03*
X1344720Y423162D03*
X1337220D03*
X1342220D03*
X1339720D03*
X1333143Y540049D03*
X1340420Y538422D03*
Y541822D03*
X1338652Y536654D03*
Y543590D03*
X1335643Y540048D03*
X1336187Y755635D03*
X1347419Y1259257D03*
X1347379Y1256687D03*
X1336269Y1274957D03*
X1333969Y1264567D03*
X1334029Y1261997D03*
X1333909Y1267167D03*
X1336339Y1269777D03*
X1336279Y1272347D03*
X1347359Y1261857D03*
X1347371Y1264564D03*
X1336519Y1264627D03*
X1336579Y1262057D03*
X1347366Y1267188D03*
X1336459Y1267227D03*
X1333687Y1269903D03*
Y1272403D03*
Y1274903D03*
X1333676Y1280218D03*
X1336261Y1277654D03*
X1333699Y1277410D03*
X1339784Y1306506D03*
X1337184D03*
X1344080Y1305919D03*
X1337663Y1301001D03*
X1343968Y1300579D03*
X1340663Y1301001D03*
X1344080Y1308519D03*
X1337184Y1309106D03*
X1339784D03*
X1338534Y1319406D03*
X1339784Y1316906D03*
Y1314306D03*
Y1311706D03*
X1337184Y1314306D03*
Y1316906D03*
Y1311706D03*
X1343948Y1317092D03*
Y1319592D03*
X1347015Y1335876D03*
X1343631Y1332568D03*
X1344532Y1328161D03*
X1347397Y1325320D03*
X1336144Y1341147D03*
X1338288Y1339653D03*
X1340488Y1340853D03*
X1336144Y1338247D03*
X1340214Y1334853D03*
X1340410Y1338017D03*
X1338288Y1336553D03*
X1334288Y1372440D03*
X1340288D03*
X1346193Y1372523D03*
X1343193D03*
X1337288Y1372440D03*
Y1375940D03*
X1334288D03*
X1343193Y1376023D03*
X1346193D03*
X1340288Y1375940D03*
X1346304Y1401986D03*
X1343304D03*
X1340304D03*
X1337304D03*
X1334304D03*
Y1404986D03*
X1346304D03*
X1343304D03*
X1340304D03*
X1337304D03*
X1337344Y1414456D03*
X1346344D03*
X1343344D03*
X1340344D03*
X1346534Y1411496D03*
Y1408496D03*
X1334344Y1414456D03*
X1346344Y1417456D03*
X1340344D03*
X1337344D03*
X1334386Y1420020D03*
X1334344Y1417456D03*
X1346386Y1420020D03*
X1343386D03*
X1340386D03*
X1337386D03*
X1343344Y1417456D03*
X1337428Y1422584D03*
X1340428D03*
X1343428D03*
X1334428D03*
X1337328Y1425164D03*
X1340328D03*
X1343328D03*
X1346178Y1425254D03*
X1346278Y1422674D03*
X1334470Y1425148D03*
X1331866Y1737108D03*
X1348610Y84712D03*
X1349480Y77072D03*
X1366369Y83820D03*
X1350550Y101632D03*
X1349570Y104147D03*
X1356223Y131569D03*
X1353394Y131812D03*
X1348620Y136162D03*
X1349220Y140362D03*
X1348084Y280259D03*
X1363846Y279848D03*
X1349362Y283155D03*
X1358624Y284644D03*
X1355224D03*
X1353902Y287540D03*
X1359902D03*
X1350592Y330749D03*
X1356968Y339611D03*
X1350032D03*
X1363539Y334043D03*
X1356603D03*
X1356220Y581862D03*
X1356047Y680000D03*
X1358907Y681262D03*
X1361727Y680665D03*
X1352474Y1256866D03*
X1349964Y1256896D03*
X1352486Y1259373D03*
X1349976Y1259403D03*
X1363258Y1256851D03*
Y1259351D03*
X1349876Y1267158D03*
X1352426Y1267218D03*
X1363266Y1267188D03*
X1349976Y1261903D03*
X1352486Y1261873D03*
Y1264373D03*
X1349976Y1264403D03*
X1363258Y1261851D03*
X1363270Y1264358D03*
X1353982Y1287048D03*
X1362382D03*
X1359382D03*
X1350982D03*
X1356983Y1334095D03*
X1359516Y1334058D03*
X1354238Y1329329D03*
X1350238Y1328591D03*
X1358448Y1330819D03*
X1356976Y1328361D03*
X1350238Y1331647D03*
X1352666Y1378560D03*
X1349666D03*
X1352666Y1381560D03*
X1349666D03*
X1352666Y1375940D03*
X1349666D03*
X1355357Y1396020D03*
X1352126Y1401986D03*
X1349426D03*
X1352126Y1404986D03*
X1349426D03*
X1349508Y1420020D03*
X1352166Y1420456D03*
Y1414456D03*
Y1411456D03*
Y1408456D03*
Y1417456D03*
X1349466Y1411456D03*
Y1408456D03*
Y1417456D03*
Y1414456D03*
X1349278Y1422674D03*
X1364860Y1455172D03*
X1362410Y1445272D03*
X1351866Y1737108D03*
X1378839Y87626D03*
X1366124Y101529D03*
X1366369Y92450D03*
X1378550Y110692D03*
X1366714Y109506D03*
X1376991Y176430D03*
X1373591D03*
X1375300Y208422D03*
X1375619Y236261D03*
X1375257Y229756D03*
X1373493Y227762D03*
X1378452Y236055D03*
X1377742Y244372D03*
Y250372D03*
X1380522Y260236D03*
Y263636D03*
X1377626Y258914D03*
Y264914D03*
X1368524Y282744D03*
X1365124D03*
X1369846Y279848D03*
X1378306Y657608D03*
X1372381Y661428D03*
X1371931Y672978D03*
X1374668Y659708D03*
X1378306Y669608D03*
X1374668Y671708D03*
X1371931Y685278D03*
X1370207Y682245D03*
X1374668Y683708D03*
X1378306Y681608D03*
X1372243Y697108D03*
X1374668Y695708D03*
X1378306Y693608D03*
Y705608D03*
X1372243Y709108D03*
Y721108D03*
X1374668Y707708D03*
Y719708D03*
X1378306Y717608D03*
X1374938Y1161569D03*
Y1170069D03*
X1379579Y1259317D03*
X1368379Y1259287D03*
X1379639Y1256747D03*
X1368439Y1256717D03*
X1365768Y1256821D03*
Y1259321D03*
X1365776Y1267158D03*
X1368326Y1267218D03*
X1379519Y1261917D03*
X1379531Y1264624D03*
X1379526Y1267248D03*
X1368361Y1264594D03*
X1368369Y1261897D03*
X1365768Y1261821D03*
X1365780Y1264328D03*
X1375463Y1287048D03*
X1372463D03*
X1370662Y1305980D03*
X1371912Y1303480D03*
X1376208Y1305919D03*
Y1303319D03*
X1371912Y1300880D03*
X1376208Y1300719D03*
Y1295586D03*
X1371912Y1295747D03*
Y1298280D03*
X1376208Y1298119D03*
X1369312Y1303480D03*
Y1300880D03*
Y1295747D03*
Y1298280D03*
X1376208Y1308519D03*
X1376076Y1317092D03*
Y1319592D03*
X1379192Y1325373D03*
X1368272Y1324821D03*
X1372538Y1324591D03*
X1370338Y1323091D03*
X1372538Y1321691D03*
X1379271Y1335963D03*
X1375814Y1332653D03*
X1377214Y1327653D03*
X1368272Y1327721D03*
X1370438Y1326091D03*
X1372538Y1327491D03*
X1377054Y1394028D03*
X1376666Y1402778D03*
X1376686Y1399758D03*
X1367316Y1399053D03*
Y1403458D03*
X1370577Y1421899D03*
X1377060Y1411231D03*
X1367436Y1414778D03*
X1370891Y1410306D03*
X1378417Y1415292D03*
X1367316Y1407458D03*
X1367889Y1419235D03*
X1371960Y1436172D03*
X1365040Y1431142D03*
X1377075Y1425014D03*
X1365235Y1428637D03*
X1370250Y1433715D03*
X1367620Y1431472D03*
X1367170Y1453142D03*
X1368842Y1449261D03*
X1364800Y1449231D03*
X1368980Y1457122D03*
X1370041Y1460374D03*
X1371866Y1737108D03*
X1393250Y93802D03*
X1383480Y88932D03*
X1389609Y145291D03*
X1389443Y147859D03*
X1386684Y145017D03*
X1386404Y149008D03*
X1394182Y171470D03*
X1398182D03*
X1384002Y197668D03*
X1389256D03*
X1380602D03*
X1392656D03*
X1395960Y226422D03*
X1393460D03*
X1386868Y222937D03*
X1384017Y223697D03*
X1386138Y225411D03*
X1384895Y221346D03*
X1381951Y221420D03*
X1380638Y245694D03*
X1386630Y238651D03*
X1380638Y249094D03*
X1386630Y242051D03*
X1381235Y236020D03*
X1383734Y243329D03*
Y237329D03*
X1388778Y250661D03*
X1390600Y248262D03*
X1388754Y253803D03*
Y257203D03*
X1388908Y260301D03*
X1386237Y265620D03*
X1386273Y268670D03*
Y272070D03*
X1386237Y275200D03*
X1385190Y501242D03*
X1390220Y497742D03*
X1392685Y498992D03*
X1387550Y502922D03*
X1387600Y499182D03*
X1391260Y507082D03*
X1381131Y656378D03*
Y668378D03*
X1395831Y666278D03*
X1386931Y660978D03*
X1393206Y664708D03*
X1389568Y662608D03*
X1381131Y680278D03*
X1396031Y680678D03*
X1386931Y675478D03*
X1387143Y690208D03*
X1393206Y679208D03*
X1389568Y677108D03*
X1380731Y692208D03*
X1395631Y695108D03*
X1380731Y704208D03*
X1387143Y704708D03*
X1393206Y693708D03*
X1389568Y691608D03*
Y706108D03*
X1380731Y716208D03*
X1395631Y709608D03*
X1387143Y719235D03*
X1393206Y708208D03*
X1393199Y722708D03*
X1389561Y720608D03*
X1395631Y724135D03*
X1382920Y733725D03*
X1391408Y738625D03*
X1385338Y735098D03*
X1388976Y737198D03*
X1384173Y1161549D03*
X1384089Y1153369D03*
X1386673Y1161520D03*
Y1153340D03*
X1396081Y1161569D03*
Y1153369D03*
X1384173Y1169599D03*
X1386673Y1169570D03*
X1396081Y1170069D03*
X1384652Y1256866D03*
X1382142Y1256896D03*
X1384664Y1259373D03*
X1382154Y1259403D03*
X1395436Y1256851D03*
Y1259351D03*
X1384586Y1267278D03*
X1395426Y1267188D03*
X1382036Y1267218D03*
X1382154Y1261903D03*
X1384664Y1261873D03*
Y1264373D03*
X1382154Y1264403D03*
X1395436Y1261851D03*
X1395448Y1264358D03*
X1390758Y1333473D03*
X1392076Y1335658D03*
X1386366Y1329329D03*
X1382366Y1328591D03*
X1390576Y1330819D03*
X1389104Y1328361D03*
X1382366Y1331647D03*
X1396311Y1385712D03*
X1398680Y1380582D03*
X1387074Y1384272D03*
X1388813Y1393160D03*
X1396115Y1405289D03*
X1390513Y1395452D03*
X1387066Y1401734D03*
X1387291Y1408163D03*
X1396115Y1412789D03*
X1396615Y1420289D03*
X1387470Y1418302D03*
X1385109Y1410427D03*
X1390170Y1423942D03*
X1387068Y1413991D03*
X1384695Y1425047D03*
X1381066Y1425008D03*
X1393630Y1426562D03*
X1388557Y1431645D03*
X1395443Y1434700D03*
X1383429Y1427652D03*
X1392620Y1446708D03*
X1389220D03*
X1382600Y1563480D03*
X1391655Y1570037D03*
X1391055Y1565037D03*
X1384840Y1565640D03*
X1386790Y1563610D03*
X1392475Y1576097D03*
X1396600Y1582500D03*
Y1594000D03*
Y1590200D03*
Y1586400D03*
X1393000Y1590300D03*
X1395325Y1606862D03*
X1386200Y1645700D03*
X1386600Y1641400D03*
X1391866Y1737108D03*
X1412954Y138742D03*
X1409558Y151948D03*
X1404402Y138742D03*
X1407029Y152732D03*
X1410370Y138742D03*
X1406970D03*
X1409558Y156904D03*
X1407029Y156132D03*
X1407613Y177159D03*
X1398770D03*
X1402258Y184263D03*
X1411101D03*
X1409716Y171696D03*
X1401240Y171672D03*
X1401341Y177159D03*
X1404829Y184263D03*
X1404741Y177159D03*
X1408229Y184263D03*
X1412284Y171696D03*
X1407178Y171684D03*
X1403778D03*
X1398006Y197668D03*
X1406786D03*
X1401406D03*
X1410186D03*
X1404630Y220018D03*
X1412270Y230952D03*
X1413900Y225212D03*
X1396900Y228932D03*
X1407420Y220018D03*
X1410820D03*
X1405436Y238378D03*
X1400207Y238257D03*
X1404385Y240929D03*
X1400985D03*
X1407913Y1161569D03*
X1410413Y1153369D03*
X1407913D03*
X1410613Y1161569D03*
X1398831D03*
Y1153369D03*
X1407913Y1170069D03*
X1410613D03*
X1398831D03*
X1411909Y1259257D03*
X1400599Y1256717D03*
X1411969Y1256687D03*
X1397946Y1256821D03*
Y1259321D03*
X1400539Y1259287D03*
X1400521Y1264594D03*
X1400529Y1261897D03*
X1397936Y1267158D03*
X1400486Y1267218D03*
X1411849Y1261857D03*
X1411861Y1264564D03*
X1411856Y1267188D03*
X1397946Y1261821D03*
X1397958Y1264328D03*
X1410819Y1287198D03*
X1407819D03*
X1399419D03*
X1402419D03*
X1404040Y1303480D03*
X1408336Y1305919D03*
Y1303319D03*
X1404040Y1300880D03*
X1408336Y1300719D03*
Y1295586D03*
X1404040Y1295747D03*
Y1298280D03*
X1408336Y1298119D03*
X1401440Y1303480D03*
X1402790Y1305980D03*
X1401440Y1300880D03*
Y1295747D03*
Y1298280D03*
X1408336Y1308519D03*
X1408204Y1317092D03*
Y1319592D03*
X1411320Y1325373D03*
X1400400Y1324821D03*
X1404666Y1324591D03*
X1402466Y1323091D03*
X1404666Y1321691D03*
X1411124Y1335924D03*
X1407719Y1332560D03*
X1408969Y1327645D03*
X1402566Y1326091D03*
X1400400Y1327721D03*
X1404666Y1327491D03*
X1401655Y1384676D03*
X1415171Y1383692D03*
X1412961Y1387387D03*
X1412608Y1391687D03*
X1403615Y1405289D03*
X1411115D03*
X1414362Y1402191D03*
X1411115Y1412789D03*
X1403615Y1420289D03*
X1411115D03*
X1414786Y1426890D03*
X1413440Y1436774D03*
X1409680Y1430613D03*
X1401371Y1434592D03*
X1405876Y1453298D03*
X1403687Y1444711D03*
X1400287D03*
X1403350Y1516435D03*
X1400220Y1518862D03*
X1403590Y1532255D03*
X1403350Y1521335D03*
X1409248Y1528862D03*
X1403740Y1548375D03*
X1403590Y1537155D03*
X1403740Y1543475D03*
X1400160Y1543342D03*
X1404433Y1565037D03*
X1400695Y1570037D03*
X1400715Y1565037D03*
X1407440Y1557552D03*
X1404433Y1570037D03*
X1402536Y1576097D03*
X1398700Y1597800D03*
X1407200Y1591400D03*
X1402680Y1597700D03*
X1411070Y1603282D03*
X1401300Y1619917D03*
X1400000Y1630362D03*
X1410900Y1624800D03*
X1400000Y1626362D03*
Y1642362D03*
Y1634362D03*
Y1638362D03*
X1410500Y1638862D03*
X1396900Y1642100D03*
X1411866Y1737108D03*
X1420222Y184263D03*
X1418268Y171696D03*
X1413950Y184263D03*
X1423110D03*
X1417350D03*
X1426510D03*
X1415684Y171696D03*
X1413350Y220018D03*
X1416020D03*
X1424690D03*
X1424520Y225002D03*
X1416810Y225422D03*
X1428640Y230022D03*
X1428336Y232762D03*
X1415340Y231812D03*
X1418630Y220018D03*
X1422030D03*
X1431430Y251265D03*
X1413847Y239528D03*
X1426020Y261501D03*
X1431430Y256383D03*
Y264060D03*
X1428940Y269292D03*
X1426647Y329050D03*
X1417022Y621419D03*
X1424119Y1161520D03*
X1426619D03*
X1424119Y1153369D03*
X1426619D03*
Y1169570D03*
X1424119D03*
X1416999Y1256866D03*
X1414489Y1256896D03*
X1417011Y1259373D03*
X1414501Y1259403D03*
X1427783Y1256851D03*
Y1259351D03*
X1414366Y1267158D03*
X1416916Y1267218D03*
X1427786Y1267158D03*
X1414501Y1261903D03*
X1417011Y1261873D03*
Y1264373D03*
X1414501Y1264403D03*
X1427783Y1261851D03*
X1427795Y1264358D03*
X1421294Y1334095D03*
X1423656Y1335468D03*
X1418494Y1329329D03*
X1414494Y1328591D03*
X1422704Y1330819D03*
X1421232Y1328361D03*
X1414494Y1331647D03*
X1418990Y1387452D03*
X1422594Y1383301D03*
X1419995Y1397492D03*
X1415620Y1396652D03*
X1419055Y1392497D03*
X1426872Y1405811D03*
X1423256Y1403728D03*
X1424255Y1396612D03*
X1422371Y1407722D03*
X1421371Y1411719D03*
X1421864Y1419730D03*
X1429345Y1433695D03*
X1424930Y1433850D03*
X1419746Y1435932D03*
X1427349Y1442776D03*
X1414264Y1439494D03*
X1419256Y1440258D03*
X1423829Y1442776D03*
X1414350Y1516435D03*
X1426020Y1521535D03*
X1414590Y1532255D03*
X1414350Y1521335D03*
X1427120Y1537355D03*
X1414590Y1537155D03*
X1414740Y1543475D03*
Y1548375D03*
X1427320Y1548575D03*
X1416800Y1564862D03*
X1425620Y1556662D03*
X1428403Y1581378D03*
X1418241Y1583441D03*
X1422145Y1575362D03*
X1416060Y1574922D03*
X1422680Y1582100D03*
X1419450Y1596150D03*
X1423700Y1600400D03*
X1426680Y1603262D03*
X1425770Y1633772D03*
X1429250Y1623391D03*
X1419270Y1631000D03*
X1413230Y1641042D03*
X1438609Y49388D03*
X1434600Y59262D03*
X1441125Y57362D03*
X1438680Y64412D03*
X1444275Y57262D03*
X1432220Y61862D03*
X1440800Y66862D03*
X1429382Y184263D03*
X1442434Y210757D03*
X1441490Y224062D03*
X1438720Y220018D03*
X1430000D03*
X1430120Y225182D03*
X1436060Y220018D03*
X1432660D03*
X1431636Y230448D03*
X1444570Y238372D03*
X1431933Y238125D03*
X1430130Y259342D03*
X1431431Y267378D03*
X1436436Y300319D03*
X1436120Y315772D03*
X1436335Y309407D03*
X1436320Y305862D03*
Y303362D03*
X1436050Y321352D03*
X1436120Y318272D03*
X1436232Y344176D03*
X1437177Y720965D03*
X1433418Y729104D03*
X1435387Y1161569D03*
X1435837Y1153369D03*
X1432887Y1161569D03*
X1433337Y1153369D03*
X1435387Y1170069D03*
X1432887D03*
X1444099Y1259397D03*
X1432899Y1259257D03*
X1444159Y1256827D03*
X1432959Y1256687D03*
X1430293Y1256821D03*
Y1259321D03*
X1444051Y1264704D03*
X1444039Y1261997D03*
X1444046Y1267328D03*
X1432889Y1261867D03*
X1432881Y1264564D03*
X1432846Y1267188D03*
X1430296Y1267128D03*
X1430293Y1261821D03*
X1430305Y1264328D03*
X1437258Y1287198D03*
X1445106Y1287158D03*
X1440258Y1287198D03*
X1437182Y1298991D03*
X1434582Y1304191D03*
Y1306791D03*
Y1301591D03*
Y1296458D03*
Y1298991D03*
X1440507Y1305430D03*
Y1302830D03*
Y1300230D03*
X1440536Y1296455D03*
X1440464Y1308519D03*
X1437182Y1304191D03*
Y1306791D03*
Y1301591D03*
Y1296458D03*
X1440332Y1317092D03*
Y1319592D03*
X1443448Y1325373D03*
X1432528Y1324821D03*
X1436794Y1324591D03*
X1434594Y1323091D03*
X1436794Y1321691D03*
X1443785Y1335981D03*
X1440879Y1333085D03*
X1441332Y1327793D03*
X1434694Y1326091D03*
X1432528Y1327721D03*
X1436794Y1327491D03*
X1439155Y1399064D03*
X1437443Y1406289D03*
X1444997Y1392885D03*
X1435462Y1393009D03*
Y1396409D03*
X1431717Y1420625D03*
Y1417125D03*
Y1409125D03*
X1431829Y1412370D03*
X1443325Y1410068D03*
X1434312Y1415197D03*
X1443112Y1417929D03*
X1445020Y1412672D03*
X1443676Y1432624D03*
X1431717Y1427632D03*
Y1424125D03*
X1433750Y1429208D03*
X1439742Y1436924D03*
X1430204Y1452014D03*
X1434720Y1454862D03*
X1440440Y1454892D03*
X1436330Y1521152D03*
X1436570Y1536972D03*
X1436720Y1548192D03*
X1437140Y1576012D03*
X1444468Y1570610D03*
X1433720Y1569762D03*
X1438300Y1598400D03*
X1440105Y1593352D03*
X1446700Y1598400D03*
X1430250Y1608442D03*
X1438300Y1611000D03*
Y1606800D03*
Y1602600D03*
X1430250Y1612812D03*
X1441800Y1620300D03*
Y1632900D03*
Y1628700D03*
Y1624500D03*
X1438547Y1638212D03*
X1443617D03*
X1431575Y1634842D03*
X1442573Y1649862D03*
X1442587Y1659242D03*
X1438320Y1668292D03*
X1438273Y1671103D03*
X1438220Y1673955D03*
X1446715Y1679957D03*
X1431866Y1737108D03*
X1458609Y49388D03*
X1446000Y67802D03*
X1458720Y153362D03*
Y149362D03*
Y145362D03*
Y169862D03*
Y165862D03*
Y161862D03*
Y157862D03*
X1450720Y169862D03*
X1458720Y181862D03*
Y177862D03*
Y173862D03*
X1450720Y181862D03*
Y177862D03*
X1456423Y209362D03*
X1453823Y205982D03*
X1462561D03*
X1457361D03*
X1459961Y210432D03*
X1456150Y214382D03*
X1449110Y233742D03*
X1446830Y236232D03*
X1453670Y278170D03*
X1455600Y297200D03*
X1459312Y341130D03*
X1456770Y342942D03*
X1460849Y343327D03*
X1445777Y362021D03*
X1460600Y352742D03*
X1462790Y359042D03*
X1462870Y355012D03*
X1449777Y362021D03*
X1459900Y370823D03*
X1456700Y369642D03*
X1455920Y373941D03*
X1463600Y374462D03*
X1449777Y371039D03*
X1449296Y410497D03*
X1455642Y409646D03*
X1449296Y407347D03*
X1449600Y402322D03*
X1456777Y418596D03*
Y426546D03*
X1457176Y656992D03*
X1460814Y654892D03*
X1454889Y658712D03*
X1454439Y670262D03*
X1460814Y666892D03*
X1457176Y668992D03*
X1454439Y682562D03*
X1460814Y678892D03*
X1457176Y680992D03*
X1454751Y694392D03*
Y706392D03*
X1460814Y690892D03*
X1457176Y704992D03*
Y692992D03*
X1460814Y702892D03*
X1454439Y718362D03*
X1457176Y716992D03*
X1460814Y714892D03*
X1459057Y733545D03*
X1457597Y739035D03*
X1456237Y726945D03*
X1457620Y736195D03*
X1460187Y729805D03*
X1457714Y741622D03*
X1458911Y1161569D03*
X1447149D03*
X1449649D03*
X1447299Y1153369D03*
X1449799D03*
X1458911Y1170069D03*
X1447149D03*
X1449649D03*
X1449176Y1256866D03*
X1446666Y1256896D03*
X1449188Y1259373D03*
X1446678Y1259403D03*
X1459960Y1259351D03*
Y1256851D03*
X1449106Y1267358D03*
X1459886Y1267218D03*
X1446556Y1267298D03*
X1446678Y1261903D03*
X1449188Y1261873D03*
Y1264373D03*
X1446678Y1264403D03*
X1459960Y1261851D03*
X1459972Y1264358D03*
X1453366Y1287198D03*
X1458766D03*
X1461766D03*
X1450366D03*
X1453303Y1334095D03*
X1455436Y1335598D03*
X1450622Y1329329D03*
X1446622Y1328591D03*
X1454832Y1330819D03*
X1453360Y1328361D03*
X1446622Y1331647D03*
X1459968Y1402765D03*
X1451176Y1399026D03*
X1451198Y1403047D03*
X1461377Y1417844D03*
X1460224Y1407545D03*
X1458138Y1409955D03*
X1461062Y1413246D03*
X1454829Y1439732D03*
X1459135Y1439627D03*
X1459136Y1442241D03*
X1455006Y1447938D03*
X1459111Y1445669D03*
Y1448669D03*
X1457577Y1526689D03*
X1457817Y1542509D03*
X1457967Y1553729D03*
X1458200Y1565037D03*
Y1560037D03*
X1448620Y1556162D03*
X1446600Y1595400D03*
X1456030Y1590302D03*
X1456120Y1586262D03*
X1453600Y1595662D03*
X1460441Y1602441D03*
X1446786Y1610639D03*
X1451500Y1612800D03*
X1451580Y1627990D03*
X1454167Y1638302D03*
X1459127D03*
X1448507Y1638212D03*
X1452757Y1671399D03*
X1446380Y1676291D03*
X1448920Y1675062D03*
X1464200Y67802D03*
X1474142Y61767D03*
X1470220Y145362D03*
X1462000Y153362D03*
X1470220Y169862D03*
X1473090Y204502D03*
X1465179Y213102D03*
X1470101Y207751D03*
X1472335Y209362D03*
X1467761Y205982D03*
X1476858Y225448D03*
X1466940Y230272D03*
X1471308Y230640D03*
X1463833Y230448D03*
X1466958Y244948D03*
X1477700Y236522D03*
X1474660Y252878D03*
X1463808Y244948D03*
X1463833Y235566D03*
X1468620Y258857D03*
X1467230Y252472D03*
X1473820Y265962D03*
X1471510Y252878D03*
X1471690Y259862D03*
X1463950Y258172D03*
X1463330Y264060D03*
X1466660Y273878D03*
X1463510D03*
X1475452Y289708D03*
X1475352Y306308D03*
X1476826Y312177D03*
X1462777Y362021D03*
X1470877Y374496D03*
X1467700Y370953D03*
X1472758Y370817D03*
X1463277Y406446D03*
X1470954D03*
X1475790Y404842D03*
X1465836Y408668D03*
X1470942Y409718D03*
X1475250Y401812D03*
X1473310Y418502D03*
X1469777Y418396D03*
X1469951Y429251D03*
X1469720Y434542D03*
X1469760Y452622D03*
X1471460Y633402D03*
X1468060D03*
X1466292Y631634D03*
X1473228D03*
X1463639Y653662D03*
X1469651Y655992D03*
X1462010Y645842D03*
X1465171Y647132D03*
X1469020Y647102D03*
X1472076Y657392D03*
X1463639Y665662D03*
X1478139Y660892D03*
X1469439Y670262D03*
X1472076Y671892D03*
X1475714Y659492D03*
Y673992D03*
X1463639Y677562D03*
X1463239Y689492D03*
X1478139Y689892D03*
X1469651Y684992D03*
X1472076Y686392D03*
X1475714Y688492D03*
X1463239Y701492D03*
X1478139Y704392D03*
X1469477Y699475D03*
X1472076Y700892D03*
X1475714Y702992D03*
X1463239Y713492D03*
X1478139Y718892D03*
X1469651Y713992D03*
X1470841Y721493D03*
X1472076Y715392D03*
X1475714Y717492D03*
X1474100Y735662D03*
X1466451Y726992D03*
X1474939Y731892D03*
X1468876Y728392D03*
X1472514Y730492D03*
X1464999Y1259317D03*
X1476369Y1259237D03*
X1465059Y1256747D03*
X1462470Y1259321D03*
Y1256821D03*
X1476291Y1275224D03*
X1464946Y1267248D03*
X1464989Y1261927D03*
X1464981Y1264624D03*
X1476339Y1264467D03*
Y1267037D03*
X1476309Y1261807D03*
X1476279Y1269637D03*
X1476291Y1272344D03*
X1462396Y1267188D03*
X1462470Y1261821D03*
X1462482Y1264328D03*
X1476291Y1278104D03*
X1472592Y1306345D03*
X1474180Y1300407D03*
X1471180D03*
X1465696Y1303480D03*
X1467046Y1305980D03*
X1468296Y1303480D03*
X1465696Y1300880D03*
X1468296D03*
X1472361Y1322440D03*
X1472592Y1308945D03*
Y1316745D03*
Y1314145D03*
Y1311545D03*
X1466819Y1324018D03*
X1469019Y1322618D03*
X1473956Y1341068D03*
X1472460Y1330493D03*
Y1333043D03*
X1475576Y1338799D03*
X1469019Y1325518D03*
X1464680Y1325772D03*
X1469019Y1328418D03*
X1466919Y1327018D03*
X1464680Y1328672D03*
X1475599Y1349468D03*
X1475959Y1385027D03*
X1476000Y1393027D03*
X1465747Y1401405D03*
X1466448Y1421499D03*
X1475935Y1439627D03*
X1475936Y1442241D03*
X1467550Y1439642D03*
X1467536Y1442241D03*
X1467567Y1445669D03*
Y1448669D03*
X1475967Y1445669D03*
Y1448669D03*
X1478320Y1522962D03*
X1472565Y1623635D03*
X1478061Y1633864D03*
X1463767Y1638302D03*
X1476570Y1657974D03*
Y1661124D03*
X1480154Y-29033D03*
Y-33989D03*
X1491661Y-27972D03*
X1491676Y-25457D03*
X1488393Y-27958D03*
X1488378Y-25443D03*
X1485383Y-26666D03*
X1491661Y-38001D03*
X1491676Y-35486D03*
X1488393Y-37987D03*
X1488378Y-35472D03*
Y-31598D03*
X1491676Y-31612D03*
X1485383Y-36695D03*
X1482650Y-19811D03*
Y-23211D03*
X1480154Y-9033D03*
Y-13989D03*
Y-19033D03*
Y-23989D03*
X1491661Y-17943D03*
X1491676Y-15428D03*
X1488393Y-17929D03*
X1488378Y-15414D03*
Y-11540D03*
X1491676Y-11554D03*
X1485383Y-16637D03*
X1488378Y-21569D03*
X1491676Y-21583D03*
X1482650Y189D03*
Y-3211D03*
X1480154Y967D03*
Y-3989D03*
X1485383Y3421D03*
X1491661Y2115D03*
X1491676Y4630D03*
X1488393Y2129D03*
X1488378Y4644D03*
X1491661Y-7914D03*
X1491676Y-5399D03*
X1488393Y-7900D03*
X1488378Y-5385D03*
Y-1511D03*
X1491676Y-1525D03*
X1485383Y-6608D03*
X1488378Y14673D03*
X1488393Y12158D03*
Y22687D03*
X1491661Y22673D03*
X1491676Y14659D03*
X1491661Y12144D03*
X1485383Y13450D03*
X1488378Y8518D03*
X1491676Y8504D03*
X1488378Y19047D03*
X1491676Y19033D03*
X1485383Y23979D03*
X1488378Y25202D03*
X1491646Y25188D03*
X1478609Y49388D03*
X1493120Y240412D03*
X1487958Y236062D03*
X1490060Y255378D03*
X1485320Y260362D03*
X1487058Y281456D03*
X1478745Y281508D03*
X1493289Y280027D03*
X1484958Y289656D03*
X1487658D03*
X1478526Y289677D03*
X1481445Y289708D03*
X1484758Y312356D03*
X1487458D03*
X1484858Y305956D03*
X1487558D03*
X1479745Y312208D03*
X1478426Y306277D03*
X1481345Y306308D03*
X1481360Y358792D03*
X1481484Y361688D03*
X1486884Y374338D03*
X1479207D03*
X1481766Y372288D03*
X1489443D03*
X1494784Y374188D03*
X1486040Y368392D03*
X1478203Y406207D03*
X1488500Y410152D03*
X1481766Y406238D03*
X1490384Y407292D03*
X1493384Y411313D03*
X1482650Y411190D03*
X1495527Y406215D03*
X1493384Y419263D03*
X1481384Y419392D03*
X1486880Y416863D03*
X1484805Y427577D03*
X1489310Y426822D03*
X1478539Y675462D03*
X1481539Y1259377D03*
X1478999Y1259257D03*
X1481479Y1261947D03*
X1481419Y1264547D03*
X1481431Y1267254D03*
X1478939Y1261827D03*
X1478879Y1264427D03*
X1478891Y1267134D03*
X1481359Y1271447D03*
X1492039D03*
X1481359Y1274144D03*
X1492091D03*
X1478859Y1271417D03*
Y1274114D03*
X1481361Y1280054D03*
X1492101D03*
X1478821D03*
X1481359Y1277024D03*
X1492091D03*
X1478859Y1276994D03*
X1491840Y1300447D03*
X1485523Y1347521D03*
X1487386Y1349258D03*
X1482750Y1342755D03*
X1478750Y1342017D03*
X1486960Y1344245D03*
X1485488Y1341787D03*
X1478750Y1345073D03*
X1481155Y1387742D03*
X1481255Y1382042D03*
X1478559Y1385027D03*
X1481159Y1384727D03*
X1481155Y1396342D03*
Y1398942D03*
Y1390342D03*
X1478600Y1393027D03*
X1481107Y1393095D03*
X1479658Y1405397D03*
X1485301Y1409442D03*
X1485274Y1406911D03*
X1485380Y1412202D03*
X1479671Y1410411D03*
Y1412911D03*
Y1407911D03*
X1482201Y1409442D03*
X1482174Y1406911D03*
X1482280Y1412202D03*
X1485387Y1420002D03*
X1481918Y1425579D03*
X1484395Y1439598D03*
X1484336Y1442241D03*
X1484442Y1445557D03*
Y1448557D03*
X1482830Y1525162D03*
X1478724Y1637189D03*
X1480800Y1663600D03*
X1491866Y1737108D03*
X1498609Y49388D03*
X1510500Y125992D03*
X1505821Y215802D03*
X1508959D03*
X1503020D03*
X1499922Y211240D03*
X1505378Y225502D03*
X1496720Y225292D03*
X1504484Y234562D03*
X1508410Y230842D03*
X1510017Y225516D03*
X1501840Y225502D03*
X1512420Y239116D03*
X1509571Y239053D03*
X1507860Y249792D03*
X1510810Y249742D03*
X1509040Y243362D03*
X1504890Y249862D03*
X1506600Y239092D03*
X1504650Y254392D03*
X1508049Y280056D03*
X1498984Y282797D03*
X1508558Y291175D03*
X1504602Y312867D03*
X1505922Y304583D03*
X1509539Y308467D03*
X1496200Y359522D03*
X1498184Y361723D03*
X1497880Y373062D03*
X1498184Y369798D03*
X1495150Y369842D03*
X1503450Y382693D03*
Y385843D03*
X1497770Y732502D03*
X1509638Y738627D03*
X1509350Y741315D03*
X1504747Y747293D03*
X1503514Y801361D03*
Y797961D03*
X1497199Y1275667D03*
X1497259Y1273097D03*
X1494629Y1271477D03*
X1494631Y1274144D03*
X1506569Y1285947D03*
X1508819Y1284797D03*
X1506539Y1288557D03*
X1508759Y1287367D03*
X1508699Y1289967D03*
X1494641Y1280054D03*
X1494631Y1277024D03*
X1506551Y1291254D03*
X1497199Y1278277D03*
X1497161Y1280974D03*
X1506689Y1283377D03*
X1494840Y1300447D03*
X1506591Y1297014D03*
Y1294134D03*
X1508711Y1295554D03*
Y1298434D03*
Y1292674D03*
X1499048Y1319946D03*
X1504720Y1329143D03*
X1503786Y1326076D03*
X1504518Y1335982D03*
X1496784Y1341147D03*
X1498924Y1334882D03*
X1498950Y1339517D03*
X1501149Y1336287D03*
X1496784Y1338247D03*
X1504720Y1342143D03*
Y1344743D03*
X1504588Y1353316D03*
Y1355816D03*
X1501033Y1341462D03*
X1498959Y1342930D03*
X1505116Y1369724D03*
X1505570Y1364212D03*
X1507704Y1361597D03*
X1510027Y1425825D03*
X1507617Y1424045D03*
X1518608Y49377D03*
X1522920Y113030D03*
Y116180D03*
X1513900Y117762D03*
X1518575Y138662D03*
X1526675Y140117D03*
X1526083Y146225D03*
X1524770Y195792D03*
X1521115Y193262D03*
X1521201Y215551D03*
X1524539D03*
X1522009Y210825D03*
X1518110Y215551D03*
X1526998Y209645D03*
X1527732Y219488D03*
X1514520Y231116D03*
X1526152Y225114D03*
X1513110Y247412D03*
X1514593Y249698D03*
Y235116D03*
X1513759Y263676D03*
X1519758Y265161D03*
X1522786Y262558D03*
X1522258Y265161D03*
X1516683Y278437D03*
X1519833Y277297D03*
X1511624Y291175D03*
X1522258Y288956D03*
X1517669Y291516D03*
X1522883Y305187D03*
X1519336Y303426D03*
X1520094Y306543D03*
X1514369Y308467D03*
X1526216Y306909D03*
X1524505Y748912D03*
X1515940Y795815D03*
Y799215D03*
X1513789Y1290037D03*
X1511289Y1287397D03*
X1511199Y1290007D03*
X1513791Y1292704D03*
X1516351D03*
X1513791Y1298464D03*
Y1295584D03*
X1516351D03*
Y1298464D03*
X1511251Y1292704D03*
Y1298464D03*
Y1295584D03*
X1522066Y1312808D03*
X1526066D03*
X1518066D03*
X1515066D03*
X1511066D03*
X1518451Y1369919D03*
X1514878Y1365553D03*
X1510878Y1364815D03*
X1519088Y1367043D03*
X1517616Y1364585D03*
X1510878Y1367871D03*
X1512177Y1427795D03*
X1516137Y1432135D03*
X1513657Y1429985D03*
X1511866Y1737108D03*
X1529002Y32290D03*
X1544010Y27552D03*
X1536310Y47492D03*
X1534818Y66801D03*
Y71793D03*
X1539774Y66801D03*
Y71793D03*
X1541774Y69297D03*
X1532818D03*
X1538996D03*
X1535596D03*
X1534774Y103093D03*
X1529818D03*
X1534060Y100162D03*
X1530660D03*
X1533520Y110662D03*
X1535320Y113062D03*
X1529500Y122122D03*
X1535575Y118862D03*
X1529500Y129602D03*
X1540090Y122782D03*
X1536925Y129937D03*
X1529500Y125862D03*
X1535520Y151562D03*
X1529233Y153162D03*
X1535450Y155262D03*
X1542401Y141561D03*
X1545447Y156035D03*
X1531750Y199762D03*
X1537262Y197834D03*
X1534720Y199803D03*
X1528720Y199862D03*
X1533385Y193108D03*
X1529610Y211614D03*
X1533148D03*
X1531824Y207677D03*
X1534194Y217519D03*
X1532590Y225432D03*
X1529670Y225522D03*
X1535561Y225393D03*
X1531110Y264862D03*
X1539150Y267132D03*
X1528716Y306909D03*
X1533716D03*
X1536216D03*
X1534899Y310447D03*
X1540958Y307756D03*
X1540937Y576522D03*
X1536527Y589012D03*
X1539720Y589862D03*
Y581862D03*
X1540989Y616587D03*
X1540377Y634165D03*
X1541211Y646178D03*
X1535052Y1325904D03*
X1532552Y1334504D03*
X1535052D03*
X1529952D03*
X1532552Y1339704D03*
X1529952D03*
X1537652Y1325904D03*
Y1334504D03*
X1532552Y1337104D03*
X1529952D03*
X1538510Y1346392D03*
X1531302Y1342204D03*
X1535892Y1346354D03*
Y1343754D03*
X1538757Y1356355D03*
Y1360855D03*
Y1365355D03*
X1533178Y1360815D03*
X1530978Y1359315D03*
X1528912Y1361045D03*
X1531078Y1362315D03*
X1533178Y1363715D03*
X1528912Y1363945D03*
X1533178Y1357915D03*
X1531866Y1737108D03*
X1547768Y3010D03*
X1555635Y16999D03*
Y21991D03*
X1553635Y19495D03*
X1556413D03*
X1553486Y23935D03*
X1548530D03*
X1546530Y25931D03*
X1555486D03*
X1547429Y28406D03*
Y37106D03*
X1554515Y28406D03*
Y37106D03*
X1549308Y26431D03*
X1552708D03*
X1554515Y40020D03*
Y48720D03*
X1547429Y40020D03*
Y48720D03*
X1554818Y69297D03*
X1556818Y66801D03*
Y71793D03*
X1557596Y69297D03*
X1543818Y75297D03*
X1552774D03*
X1550774Y77793D03*
Y72801D03*
X1545818Y77793D03*
Y72801D03*
X1546596Y75297D03*
X1549996D03*
X1554239Y138263D03*
X1552960Y124359D03*
X1553189Y127781D03*
X1556049Y147711D03*
X1545763Y159305D03*
X1554723Y200375D03*
X1557560Y196912D03*
X1551160Y189342D03*
X1557900Y220362D03*
X1557760Y214792D03*
X1550353Y217352D03*
X1557320Y203297D03*
X1554723Y224529D03*
X1559400Y229832D03*
X1554723Y248945D03*
X1545668Y305266D03*
X1545768Y302766D03*
X1543958Y307556D03*
X1546458Y307856D03*
X1543858Y310056D03*
X1559387Y589340D03*
X1547312Y579080D03*
X1543720Y581862D03*
X1548720D03*
X1552720Y589862D03*
Y581862D03*
X1554727Y631527D03*
X1554753Y628860D03*
X1553312Y636815D03*
X1559354Y655716D03*
Y659116D03*
X1550417Y677045D03*
X1550487Y681565D03*
X1550057Y693485D03*
X1548479Y706088D03*
X1550320Y696562D03*
X1550917Y704332D03*
X1550390Y709885D03*
X1551866Y1737108D03*
X1567768Y3010D03*
X1560591Y16999D03*
Y21991D03*
X1569808Y16999D03*
Y21991D03*
X1574764Y16999D03*
Y21991D03*
X1562591Y19495D03*
X1567808D03*
X1570586D03*
X1573986D03*
X1559813D03*
X1567659Y23935D03*
X1562703D03*
X1560703Y25931D03*
X1569659D03*
X1574876D03*
X1561602Y28406D03*
Y37106D03*
X1568688Y28406D03*
Y37106D03*
X1563481Y26431D03*
X1566881D03*
X1568688Y40020D03*
Y48720D03*
X1561602Y40020D03*
Y48720D03*
X1563774Y69297D03*
X1561774Y66801D03*
Y71793D03*
X1560996Y69297D03*
X1565818Y75297D03*
X1574774D03*
X1572774Y77793D03*
Y72801D03*
X1567818Y77793D03*
Y72801D03*
X1568596Y75297D03*
X1571996D03*
X1559860Y240002D03*
X1573560Y245078D03*
X1574760Y251032D03*
X1559722Y243110D03*
X1570675Y267857D03*
X1575169Y303929D03*
X1573246Y306650D03*
X1572396Y309450D03*
X1563714Y572792D03*
X1567114D03*
X1561494Y584292D03*
X1559557Y593290D03*
X1560717Y648522D03*
X1564690Y663302D03*
X1564768Y708159D03*
X1570720Y729362D03*
X1562871Y732316D03*
Y735716D03*
X1571577Y747145D03*
X1567547Y755485D03*
X1571920Y762662D03*
X1568490Y758162D03*
X1570374Y760093D03*
X1587768Y3010D03*
X1583981Y16999D03*
Y21991D03*
X1588937Y16999D03*
Y21991D03*
X1576764Y19495D03*
X1581981D03*
X1590937D03*
X1584759D03*
X1588159D03*
X1576876Y23935D03*
X1581832D03*
X1591050D03*
X1583832Y25931D03*
X1589050D03*
X1575775Y28406D03*
Y37106D03*
X1582862Y28406D03*
Y37106D03*
X1589948Y28406D03*
Y37106D03*
X1577654Y26431D03*
X1591828D03*
X1581054D03*
X1589948Y40020D03*
Y48720D03*
X1582862Y40020D03*
Y48720D03*
X1575775Y40020D03*
Y48720D03*
X1576818Y69297D03*
X1585774D03*
X1578818Y66801D03*
Y71793D03*
X1583774Y66801D03*
Y71793D03*
X1582996Y69297D03*
X1579596D03*
X1587818Y75297D03*
X1589818Y77793D03*
Y72801D03*
X1590596Y75297D03*
X1576589Y300927D03*
X1588314Y592553D03*
X1585714D03*
X1583114D03*
X1590914D03*
X1588254Y595103D03*
X1588284Y597613D03*
X1585654Y595103D03*
X1585684Y597613D03*
X1583084D03*
X1583054Y595103D03*
X1588284Y608655D03*
X1585684D03*
X1583084D03*
X1590854Y595103D03*
X1590884Y597613D03*
Y608655D03*
X1588254Y613715D03*
X1588224Y611205D03*
X1585654Y613715D03*
X1585624Y611205D03*
X1583024D03*
X1583054Y613715D03*
X1590854D03*
X1590824Y611205D03*
X1591368Y628727D03*
X1591428Y626177D03*
X1588928D03*
X1588868Y628727D03*
X1591398Y631237D03*
X1588898D03*
X1591368Y650877D03*
X1591338Y648367D03*
X1591398Y645817D03*
X1588868Y650877D03*
X1588838Y648367D03*
X1588898Y645817D03*
X1591368Y653377D03*
X1588868D03*
X1591448Y657677D03*
X1588948D03*
Y660177D03*
X1591448D03*
X1588968Y665237D03*
X1591468D03*
X1588938Y662727D03*
X1591438D03*
X1588938Y679807D03*
X1588878Y682357D03*
X1588908Y684867D03*
X1591438Y679807D03*
X1591378Y682357D03*
X1591408Y684867D03*
X1591328Y696727D03*
X1591388Y694177D03*
X1588888D03*
X1588828Y696727D03*
X1591358Y699277D03*
X1588858D03*
X1591358Y718837D03*
X1591328Y716327D03*
X1591388Y713777D03*
X1588858Y718837D03*
X1588828Y716327D03*
X1588888Y713777D03*
X1590915Y755793D03*
X1591866Y1737108D03*
X1607768Y3010D03*
X1598155Y16999D03*
Y21991D03*
X1603111Y16999D03*
Y21991D03*
X1596155Y19495D03*
X1605111D03*
X1598933D03*
X1602333D03*
X1596006Y23935D03*
X1598006Y25931D03*
X1597035Y28406D03*
Y37106D03*
X1604122Y28406D03*
Y37106D03*
X1595228Y26431D03*
X1604122Y40020D03*
Y48720D03*
X1597035Y40020D03*
Y48720D03*
X1598818Y69297D03*
X1607774D03*
X1600818Y66801D03*
Y71793D03*
X1605774Y66801D03*
Y71793D03*
X1604996Y69297D03*
X1601596D03*
X1596774Y75297D03*
X1594774Y77793D03*
Y72801D03*
X1593996Y75297D03*
X1603778Y189943D03*
X1603726Y198061D03*
X1603747Y192951D03*
X1603530Y202402D03*
X1596444Y215526D03*
X1603706Y211526D03*
X1603580Y206902D03*
X1604240Y227892D03*
X1603920Y222922D03*
X1604040Y219692D03*
X1604270Y231490D03*
X1598030Y251002D03*
X1604290Y242472D03*
X1604240Y238242D03*
X1602980Y560002D03*
X1593514Y592553D03*
X1601830Y590685D03*
X1604430D03*
X1607200Y583962D03*
X1593484Y597613D03*
X1593454Y595103D03*
X1593484Y608655D03*
X1593424Y611205D03*
X1593454Y613715D03*
X1601830Y615201D03*
X1604430D03*
X1598868Y628727D03*
X1598928Y626177D03*
X1593868Y628727D03*
X1593928Y626177D03*
X1596428D03*
X1596368Y628727D03*
X1598898Y631237D03*
X1593898D03*
X1596398D03*
X1598868Y650877D03*
X1598838Y648367D03*
X1596368Y650877D03*
X1593868D03*
X1596338Y648367D03*
X1593838D03*
X1598898Y645817D03*
X1596398D03*
X1593898D03*
X1598868Y653377D03*
X1596368D03*
X1593868D03*
X1598948Y657677D03*
X1593948D03*
X1596448D03*
Y660177D03*
X1593948D03*
X1598948D03*
X1596468Y665237D03*
X1593968D03*
X1598968D03*
X1596438Y662727D03*
X1593938D03*
X1598938D03*
X1593938Y679807D03*
X1596438D03*
X1593878Y682357D03*
X1596378D03*
X1593908Y684867D03*
X1596408D03*
X1598878Y682357D03*
X1598908Y684867D03*
X1598938Y679807D03*
X1596288Y688902D03*
X1598888D03*
X1598828Y696727D03*
X1593828D03*
X1593888Y694177D03*
X1596388D03*
X1596328Y696727D03*
X1593858Y699277D03*
X1596358D03*
X1598888Y694177D03*
X1596288Y691502D03*
X1598858Y699277D03*
X1598888Y691502D03*
X1598858Y718837D03*
X1598828Y716327D03*
X1596358Y718837D03*
X1593858D03*
X1596328Y716327D03*
X1593828D03*
X1596388Y713777D03*
X1593888D03*
X1598888D03*
X1596250Y721452D03*
X1598850D03*
X1599010Y724002D03*
X1598440Y736692D03*
X1592760Y736652D03*
X1595600D03*
X1606788Y756199D03*
X1602788D03*
X1606980Y1449922D03*
X1621920Y25962D03*
X1622220Y49862D03*
X1620818Y69297D03*
X1622818Y66801D03*
Y71793D03*
X1623596Y69297D03*
X1609818Y75297D03*
X1618774D03*
X1616774Y77793D03*
Y72801D03*
X1611818Y77793D03*
Y72801D03*
X1612596Y75297D03*
X1615996D03*
X1623881Y117627D03*
Y129627D03*
X1619980Y590685D03*
X1615800Y584062D03*
X1620170Y623762D03*
X1622770D03*
X1619980Y615201D03*
X1612980Y623762D03*
X1620170Y626362D03*
X1622770D03*
X1612980D03*
X1615580Y650092D03*
Y657762D03*
X1620170D03*
X1622770D03*
X1622109Y652469D03*
X1619509D03*
X1612980Y657762D03*
Y650092D03*
X1615580Y660362D03*
X1620170D03*
X1622770D03*
X1612980D03*
X1622109Y686469D03*
X1619509D03*
X1615580Y684092D03*
X1612980D03*
X1622770Y691762D03*
Y694362D03*
X1620170Y691762D03*
Y694362D03*
X1615580D03*
X1612980D03*
X1615580Y691762D03*
X1612980D03*
X1619509Y720469D03*
X1622109D03*
X1612980Y718092D03*
X1615580D03*
X1610100Y725152D03*
X1610788Y756199D03*
X1614788D03*
X1618788D03*
X1614116Y1411169D03*
X1623448Y1420028D03*
Y1417428D03*
Y1414828D03*
Y1412228D03*
X1612630Y1418842D03*
X1615062Y1421241D03*
X1613047Y1415669D03*
X1615597Y1433669D03*
X1614927Y1426076D03*
Y1429896D03*
X1624353Y1428766D03*
Y1431316D03*
X1617215Y1440822D03*
X1611866Y1737108D03*
X1634021Y16999D03*
Y21991D03*
X1638977Y16999D03*
Y21991D03*
X1632021Y19495D03*
X1634799D03*
X1638199D03*
X1631872Y23935D03*
X1626916D03*
X1624916Y25931D03*
X1633872D03*
X1639089D03*
X1625814Y28406D03*
Y37106D03*
X1632901Y28406D03*
Y37106D03*
X1639988Y28406D03*
Y37106D03*
X1627694Y26431D03*
X1631094D03*
X1625814Y40020D03*
Y48720D03*
X1632901Y40020D03*
Y48720D03*
X1639988Y40020D03*
Y48720D03*
X1629774Y69297D03*
X1627774Y66801D03*
Y71793D03*
X1626996Y69297D03*
X1633022Y75297D03*
X1635022Y77793D03*
X1639978D03*
Y72801D03*
X1635022D03*
X1635800Y75297D03*
X1639200D03*
X1636393Y181778D03*
X1635032Y196188D03*
X1632899Y213012D03*
X1633111Y206693D03*
X1632342Y216015D03*
X1635835Y343002D03*
X1642135Y414202D03*
X1636800Y429982D03*
X1639800D03*
X1636800Y426982D03*
X1639800D03*
X1636800Y438982D03*
X1639800D03*
X1636800Y435982D03*
X1639800D03*
X1636800Y432982D03*
X1639800D03*
X1637667Y587844D03*
Y590444D03*
X1629867D03*
Y587844D03*
X1632467Y590444D03*
Y587844D03*
X1635067Y590444D03*
Y587844D03*
X1626606Y616576D03*
X1629206D03*
X1631806D03*
X1634406D03*
X1637006D03*
X1639606D03*
X1630570Y623762D03*
X1627970D03*
X1625370D03*
X1630570Y626362D03*
X1627970D03*
X1625370D03*
X1630570Y657762D03*
X1627970D03*
X1625370D03*
X1629909Y652469D03*
X1632509D03*
X1624709D03*
X1627309D03*
X1630570Y660362D03*
X1627970D03*
X1625370D03*
X1629909Y686469D03*
X1632509D03*
X1624709D03*
X1627309D03*
X1625370Y691762D03*
Y694362D03*
X1630570D03*
Y691762D03*
X1627970D03*
Y694362D03*
X1632509Y720469D03*
X1627309D03*
X1629909D03*
X1624709D03*
X1638928Y756199D03*
X1630928D03*
X1634928D03*
X1638277Y1269065D03*
X1640812Y1270020D03*
X1631203Y1367492D03*
X1628653D03*
X1626153D03*
X1628653Y1372492D03*
X1631203D03*
X1626153D03*
X1631203Y1369992D03*
X1628653D03*
X1626153D03*
X1628653Y1379992D03*
Y1382492D03*
Y1377492D03*
Y1374992D03*
X1631203Y1377492D03*
Y1374992D03*
Y1379992D03*
Y1382492D03*
X1626153Y1379992D03*
Y1382492D03*
Y1374992D03*
Y1377492D03*
X1637183Y1394411D03*
X1639683D03*
X1629262Y1394418D03*
X1634683Y1394411D03*
X1625948Y1417428D03*
Y1412228D03*
Y1414828D03*
Y1420028D03*
X1630643Y1440290D03*
X1627469Y1437072D03*
X1627591Y1447796D03*
X1637478Y1445150D03*
X1624853Y1440875D03*
X1634643Y1442982D03*
X1638785Y1442483D03*
X1637042Y1440215D03*
X1630643Y1443090D03*
X1635315Y1465745D03*
Y1462745D03*
X1632315Y1468745D03*
X1629815D03*
X1632315Y1465745D03*
X1629815D03*
X1632315Y1462745D03*
X1629815D03*
X1635315Y1468745D03*
Y1460245D03*
X1629815D03*
X1632315D03*
X1629815Y1457745D03*
X1632315D03*
X1635315D03*
X1639645Y1473645D03*
X1631866Y1737108D03*
X1648194Y16999D03*
Y21991D03*
X1653150Y16999D03*
Y21991D03*
X1640977Y19495D03*
X1646194D03*
X1655150D03*
X1648972D03*
X1652372D03*
X1641089Y23935D03*
X1646045D03*
X1648045Y25931D03*
X1654161Y28406D03*
Y37106D03*
X1647074Y28406D03*
Y37106D03*
X1641867Y26431D03*
X1645267D03*
X1647074Y40020D03*
Y48720D03*
X1654161Y40020D03*
Y48720D03*
X1644022Y69297D03*
X1652978D03*
X1646022Y66801D03*
Y71793D03*
X1650978Y66801D03*
Y71793D03*
X1650200Y69297D03*
X1646800D03*
X1655022Y75297D03*
X1641978D03*
X1657022Y77793D03*
Y72801D03*
X1652610Y394727D03*
X1652810Y407402D03*
X1650020Y408952D03*
X1647310Y408922D03*
X1650020Y411452D03*
X1647310Y411422D03*
X1647110Y434177D03*
X1654110D03*
X1652113Y527325D03*
X1652138Y524071D03*
X1651890Y520540D03*
X1657755Y517910D03*
X1651931Y540071D03*
Y536071D03*
X1651851Y532057D03*
X1649291Y556057D03*
X1651112Y545572D03*
X1645530Y549160D03*
X1653230Y549322D03*
X1642720Y560862D03*
X1656238Y592113D03*
X1642873Y604206D03*
Y607206D03*
X1645625Y600495D03*
Y603295D03*
X1642873Y601206D03*
Y598206D03*
X1645625Y597795D03*
Y594995D03*
X1642873Y595006D03*
X1649833Y594946D03*
X1653794Y594956D03*
X1653774Y598576D03*
X1649844Y598555D03*
X1649220Y620662D03*
X1642340Y618546D03*
X1642873Y610206D03*
X1656955Y611090D03*
X1645300Y612202D03*
X1653220Y620662D03*
X1645681Y624011D03*
X1648581D03*
X1651481D03*
X1654809Y638101D03*
X1653319Y642311D03*
X1652351Y639573D03*
X1648811Y628277D03*
X1647081Y626211D03*
X1650081Y626111D03*
X1651711Y628277D03*
X1656550Y653086D03*
X1651635Y651836D03*
X1652581Y646311D03*
X1643582Y652601D03*
X1655637Y646311D03*
X1641082Y652601D03*
X1649363Y649485D03*
X1654809Y672101D03*
X1652351Y673573D03*
X1645681Y658011D03*
X1648581D03*
X1648811Y662277D03*
X1647081Y660211D03*
X1650081Y660111D03*
X1651481Y658011D03*
X1651711Y662277D03*
X1656550Y687086D03*
X1641082Y686601D03*
X1651635Y685836D03*
X1652581Y680311D03*
X1653319Y676311D03*
X1643582Y686601D03*
X1655113Y680835D03*
X1649363Y683485D03*
X1654809Y706101D03*
X1648811Y696277D03*
X1650081Y694111D03*
X1645681Y692011D03*
X1647081Y694211D03*
X1648581Y692011D03*
X1651711Y696277D03*
X1651481Y692011D03*
X1641082Y720601D03*
X1651635Y719836D03*
X1652581Y714311D03*
X1653319Y710311D03*
X1652351Y707573D03*
X1643582Y720601D03*
X1655637Y714311D03*
X1649363Y717485D03*
X1651509Y756492D03*
X1650771Y1367492D03*
X1648271D03*
X1645721D03*
X1648271Y1372492D03*
X1650771D03*
X1645721D03*
X1650771Y1369992D03*
X1648271D03*
X1645721D03*
X1648271Y1379992D03*
Y1382492D03*
X1650771Y1379992D03*
Y1382492D03*
X1648271Y1377492D03*
Y1374992D03*
X1650771Y1377492D03*
Y1374992D03*
X1645721Y1377492D03*
Y1374992D03*
Y1379992D03*
Y1382492D03*
X1656188Y1394736D03*
X1647592Y1394418D03*
X1655779Y1417618D03*
Y1412418D03*
Y1415018D03*
X1653279Y1412418D03*
X1650679D03*
X1653279Y1415018D03*
X1650679D03*
X1653168Y1417618D03*
X1650557D03*
X1655762Y1429794D03*
X1648677Y1436220D03*
X1653243Y1435690D03*
X1651043Y1434190D03*
X1653243Y1432790D03*
X1651143Y1437190D03*
X1653243Y1438590D03*
X1648677Y1439120D03*
X1655295Y1453879D03*
X1652295D03*
X1643065Y1462645D03*
Y1465645D03*
Y1468645D03*
Y1460145D03*
Y1457645D03*
X1655295Y1456899D03*
X1652295D03*
X1648947Y1476695D03*
X1642645Y1473645D03*
X1646958Y1501553D03*
X1651866Y1737108D03*
X1671050Y23935D03*
X1669050Y25931D03*
X1669948Y28406D03*
Y37106D03*
X1671828Y26431D03*
X1669948Y40020D03*
Y48720D03*
X1666022Y69297D03*
X1668022Y66801D03*
Y71793D03*
X1672978Y66801D03*
Y71793D03*
X1672200Y69297D03*
X1668800D03*
X1663978Y75297D03*
X1661978Y77793D03*
Y72801D03*
X1657800Y75297D03*
X1661200D03*
X1668100Y180852D03*
X1668030Y200580D03*
X1667739Y187187D03*
X1666690Y193290D03*
X1674432Y216981D03*
X1666074Y229710D03*
X1660176Y231100D03*
X1670400Y229462D03*
X1668426Y222432D03*
X1660861Y227548D03*
X1659610Y394727D03*
X1663610D03*
X1661110Y434177D03*
X1664970Y472112D03*
X1662447Y480619D03*
X1663376Y515531D03*
X1667376D03*
X1665790Y523417D03*
X1670004Y537065D03*
Y543065D03*
Y531065D03*
X1662262Y537334D03*
X1659740Y542222D03*
X1661872Y534703D03*
X1660243Y532071D03*
X1660866Y546749D03*
X1668917Y549992D03*
X1666902Y555115D03*
X1663502D03*
X1664040Y569642D03*
X1668040D03*
X1672040D03*
X1665700Y583462D03*
X1661510Y583442D03*
X1672770Y580512D03*
X1669770D03*
X1658738Y592113D03*
X1661238D03*
X1664997Y604762D03*
X1662120Y604782D03*
X1664197Y602191D03*
X1669222Y604490D03*
X1670700Y594562D03*
X1672500Y596462D03*
X1660660Y602273D03*
X1657220Y620662D03*
X1663720Y620434D03*
X1664410Y617953D03*
X1668920Y617637D03*
X1660754Y609837D03*
X1669397Y614064D03*
X1663471Y609837D03*
X1659458Y637149D03*
X1658085Y639511D03*
X1659914Y649681D03*
X1659458Y671149D03*
X1658085Y673511D03*
X1659914Y683681D03*
X1659458Y705149D03*
X1658085Y707511D03*
X1659914Y717681D03*
X1666686Y757162D03*
X1669303Y1372492D03*
X1664253D03*
X1666753D03*
X1669303Y1367492D03*
Y1369992D03*
X1666753Y1367492D03*
X1664253D03*
Y1369992D03*
X1666753D03*
X1669303Y1379992D03*
Y1382492D03*
Y1377492D03*
Y1374992D03*
X1666753Y1379992D03*
X1664253D03*
X1666753Y1382492D03*
X1664253D03*
X1666753Y1377492D03*
X1664253D03*
Y1374992D03*
X1666753D03*
X1673226Y1394411D03*
X1667405Y1394418D03*
X1659260Y1394693D03*
X1658390Y1420218D03*
Y1415018D03*
Y1412418D03*
Y1417618D03*
X1663590Y1420218D03*
X1660990D03*
Y1415018D03*
Y1417618D03*
Y1412418D03*
X1663590Y1415018D03*
Y1417618D03*
Y1412418D03*
X1657438Y1438156D03*
X1662496Y1428791D03*
Y1431291D03*
X1665612Y1437072D03*
X1660428Y1447566D03*
X1667577Y1447545D03*
X1662996Y1440922D03*
X1672786Y1442982D03*
X1668786Y1440290D03*
Y1443256D03*
X1657920Y1453405D03*
X1660920D03*
X1657860Y1466545D03*
Y1464045D03*
X1657950Y1456210D03*
X1657860Y1459045D03*
Y1461545D03*
X1660950Y1456210D03*
X1660860Y1466545D03*
Y1464045D03*
Y1459045D03*
Y1461545D03*
X1666123Y1497362D03*
Y1493362D03*
Y1501362D03*
X1665940Y1512862D03*
X1666110Y1504662D03*
X1666123Y1524862D03*
Y1537862D03*
Y1533862D03*
Y1520862D03*
Y1541862D03*
Y1553557D03*
Y1545862D03*
X1671673Y1550815D03*
X1666198Y1565557D03*
X1666123Y1557557D03*
X1666198Y1561557D03*
X1671660Y1569412D03*
X1666198Y1585321D03*
Y1581321D03*
X1671866Y1737108D03*
X1678155Y16999D03*
Y21991D03*
X1683111Y16999D03*
Y21991D03*
X1676155Y19495D03*
X1685111D03*
X1678933D03*
X1682333D03*
X1676006Y23935D03*
X1685223D03*
X1678006Y25931D03*
X1683223D03*
X1677035Y28406D03*
Y37106D03*
X1684122Y28406D03*
Y37106D03*
X1686001Y26431D03*
X1689401D03*
X1675228D03*
X1677035Y40020D03*
Y48720D03*
X1684122Y40020D03*
Y48720D03*
X1688156Y69297D03*
X1674978D03*
X1677156Y75297D03*
X1686112D03*
X1684112Y77793D03*
Y72801D03*
X1679156Y77793D03*
Y72801D03*
X1679934Y75297D03*
X1683334D03*
X1676300Y219762D03*
X1681900Y227962D03*
X1690208Y421855D03*
X1686154Y434160D03*
X1689095Y462640D03*
X1683394Y469878D03*
X1683476Y473378D03*
X1684356Y476290D03*
X1682810Y465940D03*
X1684940Y463030D03*
X1681602Y485180D03*
X1684356Y485628D03*
X1677464Y491790D03*
X1685779Y491230D03*
X1690229Y481845D03*
X1687238Y485496D03*
X1681817Y495290D03*
X1681612Y499290D03*
X1675664Y513802D03*
X1690999Y513107D03*
X1683702Y514687D03*
X1676600Y523902D03*
X1688768Y518107D03*
X1682004Y537065D03*
X1682180Y543065D03*
X1676004D03*
X1682004Y531065D03*
X1676004D03*
X1689544Y543874D03*
X1689506Y539882D03*
X1679941Y552222D03*
X1678860Y556752D03*
X1676040Y569627D03*
X1683369Y562698D03*
Y566098D03*
X1676644Y655345D03*
Y652745D03*
X1679244Y655345D03*
X1681864Y655286D03*
X1679244Y652745D03*
X1676624Y642404D03*
X1676644Y644945D03*
Y647545D03*
Y650145D03*
X1679244Y642345D03*
X1681864Y642286D03*
X1679244Y644945D03*
Y647545D03*
X1681864Y644886D03*
Y647486D03*
Y650086D03*
Y652686D03*
X1679244Y650145D03*
X1688301Y722158D03*
X1683121D03*
X1680401D03*
X1673860Y726522D03*
X1681810Y752955D03*
X1688912Y1372492D03*
X1686362D03*
Y1367492D03*
Y1369992D03*
X1688912Y1367492D03*
Y1369992D03*
Y1377492D03*
Y1374992D03*
Y1382492D03*
Y1379992D03*
X1686362D03*
Y1382492D03*
Y1374992D03*
Y1377492D03*
X1686135Y1394418D03*
X1675926Y1394411D03*
X1678426D03*
X1687860Y1415179D03*
X1689210Y1417679D03*
X1687860Y1412579D03*
X1686820Y1436520D03*
X1688886Y1434790D03*
X1688986Y1437790D03*
X1675621Y1445150D03*
X1676928Y1442483D03*
X1675185Y1440215D03*
X1686820Y1439420D03*
X1680720Y1487062D03*
X1679508Y1503421D03*
Y1498303D03*
X1678340Y1500862D03*
X1679508Y1517803D03*
X1677930Y1520362D03*
X1679508Y1522921D03*
Y1543921D03*
Y1538803D03*
X1678340Y1541362D03*
X1679508Y1563380D03*
Y1583880D03*
X1678230Y1590542D03*
X1674220Y1585321D03*
X1692328Y16999D03*
Y21991D03*
X1697284Y16999D03*
Y21991D03*
X1690328Y19495D03*
X1699284D03*
X1696506D03*
X1693106D03*
X1703617Y26459D03*
X1700217D03*
X1690179Y23935D03*
X1692179Y25931D03*
X1691208Y28406D03*
Y37106D03*
X1698295Y28406D03*
Y37106D03*
X1705381Y28406D03*
Y37106D03*
X1703570Y50649D03*
X1700170D03*
X1698295Y48720D03*
X1697824Y39974D03*
X1691208Y40020D03*
Y48720D03*
X1705381D03*
X1697112Y69297D03*
X1690156Y66801D03*
Y71793D03*
X1695112Y66801D03*
Y71793D03*
X1694334Y69297D03*
X1690934D03*
X1699156Y75297D03*
X1701156Y77793D03*
Y72801D03*
X1705334Y75297D03*
X1701934D03*
X1695950Y96437D03*
X1697725Y205120D03*
X1702490Y204780D03*
X1704223Y209707D03*
Y212207D03*
X1701164Y209758D03*
X1698566Y214904D03*
X1696066D03*
X1693725Y217409D03*
X1698566Y212404D03*
X1696066D03*
X1698725Y217409D03*
X1696225D03*
X1701164Y212258D03*
X1704264Y217458D03*
X1701264D03*
X1704264Y214958D03*
X1701264D03*
X1698566Y209704D03*
X1696066D03*
X1693466Y209504D03*
Y214704D03*
Y212204D03*
X1693987Y230174D03*
Y233174D03*
X1703487Y232174D03*
X1693725Y219909D03*
X1698725D03*
X1696225D03*
X1704264Y219958D03*
X1701264D03*
X1704185Y222710D03*
X1698220Y369652D03*
X1704444Y407045D03*
X1699809Y403985D03*
X1695579D03*
X1702959Y404243D03*
X1707780Y410738D03*
X1697161Y406602D03*
X1692429Y403985D03*
X1697914Y427155D03*
X1698014Y424055D03*
X1701124Y423802D03*
X1694050Y416643D03*
X1695455Y422287D03*
X1707544Y431745D03*
X1707568Y420370D03*
X1701124Y433650D03*
X1697214Y433655D03*
X1704624Y433650D03*
X1690140Y434160D03*
X1700846Y455894D03*
X1697648Y463724D03*
X1693720Y455862D03*
X1697220D03*
X1693648Y463724D03*
X1702760Y478207D03*
X1696760D03*
X1702127Y468719D03*
X1693236Y472650D03*
X1702760Y490207D03*
X1696760D03*
Y484207D03*
X1691151Y493678D03*
X1689943Y479304D03*
X1696120Y506937D03*
X1703720Y509362D03*
X1701811Y501318D03*
X1701635Y497177D03*
X1699300Y498632D03*
X1697210Y500802D03*
X1694050Y501422D03*
X1693711Y498527D03*
X1691129Y501697D03*
X1707200Y498962D03*
X1699553Y513107D03*
X1707552Y506731D03*
X1707716Y513562D03*
X1702930Y526102D03*
X1699265Y525507D03*
X1696851Y515607D03*
X1693701D03*
X1699265Y521507D03*
X1690999Y525507D03*
X1701726Y518107D03*
X1699291Y537507D03*
X1699251Y529507D03*
X1699666Y541507D03*
X1699251Y533642D03*
X1691104Y530503D03*
X1691445Y535011D03*
X1704886Y534564D03*
X1689769Y537339D03*
X1699107Y555783D03*
X1699297Y549507D03*
X1702270Y552742D03*
X1703306Y550064D03*
X1703452Y639381D03*
X1700852D03*
X1698232Y639440D03*
X1700852Y655141D03*
X1703452Y647341D03*
Y649941D03*
Y652541D03*
Y644741D03*
X1700852Y647341D03*
Y649941D03*
Y652541D03*
Y644741D03*
X1698232Y655200D03*
Y644800D03*
Y647400D03*
Y650000D03*
Y652600D03*
X1703452Y641981D03*
X1700852D03*
X1698232Y642040D03*
X1700922Y657781D03*
X1698302Y657840D03*
X1698048Y705662D03*
X1692883Y703943D03*
X1698920Y698562D03*
X1701320Y705678D03*
X1698020Y702962D03*
X1695227Y722325D03*
X1699307Y722465D03*
X1698137Y718345D03*
X1701087Y719055D03*
X1695367Y719345D03*
X1691021Y722158D03*
X1696402Y709533D03*
X1699110Y727452D03*
X1705035Y729210D03*
X1704973Y753019D03*
X1703310Y749455D03*
X1698537Y766015D03*
X1690620Y760702D03*
X1691412Y1372492D03*
Y1367492D03*
Y1369992D03*
Y1377492D03*
Y1374992D03*
Y1382492D03*
Y1379992D03*
X1690809Y1393970D03*
X1699150Y1393613D03*
X1690460Y1415179D03*
Y1412579D03*
X1691918Y1417676D03*
X1692960Y1415179D03*
Y1412579D03*
X1693404Y1421939D03*
X1699593Y1428384D03*
X1697820Y1423616D03*
X1699545Y1425868D03*
X1699437Y1431295D03*
X1691086Y1436290D03*
Y1433390D03*
X1693392Y1429808D03*
X1691086Y1439190D03*
X1691988Y1498303D03*
X1704723Y1500862D03*
X1691988Y1517803D03*
X1704723Y1520362D03*
X1691988Y1538803D03*
X1704723Y1541362D03*
X1691988Y1558262D03*
X1705003Y1564057D03*
X1705723Y1583821D03*
X1691866Y1737108D03*
X1707220Y15662D03*
X1715210Y18282D03*
X1714589Y21562D03*
X1714520Y37162D03*
X1709589Y26062D03*
X1719589Y25862D03*
X1717089D03*
X1710106Y48720D03*
Y40020D03*
X1720895Y68062D03*
X1716875D03*
X1710920Y82162D03*
X1708112Y75297D03*
X1706112Y77793D03*
Y72801D03*
X1708000Y99122D03*
X1712520Y117862D03*
X1712720Y111862D03*
X1719943Y112667D03*
Y116667D03*
X1713418Y130862D03*
X1721418Y135327D03*
X1717418D03*
X1714180Y154790D03*
X1714490Y142920D03*
X1717140Y148910D03*
X1711700Y140200D03*
X1717619Y165909D03*
X1718110Y159040D03*
X1719530Y162950D03*
X1717280Y174970D03*
X1722078Y189483D03*
X1720310Y191252D03*
X1707159Y217580D03*
Y215080D03*
Y210080D03*
Y222580D03*
Y225080D03*
Y220080D03*
X1721400Y374462D03*
X1713720Y381152D03*
X1717220D03*
X1719200Y371162D03*
X1713720Y391652D03*
Y384652D03*
Y388152D03*
X1717220Y391652D03*
Y388152D03*
Y384652D03*
X1707444Y407045D03*
X1709000Y413362D03*
X1706500D03*
X1711144Y425945D03*
X1709000Y415862D03*
X1706500D03*
X1721220Y458362D03*
X1713977Y457137D03*
X1708977Y458542D03*
X1711477Y465229D03*
Y468379D03*
X1708760Y478031D03*
X1721936Y469263D03*
X1716134Y478443D03*
X1715711Y474399D03*
X1713977Y470804D03*
X1708977D03*
X1708760Y490207D03*
Y484207D03*
X1716148Y483720D03*
X1716087Y495665D03*
X1716156Y487685D03*
X1716278Y491676D03*
X1707552Y503331D03*
X1709844Y516106D03*
X1710500Y538162D03*
X1707610Y534113D03*
X1709356Y541144D03*
X1716110Y532632D03*
X1707346Y547504D03*
X1717987Y569705D03*
X1709027Y655141D03*
X1716480Y691410D03*
X1706720Y703762D03*
X1710550Y691327D03*
X1712824Y696476D03*
X1710122Y703509D03*
X1713920Y700962D03*
X1709828Y719283D03*
X1709107Y728449D03*
X1713450Y728222D03*
X1719727Y1472088D03*
X1718149Y1496270D03*
X1717149Y1505895D03*
X1720174D03*
X1717988Y1520951D03*
X1711988D03*
X1717149Y1513945D03*
X1720174D03*
X1714988Y1520951D03*
X1708988D03*
X1717988Y1530445D03*
X1714988D03*
X1708988D03*
X1711988D03*
X1711866Y1737108D03*
X1727768Y3010D03*
X1732320Y28162D03*
X1728820D03*
X1725320D03*
X1726720Y49862D03*
X1733720D03*
X1730220D03*
X1736040Y41792D03*
X1732810Y52482D03*
X1736040Y44292D03*
X1730140Y52552D03*
X1727600Y52582D03*
X1729520Y61762D03*
X1729620Y57262D03*
X1725320Y67962D03*
X1730820Y76362D03*
X1726918Y101967D03*
X1723018Y101667D03*
X1723218Y93267D03*
X1738220Y98862D03*
X1736720Y101862D03*
X1729080Y118132D03*
X1739720Y120892D03*
X1728999Y112895D03*
X1733378Y134907D03*
X1736508D03*
X1730765Y151362D03*
X1733920D03*
X1723670Y149102D03*
X1728320Y169862D03*
X1723240Y185200D03*
X1737704Y183139D03*
X1723090Y173072D03*
Y177072D03*
X1734857Y184865D03*
X1737470Y177147D03*
X1738200Y193862D03*
X1737500Y217962D03*
Y214962D03*
Y211962D03*
Y208962D03*
Y226962D03*
Y223962D03*
Y220962D03*
X1725344Y359334D03*
X1737260Y368132D03*
X1732660Y372692D03*
X1725400Y372062D03*
X1728300Y377787D03*
X1725500Y383662D03*
X1733780Y390620D03*
X1729810D03*
X1737660D03*
X1737434Y398990D03*
X1727760Y420415D03*
X1734290Y423820D03*
X1727700Y417265D03*
X1739316Y480939D03*
X1725473Y474859D03*
X1730954Y478062D03*
X1725522Y482869D03*
X1733354Y490869D03*
Y486869D03*
X1738014Y1287344D03*
X1724431Y1336311D03*
X1734717Y1404340D03*
X1729700Y1462932D03*
X1733200D03*
X1736700D03*
X1736400Y1458942D03*
Y1455442D03*
X1731600Y1457230D03*
X1726120Y1490262D03*
X1726149Y1496270D03*
X1724649Y1513945D03*
X1727674D03*
X1729310Y1520951D03*
X1735310D03*
X1724649Y1505895D03*
X1727674D03*
X1726310Y1530445D03*
X1732310D03*
X1729310D03*
X1735310D03*
X1726310Y1520951D03*
X1732310D03*
X1731866Y1737108D03*
X1747768Y3010D03*
X1754090Y16302D03*
X1753388Y28360D03*
X1748400Y37262D03*
X1751065Y39017D03*
X1754620Y39062D03*
X1747720Y31862D03*
Y34362D03*
X1753398Y48720D03*
X1740858Y72330D03*
Y79830D03*
Y74830D03*
Y82330D03*
X1754398Y100307D03*
X1745220Y98862D03*
X1741720D03*
X1743720Y101862D03*
X1740220D03*
X1748720Y97362D03*
X1745485Y119539D03*
X1745010Y122952D03*
X1750820Y119972D03*
X1747482Y121367D03*
X1741222Y151527D03*
X1738520Y151362D03*
X1751220Y147562D03*
X1748465D03*
X1747591Y171733D03*
X1754120Y171562D03*
X1750920Y171662D03*
X1751084Y190928D03*
X1752200Y197762D03*
X1748500Y193862D03*
X1745500D03*
X1741200D03*
X1754234Y190836D03*
X1752078Y216728D03*
X1740500Y217962D03*
Y214962D03*
Y211962D03*
Y208962D03*
X1747600Y209062D03*
X1744600D03*
X1751800Y206762D03*
X1752078Y226728D03*
Y224228D03*
Y221728D03*
Y219228D03*
X1740500Y226962D03*
Y223962D03*
Y220962D03*
X1754307Y262186D03*
X1751068Y262123D03*
X1754245Y269724D03*
X1751068Y266048D03*
X1754307Y266111D03*
X1754414Y275329D03*
X1752165Y273901D03*
X1749565D03*
X1751006Y269661D03*
X1749595Y276711D03*
X1752195D03*
X1746484Y279682D03*
X1745000Y299862D03*
X1749450Y293862D03*
X1756204Y301695D03*
X1752000Y306562D03*
X1748989Y380206D03*
X1756933Y372452D03*
X1744380Y382892D03*
X1744510Y377452D03*
X1747080Y435870D03*
X1746720Y464862D03*
X1740831Y489362D03*
X1740886Y493960D03*
X1752316Y703969D03*
Y695669D03*
X1752217Y692988D03*
X1752276Y720529D03*
X1752316Y712269D03*
X1747814Y1287344D03*
X1742714Y1287244D03*
X1754165Y1304422D03*
Y1307422D03*
Y1301422D03*
Y1295422D03*
Y1298422D03*
Y1310422D03*
X1738740Y1451742D03*
X1740200Y1462932D03*
X1745111Y1463262D03*
X1747677Y1507388D03*
X1744677D03*
X1747304Y1524976D03*
X1744304D03*
X1751866Y1737108D03*
X1767768Y3010D03*
X1762420Y21562D03*
X1765238Y22062D03*
X1768026Y24165D03*
X1769669Y15244D03*
X1761998Y15187D03*
X1765260Y18262D03*
X1757320Y15872D03*
X1758672Y26431D03*
X1755272D03*
X1760475Y28360D03*
X1769900Y37732D03*
X1767220Y26962D03*
X1758669Y50649D03*
X1755269D03*
X1760485Y48720D03*
X1762738Y53262D03*
X1767220Y53342D03*
X1767185Y48817D03*
X1767400Y39915D03*
X1769274Y50742D03*
X1771774Y53682D03*
X1759700Y57662D03*
X1764400Y57462D03*
X1758063Y68637D03*
X1758573Y87107D03*
Y83607D03*
X1768168Y80497D03*
X1758568Y79697D03*
X1765068Y80397D03*
X1758063Y72623D03*
X1767170Y83607D03*
X1767990Y76797D03*
X1760478Y90027D03*
X1770368Y72691D03*
X1766278Y93627D03*
X1757978Y116727D03*
X1760978D03*
X1763678Y106127D03*
X1769278Y108027D03*
Y110927D03*
Y113727D03*
X1755978Y108427D03*
Y111027D03*
X1760478Y106127D03*
X1764678Y122927D03*
X1758300Y128242D03*
X1768483Y166260D03*
X1763435Y166862D03*
X1765870Y179392D03*
X1765820Y182282D03*
X1767300Y174587D03*
X1755078Y216928D03*
X1761500Y214062D03*
X1765000D03*
X1768500D03*
X1766880Y234842D03*
Y231842D03*
X1758500Y231822D03*
Y234822D03*
X1755378Y233528D03*
X1755078Y219428D03*
Y221928D03*
Y224428D03*
X1763731Y283817D03*
X1766725Y282981D03*
X1763731Y279517D03*
X1760398Y279548D03*
X1766765Y279433D03*
X1757439Y279611D03*
X1760398Y283848D03*
X1759509Y292434D03*
X1762549Y286704D03*
X1757439Y283911D03*
X1768045Y295238D03*
X1765053Y295188D03*
X1762285Y295137D03*
X1759629Y295164D03*
X1767309Y290994D03*
X1763045Y289691D03*
X1759529Y289864D03*
X1766655Y286531D03*
X1760104Y301648D03*
X1767455Y302651D03*
X1764955Y301951D03*
X1758563Y310478D03*
X1754963D03*
X1761936Y310709D03*
X1769230Y310478D03*
X1770520Y364148D03*
X1756800Y364048D03*
X1770520Y368148D03*
X1768757Y380498D03*
X1756800Y368048D03*
X1770280Y372452D03*
X1770220Y377452D03*
Y382952D03*
X1757066Y435721D03*
X1767300Y461393D03*
X1765670Y458012D03*
X1757650Y461393D03*
X1767300Y465893D03*
X1768560Y539042D03*
X1766060D03*
X1768317Y686375D03*
X1764112Y703948D03*
X1761612D03*
X1764112Y695648D03*
X1763570Y693192D03*
X1761612Y695648D03*
X1755112Y703948D03*
Y695648D03*
X1755013Y692967D03*
X1757612Y703948D03*
Y695648D03*
X1764072Y720508D03*
X1761572D03*
X1764112Y712248D03*
X1761612D03*
X1755072Y720508D03*
X1755112Y712248D03*
X1757572Y720508D03*
X1757612Y712248D03*
X1757165Y1304422D03*
X1760165D03*
Y1307422D03*
X1757165D03*
X1769165Y1301422D03*
X1766165D03*
X1763165D03*
X1757165D03*
X1760165D03*
X1769165Y1295422D03*
X1766165D03*
X1763165D03*
X1760165D03*
X1757165D03*
X1760165Y1298422D03*
X1757165D03*
X1763165D03*
X1766165D03*
X1769165D03*
X1758352Y1317368D03*
Y1322168D03*
X1757165Y1310422D03*
X1760165D03*
X1759987Y1325375D03*
Y1328275D03*
X1763829Y1337548D03*
X1766829D03*
Y1340448D03*
X1769829Y1337548D03*
Y1340448D03*
X1766829Y1343348D03*
X1769829Y1346248D03*
Y1343348D03*
Y1349148D03*
Y1351858D03*
X1782305Y13647D03*
X1775556Y21471D03*
X1775830Y26522D03*
X1777754Y37746D03*
X1781774Y54462D03*
X1774274Y50742D03*
X1776710Y53562D03*
X1779411Y50692D03*
X1774328Y60087D03*
X1779778Y70027D03*
X1774328Y62987D03*
X1775580Y73330D03*
X1785178Y86927D03*
X1779778Y72927D03*
X1787790Y85132D03*
X1781485Y88192D03*
X1785142Y76032D03*
X1773611Y88293D03*
X1785178Y89927D03*
X1778578Y97927D03*
X1778478Y90627D03*
X1784178Y108227D03*
Y111127D03*
Y113927D03*
X1782000Y128455D03*
X1771915Y128393D03*
X1782000Y125955D03*
Y123455D03*
X1771915Y125893D03*
Y123393D03*
X1784238Y150744D03*
X1780320Y153162D03*
X1774950Y167392D03*
X1779500Y171692D03*
X1780320Y177602D03*
X1777520Y178403D03*
Y173903D03*
X1782600Y175932D03*
X1778778Y216928D03*
X1783878D03*
X1772000Y214062D03*
X1786690Y234782D03*
Y231782D03*
X1783800Y231762D03*
Y234762D03*
X1775140Y234792D03*
Y231792D03*
X1778778Y219428D03*
Y221928D03*
X1783878Y224428D03*
Y226928D03*
Y219428D03*
Y221928D03*
X1779226Y275604D03*
X1783563Y273471D03*
X1786089D03*
X1771029Y295164D03*
X1771229Y291064D03*
X1786089Y287641D03*
X1783563D03*
X1777354Y295489D03*
X1772863Y310478D03*
X1783018Y301729D03*
X1782324Y410432D03*
Y403932D03*
Y425432D03*
Y418932D03*
X1782420Y443987D03*
X1773870Y438222D03*
X1782420Y447137D03*
X1781470Y452065D03*
X1776160Y592792D03*
X1778310Y591152D03*
X1781720Y592742D03*
X1778165Y1307422D03*
Y1304422D03*
Y1301422D03*
X1775165D03*
X1772165D03*
X1778165Y1295422D03*
X1775165D03*
X1772165D03*
Y1298422D03*
X1775165D03*
X1778165D03*
X1784165Y1307422D03*
Y1304422D03*
X1781165Y1307422D03*
Y1304422D03*
X1784165Y1301422D03*
Y1295422D03*
Y1298422D03*
X1781165Y1301422D03*
Y1295422D03*
Y1298422D03*
X1781829Y1324448D03*
X1784829D03*
X1778829D03*
X1778165Y1310422D03*
Y1312922D03*
X1784165Y1310422D03*
Y1312922D03*
X1781165Y1310422D03*
Y1312922D03*
X1781829Y1333148D03*
Y1330248D03*
Y1327348D03*
X1784829Y1333148D03*
Y1330248D03*
Y1327348D03*
X1781829Y1337548D03*
Y1340448D03*
X1784829Y1337548D03*
Y1340448D03*
X1778829Y1333148D03*
Y1330248D03*
Y1327348D03*
Y1337548D03*
X1772829D03*
X1775829D03*
X1778829Y1340448D03*
X1775829D03*
X1772829D03*
X1781829Y1346248D03*
Y1343348D03*
Y1349148D03*
Y1351858D03*
Y1354758D03*
X1772829Y1346248D03*
X1775829D03*
X1778829D03*
X1772829Y1343348D03*
X1775829D03*
X1778829D03*
X1772829Y1349148D03*
X1775829D03*
X1778829D03*
X1772829Y1351858D03*
X1775829D03*
X1778829D03*
X1772829Y1354758D03*
X1775829D03*
X1778829D03*
X1771866Y1737108D03*
X1787768Y3010D03*
X1793061Y24659D03*
X1794910Y44573D03*
X1799920Y52594D03*
X1788238Y82292D03*
Y78062D03*
Y74912D03*
X1797324Y161465D03*
X1803215Y154032D03*
X1797663Y269571D03*
X1800189D03*
X1790563Y273471D03*
X1793089D03*
X1793269Y287641D03*
X1790743D03*
X1791619Y294441D03*
X1789093D03*
X1802763Y308671D03*
X1795763D03*
X1798289D03*
X1788763D03*
X1791289D03*
X1803129Y362293D03*
X1800160Y362542D03*
X1800340Y387062D03*
X1802929Y385293D03*
X1791494Y386536D03*
X1795479Y408056D03*
X1792450Y410615D03*
X1792507Y403932D03*
X1795468Y421334D03*
X1792220Y425432D03*
X1792335Y418775D03*
X1796020Y451162D03*
X1791888Y683805D03*
X1800107Y1256426D03*
X1795484Y1496401D03*
X1800450Y1505230D03*
X1792645Y1511423D03*
X1798450Y1524830D03*
X1801450D03*
Y1527830D03*
X1795561Y1524729D03*
X1814322Y49388D03*
X1807549Y56415D03*
X1807580Y59397D03*
X1806920Y150862D03*
X1808910Y143902D03*
X1813335Y155435D03*
X1810835Y163986D03*
X1806365Y154032D03*
X1819939Y177243D03*
X1813325Y177257D03*
X1807220Y179897D03*
X1814349Y269634D03*
X1811823D03*
X1807249D03*
X1804723D03*
X1812349Y308734D03*
X1809823D03*
X1805289Y308671D03*
X1820307Y373829D03*
X1817157D03*
X1820144Y398052D03*
X1819374Y410432D03*
X1816224D03*
X1816994Y398052D03*
X1818874Y423932D03*
X1815724D03*
X1810792Y417432D03*
X1818816Y468872D03*
X1812161Y472521D03*
X1814537Y1322105D03*
X1803517Y1495567D03*
X1813700Y1494762D03*
X1807150Y1505675D03*
X1818289Y1501591D03*
X1811494Y1505349D03*
X1813994Y1507891D03*
X1818410Y1525815D03*
X1812250Y1521830D03*
X1811250Y1524830D03*
Y1527830D03*
X1807850D03*
X1804650D03*
Y1524830D03*
X1807850D03*
X1814370Y1528900D03*
X1814210Y1525815D03*
X1818524Y1528991D03*
X1834322Y49388D03*
X1828777Y156520D03*
X1823508Y158868D03*
X1825762Y167662D03*
X1835760Y185772D03*
X1829695Y226333D03*
X1832295D03*
X1827095D03*
X1824095D03*
X1834895D03*
Y223733D03*
X1824095D03*
X1827095D03*
X1832295D03*
X1829695D03*
X1832295Y233933D03*
X1829695D03*
X1827095D03*
X1824095D03*
X1829695Y231433D03*
X1832295D03*
X1829695Y228933D03*
X1832295D03*
X1827095Y231433D03*
X1824095D03*
X1827095Y228933D03*
X1824095D03*
X1834895Y233933D03*
Y231433D03*
Y228933D03*
X1828204Y328654D03*
X1829189Y363731D03*
X1829026Y367701D03*
X1829434Y406348D03*
X1834005Y401421D03*
X1821280Y413432D03*
X1834600Y406442D03*
X1826914Y431718D03*
X1829514Y1498198D03*
Y1500807D03*
X1832114Y1498198D03*
Y1500807D03*
X1824995Y1502201D03*
X1823426Y1507916D03*
X1831994Y1525977D03*
X1835334Y1520921D03*
X1828510Y1525915D03*
X1821710D03*
X1830466Y1606658D03*
X1828880Y1626595D03*
Y1646595D03*
Y1666595D03*
Y1686595D03*
X1841257Y151402D03*
X1846691Y166450D03*
X1838910Y185772D03*
X1844157Y182210D03*
X1848435Y172187D03*
X1838880Y195162D03*
X1837895Y226333D03*
Y223733D03*
Y233933D03*
Y231433D03*
Y228933D03*
X1843134Y244362D03*
X1850331Y311946D03*
X1840691Y329470D03*
Y349470D03*
Y369470D03*
X1836750Y373632D03*
X1836294Y383592D03*
X1840691Y389470D03*
Y409470D03*
Y429470D03*
Y449470D03*
X1838020Y459121D03*
X1838379Y453921D03*
X1840691Y469470D03*
Y489470D03*
Y509470D03*
Y529470D03*
Y549470D03*
Y569470D03*
Y589470D03*
Y669470D03*
Y1329470D03*
Y1409470D03*
Y1429470D03*
Y1449470D03*
Y1469470D03*
Y1489470D03*
Y1509470D03*
Y1529470D03*
Y1549470D03*
Y1569470D03*
Y1589470D03*
X1854096Y52383D03*
X1854470Y112379D03*
Y152379D03*
Y172379D03*
Y192379D03*
Y212379D03*
Y232379D03*
Y252379D03*
Y272379D03*
Y292379D03*
G54D203*
X694225Y144488D03*
Y225984D03*
G54D320*
X1806657Y1502389D03*
G54D330*
G01X726597Y438486D02*
X728172Y436911D01*
G01X1326195Y144232D02*
X1325793Y143830D01*
Y119011D01*
X1325641Y118859D01*
G01D02*
Y116295D01*
X1329646Y112290D01*
Y110544D01*
G01X1332161Y128642D02*
Y127628D01*
X1331593Y127060D01*
Y125262D01*
G01X1345083Y96918D02*
X1342918Y99083D01*
Y111483D01*
X1342727Y111944D01*
Y115578D01*
X1338148Y120157D01*
X1337731Y121164D01*
G01X1331593Y125262D02*
Y122913D01*
X1332373Y122133D01*
Y117583D01*
X1336549Y113407D01*
Y111520D01*
G01X1344259Y125217D02*
X1345514Y123962D01*
Y122161D01*
X1347082Y120593D01*
G01X1336575Y130707D02*
Y122320D01*
X1337731Y121164D01*
G01X1348620Y136162D02*
X1348220Y136562D01*
Y137846D01*
X1347644Y138422D01*
G01X1347082Y120593D02*
X1348357Y119318D01*
Y113068D01*
X1348575Y112541D01*
X1349621Y111495D01*
Y109797D01*
G01X1473090Y204502D02*
X1473880Y203712D01*
Y154822D01*
X1464620Y145562D01*
Y144090D01*
X1399992Y79462D01*
X1374720D01*
X1373071Y81111D01*
X1371827D01*
G01X1366369Y86495D02*
Y83820D01*
G01D02*
X1368677Y81512D01*
Y81111D01*
G54D240*
X926789Y986734D03*
G54D132*
X277098Y185236D03*
X395208D03*
G54D213*
X735882Y1585521D03*
X788079Y1585523D03*
X830079D03*
X872079D03*
X914079D03*
G54D303*
X1643670Y602634D03*
G54D141*
X303147Y572658D03*
Y575158D03*
Y577658D03*
Y580158D03*
Y582658D03*
Y585158D03*
Y587658D03*
Y590158D03*
X324347Y572658D03*
Y575158D03*
Y577658D03*
Y580158D03*
Y582658D03*
Y585158D03*
Y587658D03*
Y590158D03*
G54D150*
X333568Y391643D03*
Y403581D03*
X340654Y391643D03*
Y403581D03*
X366714Y366391D03*
Y378649D03*
Y403581D03*
X373800Y366391D03*
Y378649D03*
Y403581D03*
G54D123*
X229825Y423824D03*
Y426383D03*
Y428942D03*
Y431501D03*
Y434060D03*
Y436619D03*
Y439179D03*
Y441738D03*
Y444297D03*
Y446856D03*
Y449415D03*
Y451974D03*
X251873Y428942D03*
Y426383D03*
Y423824D03*
Y444297D03*
Y441738D03*
Y439179D03*
Y436619D03*
Y434060D03*
Y431501D03*
Y451974D03*
Y449415D03*
Y446856D03*
X464994Y513372D03*
Y515931D03*
Y518490D03*
Y521049D03*
Y523608D03*
Y526167D03*
Y528727D03*
Y531286D03*
Y533845D03*
Y536404D03*
Y538963D03*
Y541522D03*
X487042Y526167D03*
Y523608D03*
Y521049D03*
Y518490D03*
Y515931D03*
Y513372D03*
Y541522D03*
Y538963D03*
Y536404D03*
Y533845D03*
Y531286D03*
Y528727D03*
G54D12*
X14092Y290137D03*
Y298207D03*
X28068Y290137D03*
Y298207D03*
X44692Y290637D03*
Y298707D03*
X58668Y290637D03*
Y298707D03*
X1744422Y151527D03*
Y159597D03*
X1758398Y151527D03*
Y159597D03*
G54D222*
X781189Y1576664D03*
Y1594382D03*
X794969Y1576664D03*
Y1594382D03*
X823189Y1576664D03*
Y1594382D03*
X836969Y1576664D03*
Y1594382D03*
X865189Y1576664D03*
Y1594382D03*
X878969Y1576664D03*
Y1594382D03*
X907189Y1576664D03*
Y1594382D03*
X920969Y1576664D03*
Y1594382D03*
G54D231*
X834903Y529786D03*
G54D114*
X199866Y680633D03*
Y682602D03*
Y684570D03*
Y686539D03*
Y688507D03*
Y690476D03*
Y692444D03*
X432640Y1632513D03*
Y1630545D03*
Y1628576D03*
Y1626608D03*
Y1624639D03*
Y1622671D03*
Y1620702D03*
Y1634482D03*
X451340Y1632513D03*
Y1630545D03*
Y1628576D03*
Y1626608D03*
Y1624639D03*
Y1622671D03*
Y1620702D03*
Y1634482D03*
X919407Y981813D03*
Y983781D03*
Y985750D03*
Y987718D03*
Y989687D03*
Y991655D03*
X934171Y981813D03*
Y991655D03*
Y989687D03*
Y987718D03*
Y985750D03*
Y983781D03*
X1657107Y607949D03*
Y605980D03*
Y604012D03*
Y602043D03*
Y600075D03*
Y598106D03*
Y596138D03*
G54D105*
X174685Y647210D03*
X174393Y678354D03*
X195316Y1430034D03*
X383224Y1354446D03*
X412990D03*
X443326D03*
X458600Y1379662D03*
X472700Y1353962D03*
X526478Y1449795D03*
X708795Y1429579D03*
X1168627Y1466363D03*
X1359365Y1353946D03*
X1389131D03*
X1419467D03*
X1434200Y1379362D03*
X1449233Y1353946D03*
X1502956Y1449373D03*
X1670101Y1463655D03*
X1682882Y628017D03*
Y678952D03*
X1769790Y204632D03*
X1799350D03*
X1826405Y269763D03*
Y299056D03*
G54D21*
G01X94463Y1545675D02*
X94975Y1546187D01*
X96570D01*
G01X84048Y1574536D02*
X88048D01*
G01X84048D02*
Y1578008D01*
G01X92251Y1574536D02*
X96251D01*
G01D02*
Y1577532D01*
G01X122599Y665515D02*
Y661515D01*
G01Y665515D02*
Y669376D01*
X122575Y669400D01*
G01D02*
Y671930D01*
G01X116158Y1535767D02*
Y1541833D01*
X116260Y1541935D01*
G01X116331Y1548027D02*
X116260Y1547956D01*
Y1541935D01*
G01X117707Y1553759D02*
X116331Y1552383D01*
Y1548027D01*
G01X129962Y1535855D02*
X127366D01*
G01X130114Y1541874D02*
X127366D01*
G01X130206Y1547935D02*
X127366D01*
G01X154581Y1523389D02*
Y1520981D01*
G01X158570Y1523430D02*
Y1520981D01*
G01X159107Y1571364D02*
Y1566168D01*
G01X155098Y1566240D02*
X159035D01*
X159107Y1566168D01*
G01X159014Y1576984D02*
Y1577861D01*
X157441Y1579434D01*
Y1581932D01*
G01X154580Y1576984D02*
X159014D01*
G01X183057Y1535462D02*
X185895D01*
G01X183046Y1539723D02*
X185895D01*
G01X182943Y1544028D02*
X182944Y1544029D01*
X185895D01*
G01X183023Y1548486D02*
X183024Y1548487D01*
X185895D01*
G01X183014Y1552874D02*
X183015Y1552875D01*
X185895D01*
G01X195766Y1552940D02*
Y1554194D01*
X192600Y1557360D01*
G01X195966Y1539678D02*
Y1535436D01*
X196025Y1535377D01*
G01X195966Y1542863D02*
Y1539678D01*
G01X195858Y1548430D02*
X195766Y1548522D01*
Y1552940D01*
G01X243892Y140912D02*
X238425D01*
X237275Y142062D01*
G01X295342Y67513D02*
X292942D01*
G01Y71499D02*
X292956Y71513D01*
X295342D01*
G01X313995Y235324D02*
Y237724D01*
G01X317981D02*
X317995Y237710D01*
Y235324D01*
G01X325617Y81168D02*
X323117D01*
G01X325617Y76938D02*
X323117D01*
G01X453165Y1431134D02*
Y1432295D01*
X454450Y1433580D01*
G01X599855Y458688D02*
X597220D01*
G01X727518Y90984D02*
X727532Y90998D01*
X729918D01*
G01X730820Y84062D02*
X729918Y84964D01*
Y86998D01*
G01X760193Y96423D02*
X757693D01*
G01X760193Y100653D02*
X757693D01*
G01X856228Y265057D02*
X853828D01*
G01Y269043D02*
X853842Y269057D01*
X856228D01*
G01X886503Y278712D02*
X884003D01*
G01X886503Y274482D02*
X885183Y275802D01*
X883870D01*
G01X981445Y178658D02*
Y181058D01*
G01X985431D02*
X985445Y181044D01*
Y178658D01*
G01X995000Y150883D02*
Y148724D01*
X994575Y148299D01*
G01X1102460Y1613720D02*
X1103540D01*
X1108140Y1618320D01*
Y1634950D01*
X1111010Y1637820D01*
X1118260D01*
X1121610Y1634470D01*
X1142050D01*
X1144580Y1637000D01*
X1192120D01*
X1193640Y1635480D01*
Y1611780D01*
X1191400Y1609540D01*
X1183054D01*
X1180800Y1607286D01*
Y1598940D01*
X1179200Y1597340D01*
Y1562754D01*
X1173250Y1556804D01*
Y1545651D01*
X1173150Y1545551D01*
G01X1127008Y1524203D02*
Y1537244D01*
G01X1135748Y1528937D02*
Y1524187D01*
G01X1127008Y1550285D02*
Y1537244D01*
G01X1133780Y1545551D02*
Y1550301D01*
G01X1137717Y1555301D02*
Y1545551D01*
G01X1179922Y1524203D02*
Y1537244D01*
G01X1171182Y1528937D02*
Y1524187D01*
G01X1179922Y1550285D02*
Y1537244D01*
G01X1413847Y239528D02*
X1408808Y234489D01*
Y227948D01*
G01X1429345Y1431150D02*
Y1433695D01*
G01X1498984Y280027D02*
X1502354D01*
X1502383Y280056D01*
G01X1498984Y280027D02*
Y282797D01*
G01X1502383Y280056D02*
Y282985D01*
X1504278Y284880D01*
G01X1686154Y431760D02*
Y434160D01*
G01X1685945Y465940D02*
X1682810D01*
G01X1699809Y401485D02*
Y403985D01*
G01X1695579Y401485D02*
Y403985D01*
G01X1690140Y434160D02*
X1690154Y434146D01*
Y431760D01*
G01X1705035Y726552D02*
Y729210D01*
G01X1760463Y68637D02*
X1758063D01*
G01Y72623D02*
X1758077Y72637D01*
X1760463D01*
G01X1790738Y82292D02*
X1788238D01*
G01X1790738Y78062D02*
X1788238D01*
X27699Y770144D03*
Y783530D03*
Y776837D03*
Y800263D03*
Y793570D03*
Y820341D03*
Y813648D03*
Y806955D03*
Y830381D03*
Y850459D03*
Y843766D03*
Y837074D03*
Y867192D03*
Y857152D03*
Y880577D03*
Y873885D03*
Y893963D03*
Y887270D03*
Y917389D03*
Y910696D03*
Y904003D03*
Y930774D03*
Y924081D03*
Y947507D03*
Y940814D03*
Y964239D03*
Y954200D03*
Y977625D03*
Y970932D03*
Y991011D03*
Y984318D03*
Y1031168D03*
Y1024475D03*
Y1017782D03*
Y1044554D03*
Y1037861D03*
Y1057940D03*
Y1051247D03*
Y1078018D03*
Y1071326D03*
Y1064633D03*
Y1094751D03*
Y1088058D03*
Y1108137D03*
Y1101444D03*
Y1124869D03*
Y1114829D03*
Y1144948D03*
Y1138255D03*
Y1131562D03*
Y1161680D03*
Y1151641D03*
Y1175066D03*
Y1168373D03*
Y1188452D03*
Y1181759D03*
Y1205184D03*
Y1198491D03*
Y1225263D03*
Y1218570D03*
Y1211877D03*
Y1241995D03*
Y1235302D03*
Y1248688D03*
Y1258727D03*
Y1255381D03*
Y1265420D03*
Y1262074D03*
X43841Y766798D03*
X36399Y770144D03*
X43841Y780184D03*
Y773491D03*
X36399Y783530D03*
Y776837D03*
X43841Y803609D03*
Y796916D03*
Y790223D03*
X36399Y800263D03*
Y793570D03*
X43841Y816995D03*
Y810302D03*
X36399Y820341D03*
Y813648D03*
Y806955D03*
X43841Y833727D03*
Y827034D03*
X36399Y830381D03*
X43841Y847113D03*
Y840420D03*
X36399Y850459D03*
Y843766D03*
Y837074D03*
X43841Y863845D03*
Y853806D03*
X36399Y867192D03*
Y857152D03*
X43841Y883924D03*
Y877231D03*
Y870538D03*
X36399Y880577D03*
Y873885D03*
X43841Y900656D03*
Y890617D03*
X36399Y893963D03*
Y887270D03*
X43841Y914042D03*
Y907349D03*
X36399Y917389D03*
Y910696D03*
Y904003D03*
X43841Y927428D03*
Y920735D03*
X36399Y930774D03*
Y924081D03*
X43841Y944160D03*
Y937467D03*
X36399Y947507D03*
Y940814D03*
X43841Y960892D03*
Y950853D03*
X36399Y964239D03*
Y954200D03*
Y960892D03*
Y957546D03*
X43841Y980971D03*
Y974278D03*
Y967585D03*
X36399Y977625D03*
Y970932D03*
Y967585D03*
X43841Y987664D03*
X36399Y991011D03*
Y984318D03*
X43841Y994357D03*
Y1027822D03*
Y1017782D03*
X36399Y1031168D03*
Y1024475D03*
Y1017782D03*
X43841Y1047900D03*
Y1041207D03*
Y1034515D03*
X36399Y1044554D03*
Y1037861D03*
X43841Y1061286D03*
Y1054593D03*
X36399Y1057940D03*
Y1051247D03*
Y1054593D03*
X43841Y1074672D03*
Y1067979D03*
X36399Y1078018D03*
Y1071326D03*
Y1064633D03*
X43841Y1091404D03*
Y1084711D03*
X36399Y1094751D03*
Y1088058D03*
X43841Y1111483D03*
Y1104790D03*
Y1098097D03*
X36399Y1108137D03*
Y1101444D03*
X43841Y1128215D03*
Y1121522D03*
X36399Y1124869D03*
Y1114829D03*
X43841Y1141601D03*
Y1134908D03*
X36399Y1144948D03*
Y1138255D03*
Y1131562D03*
X43841Y1158333D03*
Y1148294D03*
X36399Y1161680D03*
Y1151641D03*
X43841Y1171719D03*
Y1165026D03*
X36399Y1175066D03*
Y1168373D03*
X43841Y1185105D03*
Y1178412D03*
X36399Y1188452D03*
Y1181759D03*
X43841Y1208530D03*
Y1201837D03*
Y1195144D03*
X36399Y1205184D03*
Y1198491D03*
X43841Y1221916D03*
Y1215223D03*
X36399Y1225263D03*
Y1218570D03*
Y1211877D03*
X43841Y1238648D03*
Y1231955D03*
X36399Y1241995D03*
Y1235302D03*
X43841Y1245341D03*
X36399Y1248688D03*
X36449Y1257262D03*
X43841Y1255381D03*
Y1258727D03*
Y1252034D03*
X33546Y1273364D03*
X30746D03*
X43841Y1262074D03*
Y1265420D03*
X57399Y770144D03*
X52541Y766798D03*
X57299D03*
X57399Y783530D03*
Y776837D03*
X52541Y780184D03*
Y773491D03*
X57399Y800263D03*
Y793570D03*
X52541Y803609D03*
Y796916D03*
Y790223D03*
X57399Y820341D03*
Y813648D03*
Y806955D03*
X52541Y816995D03*
Y810302D03*
X57399Y830381D03*
X52541Y833727D03*
Y827034D03*
X57399Y850459D03*
Y843766D03*
Y837074D03*
X52541Y847113D03*
Y840420D03*
X57399Y867192D03*
Y857152D03*
X52541Y863845D03*
Y853806D03*
X57399Y880577D03*
Y873885D03*
X52541Y883924D03*
Y877231D03*
Y870538D03*
X57399Y893963D03*
Y887270D03*
X52541Y900656D03*
Y890617D03*
X57399Y917389D03*
Y910696D03*
Y904003D03*
X52541Y914042D03*
Y907349D03*
X57399Y930774D03*
Y924081D03*
X52541Y927428D03*
Y920735D03*
X57399Y947507D03*
Y940814D03*
X52541Y944160D03*
Y937467D03*
X57399Y964239D03*
Y954200D03*
X52541Y960892D03*
Y950853D03*
Y964239D03*
Y957546D03*
Y954200D03*
X57399Y977625D03*
Y970932D03*
X52541Y980971D03*
Y974278D03*
Y967585D03*
X57399Y991011D03*
Y984318D03*
X52541Y987664D03*
X57399Y1031168D03*
Y1024475D03*
Y1017782D03*
X52541Y1027822D03*
Y1017782D03*
Y1021129D03*
Y1024475D03*
X57399Y1044554D03*
Y1037861D03*
X52541Y1047900D03*
Y1041207D03*
Y1034515D03*
X57399Y1057940D03*
Y1051247D03*
X52541Y1061286D03*
Y1054593D03*
Y1051247D03*
X57399Y1078018D03*
Y1071326D03*
Y1064633D03*
X52541Y1074672D03*
Y1067979D03*
X57399Y1094751D03*
Y1088058D03*
X52541Y1091404D03*
Y1084711D03*
X57399Y1108137D03*
Y1101444D03*
X52541Y1111483D03*
Y1104790D03*
Y1098097D03*
X57399Y1124869D03*
Y1114829D03*
X52541Y1128215D03*
Y1121522D03*
X57399Y1144948D03*
Y1138255D03*
Y1131562D03*
X52541Y1141601D03*
Y1134908D03*
X57399Y1161680D03*
Y1151641D03*
X52541Y1158333D03*
Y1148294D03*
X57399Y1175066D03*
Y1168373D03*
X52541Y1171719D03*
Y1165026D03*
X57399Y1188452D03*
Y1181759D03*
X52541Y1185105D03*
Y1178412D03*
X57399Y1205184D03*
Y1198491D03*
X52541Y1208530D03*
Y1201837D03*
Y1195144D03*
X57399Y1225263D03*
Y1218570D03*
Y1211877D03*
X52541Y1221916D03*
Y1215223D03*
X57399Y1241995D03*
Y1235302D03*
X52541Y1238648D03*
Y1231955D03*
Y1248688D03*
X57399D03*
X52541Y1245341D03*
X57399Y1258727D03*
X52820Y1253862D03*
X60446Y1273364D03*
X49546D03*
X46746D03*
X57399Y1265420D03*
Y1262074D03*
X73541Y766798D03*
X66099Y770144D03*
X73541Y780184D03*
Y773491D03*
X66099Y783530D03*
Y776837D03*
Y780184D03*
Y773491D03*
Y786877D03*
X73541Y803609D03*
Y796916D03*
Y790223D03*
X66099Y800263D03*
Y793570D03*
Y803609D03*
Y796916D03*
Y790223D03*
X73541Y816995D03*
Y810302D03*
X66099Y820341D03*
Y813648D03*
Y806955D03*
Y816995D03*
Y810302D03*
X73541Y833727D03*
Y827034D03*
X66099Y830381D03*
Y833727D03*
Y823688D03*
Y827034D03*
X73541Y847113D03*
Y840420D03*
X66099Y850459D03*
Y843766D03*
Y837074D03*
Y847113D03*
Y840420D03*
X73541Y863845D03*
Y853806D03*
X66099Y867192D03*
Y857152D03*
Y853806D03*
Y860499D03*
Y863845D03*
X73541Y883924D03*
Y877231D03*
Y870538D03*
X66099Y880577D03*
Y873885D03*
Y883924D03*
Y877231D03*
Y870538D03*
X73541Y900656D03*
Y890617D03*
X66099Y893963D03*
Y887270D03*
Y890617D03*
Y897310D03*
Y900656D03*
X73541Y914042D03*
Y907349D03*
X66099Y917389D03*
Y910696D03*
Y904003D03*
Y914042D03*
Y907349D03*
X73541Y927428D03*
Y920735D03*
X66099Y930774D03*
Y924081D03*
Y927428D03*
Y920735D03*
Y934121D03*
X73541Y944160D03*
Y937467D03*
X66099Y947507D03*
Y940814D03*
Y944160D03*
Y937467D03*
X73541Y960892D03*
Y950853D03*
X66099Y964239D03*
Y954200D03*
Y960892D03*
Y950853D03*
Y957546D03*
X73541Y980971D03*
Y974278D03*
Y967585D03*
X66099Y977625D03*
Y970932D03*
Y980971D03*
Y974278D03*
Y967585D03*
X73541Y987664D03*
X66099Y991011D03*
Y984318D03*
Y994357D03*
Y987664D03*
X73541Y1027822D03*
Y1017782D03*
X66099Y1031168D03*
Y1024475D03*
Y1017782D03*
Y1027822D03*
Y1021129D03*
X73541Y1047900D03*
Y1041207D03*
Y1034515D03*
X66099Y1044554D03*
Y1037861D03*
Y1047900D03*
Y1041207D03*
Y1034515D03*
X73541Y1061286D03*
Y1054593D03*
X66099Y1057940D03*
Y1051247D03*
Y1061286D03*
Y1054593D03*
X73541Y1074672D03*
Y1067979D03*
X66099Y1078018D03*
Y1071326D03*
Y1064633D03*
Y1074672D03*
Y1067979D03*
X73541Y1091404D03*
Y1084711D03*
X66099Y1094751D03*
Y1088058D03*
Y1091404D03*
Y1081365D03*
Y1084711D03*
X73541Y1111483D03*
Y1104790D03*
Y1098097D03*
X66099Y1108137D03*
Y1101444D03*
Y1098097D03*
Y1111483D03*
Y1104790D03*
X73541Y1128215D03*
Y1121522D03*
X66099Y1124869D03*
Y1114829D03*
Y1128215D03*
Y1118176D03*
Y1121522D03*
X73541Y1141601D03*
Y1134908D03*
X66099Y1144948D03*
Y1138255D03*
Y1131562D03*
Y1141601D03*
Y1134908D03*
X73541Y1158333D03*
Y1148294D03*
X66099Y1161680D03*
Y1151641D03*
Y1148294D03*
Y1154987D03*
Y1158333D03*
X73541Y1171719D03*
Y1165026D03*
X66099Y1175066D03*
Y1168373D03*
Y1171719D03*
Y1165026D03*
X73541Y1185105D03*
Y1178412D03*
X66099Y1188452D03*
Y1181759D03*
Y1185105D03*
Y1178412D03*
Y1191798D03*
X73541Y1208530D03*
Y1201837D03*
Y1195144D03*
X66099Y1205184D03*
Y1198491D03*
Y1208530D03*
Y1201837D03*
Y1195144D03*
X73541Y1221916D03*
Y1215223D03*
X66099Y1225263D03*
Y1218570D03*
Y1211877D03*
Y1221916D03*
Y1215223D03*
X73541Y1238648D03*
Y1231955D03*
X66099Y1241995D03*
Y1235302D03*
Y1238648D03*
Y1228609D03*
Y1231955D03*
X66189Y1257488D03*
X73541Y1245341D03*
X66099Y1248688D03*
Y1245341D03*
X73541Y1255381D03*
Y1258727D03*
Y1252034D03*
X76446Y1273364D03*
X63246D03*
X73541Y1265420D03*
Y1262074D03*
X87099Y770144D03*
X82241Y766798D03*
Y770144D03*
X86999Y766798D03*
X87099Y783530D03*
Y776837D03*
X82241Y780184D03*
Y773491D03*
Y776837D03*
Y786877D03*
Y783530D03*
X87099Y800263D03*
Y793570D03*
X82241Y803609D03*
Y796916D03*
Y790223D03*
Y800263D03*
Y793570D03*
X87099Y820341D03*
Y813648D03*
Y806955D03*
X82241Y816995D03*
Y810302D03*
Y813648D03*
Y806955D03*
Y820341D03*
X87099Y830381D03*
X82241Y833727D03*
Y827034D03*
Y830381D03*
Y823688D03*
X87099Y850459D03*
Y843766D03*
Y837074D03*
X82241Y847113D03*
Y840420D03*
Y850459D03*
Y843766D03*
Y837074D03*
X87099Y867192D03*
Y857152D03*
X82241Y863845D03*
Y853806D03*
Y867192D03*
Y860499D03*
Y857152D03*
X87099Y880577D03*
Y873885D03*
X82241Y883924D03*
Y877231D03*
Y870538D03*
Y873885D03*
Y880577D03*
X87099Y893963D03*
Y887270D03*
X82241Y900656D03*
Y890617D03*
Y887270D03*
Y897310D03*
Y893963D03*
X87099Y917389D03*
Y910696D03*
Y904003D03*
X82241Y914042D03*
Y907349D03*
Y917389D03*
Y910696D03*
Y904003D03*
X87099Y930774D03*
Y924081D03*
X82241Y927428D03*
Y920735D03*
Y924081D03*
Y934121D03*
Y930774D03*
X87099Y947507D03*
Y940814D03*
X82241Y944160D03*
Y937467D03*
Y947507D03*
Y940814D03*
X87099Y964239D03*
Y954200D03*
X82241Y960892D03*
Y950853D03*
Y964239D03*
Y957546D03*
Y954200D03*
X87099Y977625D03*
Y970932D03*
X82241Y980971D03*
Y974278D03*
Y967585D03*
Y977625D03*
Y970932D03*
X87099Y991011D03*
Y984318D03*
X82241Y987664D03*
Y991011D03*
Y984318D03*
Y994357D03*
X87099Y1031168D03*
Y1024475D03*
Y1017782D03*
X82241Y1027822D03*
Y1017782D03*
Y1021129D03*
Y1024475D03*
Y1031168D03*
X87099Y1044554D03*
Y1037861D03*
X82241Y1047900D03*
Y1041207D03*
Y1034515D03*
Y1044554D03*
Y1037861D03*
X87099Y1057940D03*
Y1051247D03*
X82241Y1061286D03*
Y1054593D03*
Y1051247D03*
X87099Y1078018D03*
Y1071326D03*
Y1064633D03*
X82241Y1074672D03*
Y1067979D03*
Y1071326D03*
Y1064633D03*
Y1078018D03*
X87099Y1094751D03*
Y1088058D03*
X82241Y1091404D03*
Y1084711D03*
Y1094751D03*
Y1088058D03*
Y1081365D03*
X87099Y1108137D03*
Y1101444D03*
X82241Y1111483D03*
Y1104790D03*
Y1098097D03*
Y1108137D03*
Y1101444D03*
X87099Y1124869D03*
Y1114829D03*
X82241Y1128215D03*
Y1121522D03*
Y1124869D03*
Y1118176D03*
Y1114829D03*
X87099Y1144948D03*
Y1138255D03*
Y1131562D03*
X82241Y1141601D03*
Y1134908D03*
Y1144948D03*
Y1138255D03*
Y1131562D03*
X87099Y1161680D03*
Y1151641D03*
X82241Y1158333D03*
Y1148294D03*
Y1161680D03*
Y1154987D03*
Y1151641D03*
X87099Y1175066D03*
Y1168373D03*
X82241Y1171719D03*
Y1165026D03*
Y1175066D03*
Y1168373D03*
X87099Y1188452D03*
Y1181759D03*
X82241Y1185105D03*
Y1178412D03*
Y1181759D03*
Y1191798D03*
Y1188452D03*
X87099Y1205184D03*
Y1198491D03*
X82241Y1208530D03*
Y1201837D03*
Y1195144D03*
Y1205184D03*
Y1198491D03*
X87099Y1225263D03*
Y1218570D03*
Y1211877D03*
X82241Y1221916D03*
Y1215223D03*
Y1218570D03*
Y1211877D03*
Y1225263D03*
X87099Y1241995D03*
Y1235302D03*
X82241Y1238648D03*
Y1231955D03*
Y1241995D03*
Y1235302D03*
Y1228609D03*
X87099Y1248688D03*
X82241Y1245341D03*
X87099Y1258727D03*
X82241Y1248688D03*
X84334Y1254263D03*
X92946Y1273364D03*
X90146D03*
X79246D03*
X87099Y1265420D03*
Y1262074D03*
X103241Y766798D03*
X95799Y770144D03*
X103241Y780184D03*
Y773491D03*
X95799Y783530D03*
Y776837D03*
X103241Y803609D03*
Y796916D03*
Y790223D03*
X95799Y800263D03*
Y793570D03*
X103241Y816995D03*
Y810302D03*
X95799Y820341D03*
Y813648D03*
Y806955D03*
X103241Y833727D03*
Y827034D03*
X95799Y830381D03*
X103241Y847113D03*
Y840420D03*
X95799Y850459D03*
Y843766D03*
Y837074D03*
X103241Y863845D03*
Y853806D03*
X95799Y867192D03*
Y857152D03*
X103241Y883924D03*
Y877231D03*
Y870538D03*
X95799Y880577D03*
Y873885D03*
X103241Y900656D03*
Y890617D03*
X95799Y893963D03*
Y887270D03*
X103241Y914042D03*
Y907349D03*
X95799Y917389D03*
Y910696D03*
Y904003D03*
X103241Y927428D03*
Y920735D03*
X95799Y930774D03*
Y924081D03*
X103241Y944160D03*
Y937467D03*
X95799Y947507D03*
Y940814D03*
X103241Y960892D03*
Y950853D03*
X95799Y964239D03*
Y954200D03*
Y960892D03*
Y957546D03*
X103241Y980971D03*
Y974278D03*
Y967585D03*
X95799Y977625D03*
Y970932D03*
Y967585D03*
X103241Y987664D03*
X95799Y991011D03*
Y984318D03*
X103241Y994357D03*
Y1027822D03*
Y1017782D03*
X95799Y1031168D03*
Y1024475D03*
Y1017782D03*
X103241Y1047900D03*
Y1041207D03*
Y1034515D03*
X95799Y1044554D03*
Y1037861D03*
X103241Y1061286D03*
Y1054593D03*
X95799Y1057940D03*
Y1051247D03*
Y1054593D03*
X103241Y1074672D03*
Y1067979D03*
X95799Y1078018D03*
Y1071326D03*
Y1064633D03*
X103241Y1091404D03*
Y1084711D03*
X95799Y1094751D03*
Y1088058D03*
X103241Y1111483D03*
Y1104790D03*
Y1098097D03*
X95799Y1108137D03*
Y1101444D03*
X103241Y1128215D03*
Y1121522D03*
X95799Y1124869D03*
Y1114829D03*
X103241Y1141601D03*
Y1134908D03*
X95799Y1144948D03*
Y1138255D03*
Y1131562D03*
X103241Y1158333D03*
Y1148294D03*
X95799Y1161680D03*
Y1151641D03*
X103241Y1171719D03*
Y1165026D03*
X95799Y1175066D03*
Y1168373D03*
X103241Y1185105D03*
Y1178412D03*
X95799Y1188452D03*
Y1181759D03*
X103241Y1208530D03*
Y1201837D03*
Y1195144D03*
X95799Y1205184D03*
Y1198491D03*
X103241Y1221916D03*
Y1215223D03*
X95799Y1225263D03*
Y1218570D03*
Y1211877D03*
X103241Y1238648D03*
Y1231955D03*
X95799Y1241995D03*
Y1235302D03*
X95849Y1257262D03*
X103241Y1245341D03*
X95799Y1248688D03*
X103241Y1255381D03*
Y1258727D03*
Y1252034D03*
X108946Y1273364D03*
X106146D03*
X103241Y1265420D03*
Y1262074D03*
X125499Y770144D03*
X116799D03*
X111941Y766798D03*
X116567Y766775D03*
X125499Y783530D03*
X116799D03*
X125499Y776837D03*
X116799D03*
X111941Y780184D03*
Y773491D03*
X125499Y780184D03*
Y773491D03*
Y786877D03*
Y800263D03*
X116799D03*
X125499Y793570D03*
X116799D03*
X111941Y803609D03*
Y796916D03*
Y790223D03*
X125499Y803609D03*
Y796916D03*
Y790223D03*
Y820341D03*
X116799D03*
X125499Y813648D03*
X116799D03*
X125499Y806955D03*
X116799D03*
X111941Y816995D03*
Y810302D03*
X125499Y816995D03*
Y810302D03*
Y830381D03*
X116799D03*
X111941Y833727D03*
Y827034D03*
X125499Y833727D03*
Y823688D03*
Y827034D03*
Y850459D03*
X116799D03*
X125499Y843766D03*
X116799D03*
X125499Y837074D03*
X116799D03*
X111941Y847113D03*
Y840420D03*
X125499Y847113D03*
Y840420D03*
Y867192D03*
X116799D03*
X125499Y857152D03*
X116799D03*
X111941Y863845D03*
Y853806D03*
X125499D03*
Y860499D03*
Y863845D03*
Y880577D03*
X116799D03*
X125499Y873885D03*
X116799D03*
X111941Y883924D03*
Y877231D03*
Y870538D03*
X125499Y883924D03*
Y877231D03*
Y870538D03*
Y893963D03*
X116799D03*
X125499Y887270D03*
X116799D03*
X111941Y900656D03*
Y890617D03*
X125499D03*
Y897310D03*
Y900656D03*
Y917389D03*
X116799D03*
X125499Y910696D03*
X116799D03*
X125499Y904003D03*
X116799D03*
X111941Y914042D03*
Y907349D03*
X125499Y914042D03*
Y907349D03*
Y930774D03*
X116799D03*
X125499Y924081D03*
X116799D03*
X111941Y927428D03*
Y920735D03*
X125499Y927428D03*
Y920735D03*
Y934121D03*
Y947507D03*
X116799D03*
X125499Y940814D03*
X116799D03*
X111941Y944160D03*
Y937467D03*
X125499Y944160D03*
Y937467D03*
Y964239D03*
X116799D03*
X125499Y954200D03*
X116799D03*
X111941Y960892D03*
Y950853D03*
X125499Y960892D03*
Y950853D03*
X111941Y964239D03*
X125499Y957546D03*
X111941D03*
Y954200D03*
X125499Y977625D03*
X116799D03*
X125499Y970932D03*
X116799D03*
X111941Y980971D03*
Y974278D03*
Y967585D03*
X125499Y980971D03*
Y974278D03*
Y967585D03*
Y991011D03*
X116799D03*
X125499Y984318D03*
X116799D03*
X111941Y987664D03*
X125499Y994357D03*
Y987664D03*
Y1031168D03*
X116799D03*
X125499Y1024475D03*
X116799D03*
X125499Y1017782D03*
X116799D03*
X111941Y1027822D03*
Y1017782D03*
Y1021129D03*
Y1024475D03*
X125499Y1027822D03*
Y1021129D03*
Y1044554D03*
X116799D03*
X125499Y1037861D03*
X116799D03*
X111941Y1047900D03*
Y1041207D03*
Y1034515D03*
X125499Y1047900D03*
Y1041207D03*
Y1034515D03*
Y1057940D03*
X116799D03*
X125499Y1051247D03*
X116799D03*
X111941Y1061286D03*
Y1054593D03*
X125499Y1061286D03*
X111941Y1051247D03*
X125499Y1054593D03*
Y1078018D03*
X116799D03*
X125499Y1071326D03*
X116799D03*
X125499Y1064633D03*
X116799D03*
X111941Y1074672D03*
Y1067979D03*
X125499Y1074672D03*
Y1067979D03*
Y1094751D03*
X116799D03*
X125499Y1088058D03*
X116799D03*
X111941Y1091404D03*
Y1084711D03*
X125499Y1091404D03*
Y1081365D03*
Y1084711D03*
Y1108137D03*
X116799D03*
X125499Y1101444D03*
X116799D03*
X111941Y1111483D03*
Y1104790D03*
Y1098097D03*
X125499D03*
Y1111483D03*
Y1104790D03*
Y1124869D03*
X116799D03*
X125499Y1114829D03*
X116799D03*
X111941Y1128215D03*
Y1121522D03*
X125499Y1128215D03*
Y1118176D03*
Y1121522D03*
Y1144948D03*
X116799D03*
X125499Y1138255D03*
X116799D03*
X125499Y1131562D03*
X116799D03*
X111941Y1141601D03*
Y1134908D03*
X125499Y1141601D03*
Y1134908D03*
Y1161680D03*
X116799D03*
X125499Y1151641D03*
X116799D03*
X111941Y1158333D03*
Y1148294D03*
X125499D03*
Y1154987D03*
Y1158333D03*
Y1175066D03*
X116799D03*
X125499Y1168373D03*
X116799D03*
X111941Y1171719D03*
Y1165026D03*
X125499Y1171719D03*
Y1165026D03*
Y1188452D03*
X116799D03*
X125499Y1181759D03*
X116799D03*
X111941Y1185105D03*
Y1178412D03*
X125499Y1185105D03*
Y1178412D03*
Y1191798D03*
Y1205184D03*
X116799D03*
X125499Y1198491D03*
X116799D03*
X111941Y1208530D03*
Y1201837D03*
Y1195144D03*
X125499Y1208530D03*
Y1201837D03*
Y1195144D03*
Y1225263D03*
X116799D03*
X125499Y1218570D03*
X116799D03*
X125499Y1211877D03*
X116799D03*
X111941Y1221916D03*
Y1215223D03*
X125499Y1221916D03*
Y1215223D03*
Y1241995D03*
X116799D03*
X125499Y1235302D03*
X116799D03*
X111941Y1238648D03*
Y1231955D03*
X125499Y1238648D03*
Y1228609D03*
Y1231955D03*
X125412Y1257102D03*
X125499Y1248688D03*
X116799D03*
X111941Y1245341D03*
X125499D03*
X116799Y1258727D03*
X111941Y1248688D03*
X114191Y1254604D03*
X119846Y1273364D03*
X122646D03*
X116799Y1265420D03*
Y1262074D03*
X141641Y766798D03*
X132941D03*
X141641Y770144D03*
Y773491D03*
X132941D03*
X141641Y780184D03*
X132941D03*
X141641Y776837D03*
Y786877D03*
Y783530D03*
Y803609D03*
X132941D03*
X141641Y790223D03*
X132941D03*
X141641Y796916D03*
X132941D03*
X141641Y800263D03*
Y793570D03*
Y816995D03*
X132941D03*
X141641Y810302D03*
X132941D03*
X141641Y813648D03*
Y806955D03*
Y820341D03*
Y833727D03*
X132941D03*
X141641Y827034D03*
X132941D03*
X141641Y830381D03*
Y823688D03*
Y840420D03*
X132941D03*
X141641Y847113D03*
X132941D03*
X141641Y850459D03*
Y843766D03*
Y837074D03*
X132941Y863845D03*
X141641D03*
Y853806D03*
X132941D03*
X141641Y867192D03*
Y860499D03*
Y857152D03*
X132941Y883924D03*
X141641D03*
X132941Y870538D03*
X141641D03*
X132941Y877231D03*
X141641D03*
Y873885D03*
Y880577D03*
X132941Y900656D03*
X141641D03*
X132941Y890617D03*
X141641D03*
Y887270D03*
Y897310D03*
Y893963D03*
X132941Y907349D03*
X141641D03*
X132941Y914042D03*
X141641D03*
Y917389D03*
Y910696D03*
Y904003D03*
X132941Y920735D03*
X141641D03*
X132941Y927428D03*
X141641D03*
Y924081D03*
Y934121D03*
Y930774D03*
X132941Y937467D03*
X141641D03*
X132941Y944160D03*
X141641D03*
Y947507D03*
Y940814D03*
X132941Y960892D03*
X141641D03*
X132941Y950853D03*
X141641D03*
Y964239D03*
Y957546D03*
Y954200D03*
X132941Y980971D03*
X141641D03*
X132941Y974278D03*
X141641D03*
X132941Y967585D03*
X141641D03*
Y977625D03*
Y970932D03*
X132941Y987664D03*
X141641D03*
Y991011D03*
Y984318D03*
Y994357D03*
X132941Y1027822D03*
X141641D03*
X132941Y1017782D03*
X141641D03*
Y1021129D03*
Y1024475D03*
Y1031168D03*
X132941Y1047900D03*
X141641D03*
X132941Y1041207D03*
X141641D03*
X132941Y1034515D03*
X141641D03*
Y1044554D03*
Y1037861D03*
Y1061286D03*
X132941D03*
X141641Y1054593D03*
X132941D03*
X141641Y1051247D03*
Y1057940D03*
Y1074672D03*
X132941D03*
X141641Y1067979D03*
X132941D03*
X141641Y1071326D03*
Y1064633D03*
Y1078018D03*
Y1091404D03*
X132941D03*
X141641Y1084711D03*
X132941D03*
X141641Y1094751D03*
Y1088058D03*
Y1081365D03*
Y1111483D03*
X132941D03*
X141641Y1104790D03*
X132941D03*
X141641Y1098097D03*
X132941D03*
X141641Y1108137D03*
Y1101444D03*
Y1128215D03*
X132941D03*
X141641Y1121522D03*
X132941D03*
X141641Y1124869D03*
Y1118176D03*
Y1114829D03*
Y1141601D03*
X132941D03*
X141641Y1134908D03*
X132941D03*
X141641Y1144948D03*
Y1138255D03*
Y1131562D03*
Y1158333D03*
X132941D03*
X141641Y1148294D03*
X132941D03*
X141641Y1161680D03*
Y1154987D03*
Y1151641D03*
Y1171719D03*
X132941D03*
X141641Y1165026D03*
X132941D03*
X141641Y1175066D03*
Y1168373D03*
Y1185105D03*
X132941D03*
X141641Y1178412D03*
X132941D03*
X141641Y1181759D03*
Y1191798D03*
Y1188452D03*
Y1208530D03*
X132941D03*
X141641Y1201837D03*
X132941D03*
X141641Y1195144D03*
X132941D03*
X141641Y1205184D03*
Y1198491D03*
X132941Y1221916D03*
X141641D03*
X132941Y1215223D03*
X141641D03*
Y1218570D03*
Y1211877D03*
Y1225263D03*
X132941Y1238648D03*
X141641D03*
X132941Y1231955D03*
X141641D03*
X129933Y1238461D03*
X141641Y1241995D03*
Y1235302D03*
Y1228609D03*
X132941Y1245341D03*
X141641D03*
X132941Y1255381D03*
Y1258727D03*
Y1252034D03*
X141641Y1248688D03*
X143675Y1255567D03*
X135846Y1273364D03*
X138646D03*
X132941Y1265420D03*
Y1262074D03*
X146499Y770144D03*
X155199D03*
X146367Y766775D03*
X146499Y783530D03*
X155199D03*
X146499Y776837D03*
X155199D03*
X146499Y800263D03*
X155199D03*
X146499Y793570D03*
X155199D03*
X146499Y820341D03*
X155199D03*
X146499Y813648D03*
X155199D03*
X146499Y806955D03*
X155199D03*
X146499Y830381D03*
X155199D03*
X146499Y850459D03*
X155199D03*
X146499Y843766D03*
X155199D03*
X146499Y837074D03*
X155199D03*
Y867192D03*
X146499D03*
Y857152D03*
X155199D03*
Y880577D03*
X146499D03*
X155199Y873885D03*
X146499D03*
X155199Y893963D03*
X146499D03*
X155199Y887270D03*
X146499D03*
X155199Y917389D03*
X146499D03*
X155199Y910696D03*
X146499D03*
X155199Y904003D03*
X146499D03*
X155199Y930774D03*
X146499D03*
X155199Y924081D03*
X146499D03*
X155199Y947507D03*
X146499D03*
X155199Y940814D03*
X146499D03*
X155199Y964239D03*
X146499D03*
X155199Y954200D03*
X146499D03*
X155199Y960892D03*
Y957546D03*
Y977625D03*
X146499D03*
X155199Y970932D03*
X146499D03*
X155199Y967585D03*
Y991011D03*
X146499D03*
X155199Y984318D03*
X146499D03*
X155199Y1031168D03*
X146499D03*
X155199Y1024475D03*
X146499D03*
X155199Y1017782D03*
X146499D03*
X155199Y1044554D03*
X146499D03*
X155199Y1037861D03*
X146499D03*
X155199Y1057940D03*
X146499D03*
X155199Y1051247D03*
X146499D03*
X155199Y1054593D03*
Y1078018D03*
X146499D03*
X155199Y1071326D03*
X146499D03*
X155199Y1064633D03*
X146499D03*
X155199Y1094751D03*
X146499D03*
X155199Y1088058D03*
X146499D03*
X155199Y1108137D03*
X146499D03*
X155199Y1101444D03*
X146499D03*
X155199Y1124869D03*
X146499D03*
X155199Y1114829D03*
X146499D03*
X155199Y1144948D03*
X146499D03*
X155199Y1138255D03*
X146499D03*
X155199Y1131562D03*
X146499D03*
X155199Y1161680D03*
X146499D03*
X155199Y1151641D03*
X146499D03*
X155199Y1175066D03*
X146499D03*
X155199Y1168373D03*
X146499D03*
X155199Y1188452D03*
X146499D03*
X155199Y1181759D03*
X146499D03*
X155199Y1205184D03*
X146499D03*
X155199Y1198491D03*
X146499D03*
X155199Y1225263D03*
X146499D03*
X155199Y1218570D03*
X146499D03*
X155199Y1211877D03*
X146499D03*
X155199Y1241995D03*
X146499D03*
X155199Y1235302D03*
X146499D03*
X155135Y1257134D03*
X155199Y1248688D03*
X146499D03*
X160130Y1251847D03*
X146499Y1258727D03*
X149546Y1273364D03*
X152346D03*
X146499Y1265420D03*
Y1262074D03*
X176199Y770144D03*
X162641Y766798D03*
X171341D03*
X176099D03*
X176199Y783530D03*
Y776837D03*
X162641Y780184D03*
X171341D03*
Y773491D03*
X162641D03*
X176199Y800263D03*
X162641Y803609D03*
X171341D03*
X176199Y793570D03*
X162641Y796916D03*
X171341D03*
X162641Y790223D03*
X171341D03*
X176199Y820341D03*
X162641Y816995D03*
X171341D03*
X176199Y813648D03*
Y806955D03*
X162641Y810302D03*
X171341D03*
X162641Y833727D03*
X171341D03*
X176199Y830381D03*
X162641Y827034D03*
X171341D03*
X176199Y850459D03*
Y843766D03*
Y837074D03*
X162641Y847113D03*
X171341D03*
X162641Y840420D03*
X171341D03*
X176199Y867192D03*
X171341Y863845D03*
X162641D03*
X176199Y857152D03*
X162641Y853806D03*
X171341D03*
Y883924D03*
X162641D03*
X176199Y880577D03*
Y873885D03*
X171341Y877231D03*
X162641D03*
X171341Y870538D03*
X162641D03*
X171341Y900656D03*
X162641D03*
X176199Y893963D03*
Y887270D03*
X171341Y890617D03*
X162641D03*
X176199Y917389D03*
Y910696D03*
Y904003D03*
X171341Y914042D03*
X162641D03*
X171341Y907349D03*
X162641D03*
X176199Y930774D03*
Y924081D03*
X171341Y927428D03*
X162641D03*
X171341Y920735D03*
X162641D03*
X176199Y947507D03*
Y940814D03*
X171341Y944160D03*
X162641D03*
X171341Y937467D03*
X162641D03*
X176199Y964239D03*
Y954200D03*
X171341Y960892D03*
X162641D03*
X171341Y950853D03*
X162641D03*
X171341Y964239D03*
Y957546D03*
Y954200D03*
Y980971D03*
X162641D03*
X176199Y977625D03*
Y970932D03*
X171341Y974278D03*
X162641D03*
X171341Y967585D03*
X162641D03*
X176199Y991011D03*
Y984318D03*
X171341Y987664D03*
X162641D03*
Y994357D03*
X176199Y1031168D03*
Y1024475D03*
Y1017782D03*
X171341Y1027822D03*
X162641D03*
X171341Y1017782D03*
X162641D03*
X171341Y1021129D03*
Y1024475D03*
Y1047900D03*
X162641D03*
X176199Y1044554D03*
Y1037861D03*
X171341Y1041207D03*
X162641D03*
X171341Y1034515D03*
X162641D03*
X176199Y1057940D03*
Y1051247D03*
X171341Y1061286D03*
X162641D03*
X171341Y1054593D03*
X162641D03*
X171341Y1051247D03*
X176199Y1078018D03*
Y1071326D03*
Y1064633D03*
X171341Y1074672D03*
X162641D03*
X171341Y1067979D03*
X162641D03*
X176199Y1094751D03*
Y1088058D03*
X171341Y1091404D03*
X162641D03*
X171341Y1084711D03*
X162641D03*
X171341Y1111483D03*
X162641D03*
X176199Y1108137D03*
Y1101444D03*
X171341Y1104790D03*
X162641D03*
X171341Y1098097D03*
X162641D03*
X171341Y1128215D03*
X162641D03*
X176199Y1124869D03*
Y1114829D03*
X171341Y1121522D03*
X162641D03*
X176199Y1144948D03*
Y1138255D03*
Y1131562D03*
X171341Y1141601D03*
X162641D03*
X171341Y1134908D03*
X162641D03*
X176199Y1161680D03*
Y1151641D03*
X171341Y1158333D03*
X162641D03*
X171341Y1148294D03*
X162641D03*
X176199Y1175066D03*
Y1168373D03*
X171341Y1171719D03*
X162641D03*
X171341Y1165026D03*
X162641D03*
X176199Y1188452D03*
Y1181759D03*
X171341Y1185105D03*
X162641D03*
X171341Y1178412D03*
X162641D03*
X176199Y1205184D03*
Y1198491D03*
X171341Y1208530D03*
X162641D03*
X171341Y1201837D03*
X162641D03*
X171341Y1195144D03*
X162641D03*
X176199Y1225263D03*
Y1218570D03*
Y1211877D03*
X162641Y1221916D03*
X171341D03*
Y1215223D03*
X162641D03*
X176199Y1241995D03*
Y1235302D03*
X171341Y1238648D03*
X162641D03*
X171341Y1231955D03*
X162641D03*
X176199Y1248688D03*
X171341Y1245341D03*
X162641D03*
X176199Y1258727D03*
X162641Y1255381D03*
Y1258727D03*
Y1252034D03*
X171341Y1248688D03*
X171947Y1255837D03*
X165546Y1273364D03*
X168346D03*
X176199Y1265420D03*
X162641D03*
Y1262074D03*
X176199D03*
X192341Y766798D03*
X184899Y770144D03*
X192341Y780184D03*
Y773491D03*
X184899Y783530D03*
Y776837D03*
Y780184D03*
Y773491D03*
Y786877D03*
X192341Y803609D03*
Y796916D03*
Y790223D03*
X184899Y800263D03*
Y793570D03*
Y803609D03*
Y796916D03*
Y790223D03*
X192341Y816995D03*
Y810302D03*
X184899Y820341D03*
Y813648D03*
Y806955D03*
Y816995D03*
Y810302D03*
X192341Y833727D03*
X191491Y827034D03*
X184899Y830381D03*
Y833727D03*
Y823688D03*
Y827034D03*
X192341Y847113D03*
Y840420D03*
X184899Y850459D03*
Y843766D03*
Y837074D03*
Y847113D03*
Y840420D03*
X191491Y863845D03*
X184899Y867192D03*
X192341Y853806D03*
X184899Y857152D03*
Y853806D03*
Y860499D03*
Y863845D03*
X192341Y883924D03*
Y877231D03*
Y870538D03*
X184899Y880577D03*
Y873885D03*
Y883924D03*
Y877231D03*
Y870538D03*
X192341Y900656D03*
Y890617D03*
X184899Y893963D03*
Y887270D03*
Y890617D03*
Y897310D03*
Y900656D03*
X192341Y914042D03*
Y907349D03*
X184899Y917389D03*
Y910696D03*
Y904003D03*
Y914042D03*
Y907349D03*
X191491Y927428D03*
X192341Y920735D03*
X184899Y930774D03*
Y924081D03*
Y927428D03*
Y920735D03*
Y934121D03*
X192341Y937467D03*
Y944160D03*
X184899Y947507D03*
Y940814D03*
Y944160D03*
Y937467D03*
X192341Y960892D03*
Y950853D03*
X184899Y964239D03*
Y954200D03*
Y960892D03*
Y950853D03*
Y957546D03*
X192341Y974278D03*
Y980971D03*
Y967585D03*
X184899Y977625D03*
Y970932D03*
Y980971D03*
Y974278D03*
Y967585D03*
X192341Y987664D03*
X184899Y991011D03*
Y984318D03*
Y994357D03*
Y987664D03*
X192341Y1027822D03*
Y1017782D03*
X184899Y1031168D03*
Y1024475D03*
Y1017782D03*
Y1027822D03*
Y1021129D03*
X192341Y1047900D03*
Y1041207D03*
Y1034515D03*
X184899Y1044554D03*
Y1037861D03*
Y1047900D03*
Y1041207D03*
Y1034515D03*
X192341Y1054593D03*
Y1061286D03*
X184899Y1057940D03*
Y1051247D03*
Y1061286D03*
Y1054593D03*
X192341Y1074672D03*
Y1067979D03*
X184899Y1078018D03*
Y1071326D03*
Y1064633D03*
Y1074672D03*
Y1067979D03*
X192341Y1091404D03*
X191491Y1084711D03*
X184899Y1094751D03*
Y1088058D03*
Y1091404D03*
Y1081365D03*
Y1084711D03*
X192341Y1111483D03*
Y1104790D03*
Y1098097D03*
X184899Y1108137D03*
Y1101444D03*
Y1098097D03*
Y1111483D03*
Y1104790D03*
X192341Y1128215D03*
Y1121522D03*
X184899Y1124869D03*
Y1114829D03*
Y1128215D03*
Y1118176D03*
Y1121522D03*
X192341Y1141601D03*
Y1134908D03*
X184899Y1144948D03*
Y1138255D03*
Y1131562D03*
Y1141601D03*
Y1134908D03*
X191491Y1158333D03*
X192341Y1148294D03*
X184899Y1161680D03*
Y1151641D03*
Y1148294D03*
Y1154987D03*
Y1158333D03*
X192341Y1171719D03*
Y1165026D03*
X184899Y1175066D03*
Y1168373D03*
Y1171719D03*
Y1165026D03*
X192341Y1185105D03*
Y1178412D03*
X184899Y1188452D03*
Y1181759D03*
Y1185105D03*
Y1178412D03*
Y1191798D03*
X192341Y1208530D03*
Y1201837D03*
Y1195144D03*
X184899Y1205184D03*
Y1198491D03*
Y1208530D03*
Y1201837D03*
Y1195144D03*
X192341Y1221916D03*
Y1215223D03*
X184899Y1225263D03*
Y1218570D03*
Y1211877D03*
Y1221916D03*
Y1215223D03*
X192341Y1238648D03*
X191491Y1231955D03*
X184899Y1241995D03*
Y1235302D03*
Y1238648D03*
Y1228609D03*
Y1231955D03*
X184923Y1258871D03*
X192341Y1245341D03*
X184899Y1248688D03*
Y1245341D03*
X192341Y1255381D03*
Y1258727D03*
Y1252034D03*
X192594Y1271262D03*
X192605Y1268774D03*
X182046Y1273364D03*
X179246D03*
X192341Y1265420D03*
Y1262074D03*
X188119Y1580678D03*
Y1575686D03*
X188897Y1578182D03*
X192297D03*
X188119Y1592590D03*
Y1587598D03*
X188897Y1590094D03*
X192297D03*
X205899Y770144D03*
X201041Y766798D03*
Y770144D03*
X205799Y766798D03*
X205899Y783530D03*
Y776837D03*
X201041Y780184D03*
Y773491D03*
Y776837D03*
Y786877D03*
Y783530D03*
X205899Y800263D03*
Y793570D03*
X201041Y803609D03*
Y796916D03*
Y790223D03*
Y800263D03*
Y793570D03*
X205899Y813648D03*
Y806955D03*
X205049Y820341D03*
X201041Y816995D03*
Y810302D03*
Y813648D03*
Y806955D03*
Y820341D03*
X205049Y830381D03*
X201041Y833727D03*
Y827034D03*
Y830381D03*
Y823688D03*
X205899Y850459D03*
Y837074D03*
Y843766D03*
X201041Y847113D03*
Y840420D03*
Y850459D03*
Y843766D03*
Y837074D03*
X205049Y867192D03*
X201041Y863845D03*
X205049Y857152D03*
X201041Y853806D03*
Y867192D03*
Y860499D03*
Y857152D03*
X205899Y873885D03*
Y880577D03*
X201041Y883924D03*
Y877231D03*
Y870538D03*
Y873885D03*
Y880577D03*
X205899Y893963D03*
Y887270D03*
X201041Y900656D03*
Y890617D03*
Y887270D03*
Y897310D03*
Y893963D03*
X205899Y917389D03*
Y910696D03*
Y904003D03*
X201041Y914042D03*
Y907349D03*
Y917389D03*
Y910696D03*
Y904003D03*
X205049Y930774D03*
Y924081D03*
X201041Y927428D03*
Y920735D03*
Y924081D03*
Y934121D03*
Y930774D03*
X205899Y940814D03*
Y947507D03*
X201041Y937467D03*
Y944160D03*
Y947507D03*
Y940814D03*
X205899Y964239D03*
Y954200D03*
X201041Y960892D03*
Y950853D03*
Y964239D03*
Y957546D03*
Y954200D03*
X205899Y970932D03*
Y977625D03*
X201041Y974278D03*
Y980971D03*
Y967585D03*
Y977625D03*
Y970932D03*
X205899Y991011D03*
Y984318D03*
X201041Y987664D03*
Y991011D03*
Y984318D03*
Y994357D03*
X205899Y1031168D03*
Y1017782D03*
Y1024475D03*
X201041Y1027822D03*
Y1017782D03*
X201141Y1021129D03*
Y1024475D03*
Y1031168D03*
X205899Y1044554D03*
Y1037861D03*
X201041Y1047900D03*
Y1041207D03*
Y1034515D03*
X201141Y1044554D03*
Y1037861D03*
X205899Y1057940D03*
Y1051247D03*
X201041Y1054593D03*
Y1061286D03*
X201141Y1051247D03*
X205049Y1078018D03*
X205899Y1071326D03*
Y1064633D03*
X201041Y1074672D03*
Y1067979D03*
X201141Y1071326D03*
Y1064633D03*
Y1078018D03*
X205899Y1094751D03*
X205049Y1088058D03*
X201041Y1091404D03*
Y1084711D03*
X201141Y1094752D03*
Y1088059D03*
Y1081366D03*
X205899Y1101444D03*
Y1108137D03*
X201041Y1111483D03*
Y1104790D03*
Y1098097D03*
X201141Y1108137D03*
Y1101444D03*
X205899Y1114829D03*
Y1124869D03*
X201041Y1128215D03*
Y1121522D03*
Y1124869D03*
X201141Y1118177D03*
Y1114830D03*
X205899Y1144948D03*
Y1138255D03*
Y1131562D03*
X201041Y1141601D03*
Y1134908D03*
X201141Y1144948D03*
Y1138255D03*
X201041Y1131562D03*
X205049Y1161680D03*
Y1151641D03*
X201041Y1158333D03*
Y1148294D03*
X201141Y1161680D03*
Y1154988D03*
Y1151641D03*
X205899Y1168373D03*
Y1175066D03*
X201041Y1171719D03*
Y1165026D03*
X201141Y1175066D03*
Y1168373D03*
X205899Y1188452D03*
Y1181759D03*
X201041Y1185105D03*
Y1178412D03*
X201141Y1181759D03*
Y1191799D03*
Y1188452D03*
X205899Y1205184D03*
Y1198491D03*
X201041Y1208530D03*
Y1201837D03*
Y1195144D03*
X201141Y1205184D03*
Y1198491D03*
X205049Y1225263D03*
X205899Y1211877D03*
Y1218570D03*
X201041Y1221916D03*
Y1215223D03*
X201141Y1218570D03*
Y1211877D03*
Y1225263D03*
X205899Y1241995D03*
X205049Y1235302D03*
X201041Y1238648D03*
Y1231955D03*
X201141Y1241995D03*
Y1235302D03*
Y1228609D03*
X205899Y1248688D03*
X201041Y1245341D03*
X205899Y1258727D03*
X201041Y1248688D03*
X201193Y1257900D03*
X206268Y1271348D03*
X206337Y1268720D03*
X205899Y1265420D03*
Y1262074D03*
X193075Y1580678D03*
Y1575686D03*
X200179D03*
X205135D03*
X200179Y1580678D03*
X205135D03*
X200957Y1578182D03*
X204357D03*
X193075Y1592590D03*
Y1587598D03*
X200179Y1592590D03*
X205135D03*
X200179Y1587598D03*
X205135D03*
X198375Y1599884D03*
X193419D03*
X205479D03*
X200957Y1590094D03*
X204357D03*
X193419Y1616788D03*
Y1611796D03*
X198375D03*
X193419Y1604876D03*
X198375D03*
Y1616788D03*
X205479Y1611796D03*
Y1604876D03*
Y1616788D03*
X194197Y1614292D03*
X197597D03*
X206257D03*
X194197Y1602380D03*
X197597D03*
X206257D03*
X222041Y766798D03*
X214599Y770144D03*
X222041Y780184D03*
Y773491D03*
X214599Y783530D03*
Y776837D03*
X222041Y803609D03*
Y796916D03*
Y790223D03*
X214599Y800263D03*
Y793570D03*
X222041Y810302D03*
X221191Y816995D03*
X214599Y813648D03*
Y806955D03*
X215449Y820341D03*
X222041Y833727D03*
X221191Y827034D03*
X215449Y830381D03*
X222041Y847113D03*
Y840420D03*
X214599Y850459D03*
Y837074D03*
Y843766D03*
X221191Y863845D03*
X215449Y867192D03*
X222041Y853806D03*
X215449Y857152D03*
X222041Y877231D03*
X221191Y870538D03*
X222041Y883924D03*
X214599Y873885D03*
Y880577D03*
X222041Y900656D03*
Y890617D03*
X214599Y893963D03*
Y887270D03*
X222041Y914042D03*
Y907349D03*
X214599Y917389D03*
Y910696D03*
Y904003D03*
X221241Y927428D03*
X222041Y920735D03*
X215449Y930774D03*
Y924081D03*
X222041Y944160D03*
X221191Y937467D03*
X214599Y940814D03*
Y947507D03*
X222041Y960892D03*
Y950853D03*
X214599Y964239D03*
Y954200D03*
Y960892D03*
Y957546D03*
X222041D03*
Y954200D03*
Y980971D03*
Y974278D03*
Y967585D03*
X214599Y970932D03*
Y977625D03*
Y991011D03*
Y984318D03*
X222041Y987664D03*
Y994357D03*
Y1027822D03*
Y1017782D03*
X214599Y1031168D03*
Y1017782D03*
Y1024475D03*
X222041Y1047900D03*
Y1041207D03*
Y1034515D03*
X214599Y1044554D03*
Y1037861D03*
X222041Y1054593D03*
Y1061286D03*
X214599Y1057940D03*
Y1051247D03*
X222041Y1067979D03*
X221191Y1074672D03*
X215449Y1078018D03*
X214599Y1071326D03*
Y1064633D03*
X222041Y1091404D03*
X221191Y1084711D03*
X214599Y1094751D03*
X215449Y1088058D03*
X222041Y1111483D03*
Y1098097D03*
Y1104790D03*
X214599Y1101444D03*
Y1108137D03*
X222041Y1128215D03*
Y1121522D03*
X214599Y1114829D03*
Y1124869D03*
X222041Y1141601D03*
X221191Y1134908D03*
X214599Y1144948D03*
Y1138255D03*
Y1131562D03*
X222041Y1158333D03*
X221191Y1148294D03*
X215449Y1161680D03*
Y1151641D03*
X222041Y1165026D03*
Y1171719D03*
X214599Y1168373D03*
Y1175066D03*
X222041Y1185105D03*
Y1178412D03*
X214599Y1188452D03*
Y1181759D03*
X222041Y1208530D03*
Y1201837D03*
Y1195144D03*
X214599Y1205184D03*
Y1198491D03*
X222041Y1221916D03*
Y1215223D03*
X215449Y1225263D03*
X214599Y1211877D03*
Y1218570D03*
X221191Y1231955D03*
Y1238648D03*
X214599Y1241995D03*
X215449Y1235302D03*
X222041Y1245341D03*
X214824Y1258711D03*
X214599Y1248688D03*
X222041Y1255381D03*
X219660Y1260492D03*
X222041Y1252034D03*
X224987Y1273535D03*
X222041Y1265420D03*
Y1262074D03*
X212239Y1580678D03*
X217195D03*
Y1575686D03*
X212239D03*
X224299D03*
Y1580678D03*
X225077Y1578182D03*
X213017D03*
X216417D03*
X212239Y1587598D03*
X217195D03*
X212239Y1592590D03*
X217195D03*
X224299Y1587598D03*
Y1592590D03*
X210435Y1599884D03*
X222495D03*
X217539D03*
X225077Y1590094D03*
X213017D03*
X216417D03*
X210435Y1611796D03*
Y1604876D03*
Y1616788D03*
X222495D03*
X217539D03*
X222495Y1604876D03*
Y1611796D03*
X217539Y1604876D03*
Y1611796D03*
X209657Y1614292D03*
X218317D03*
X221717D03*
X209657Y1602380D03*
X218317D03*
X221717D03*
X235599Y770144D03*
X230741Y766798D03*
X235499D03*
X235599Y783530D03*
Y776837D03*
X230741Y780184D03*
Y773491D03*
X235599Y800263D03*
Y793570D03*
X230741Y803609D03*
Y796916D03*
Y790223D03*
X234749Y820341D03*
Y813648D03*
X235599Y806955D03*
X230741Y810302D03*
X231006Y817554D03*
X235599Y830381D03*
X230741Y833727D03*
X231591Y827034D03*
X235599Y850459D03*
Y837074D03*
Y843766D03*
X230741Y847113D03*
Y840420D03*
X234749Y867492D03*
X231591Y863845D03*
X234749Y857152D03*
X230741Y853806D03*
X235599Y874185D03*
Y880577D03*
X230741Y877231D03*
X231059Y871084D03*
X230741Y883924D03*
X235599Y893963D03*
Y887270D03*
X230741Y900656D03*
Y890617D03*
X235599Y917389D03*
Y910696D03*
Y904003D03*
X230741Y914042D03*
Y907349D03*
X235599Y930774D03*
Y924081D03*
X231541Y927428D03*
X230741Y920735D03*
X235599Y947507D03*
X234859Y940814D03*
X230741Y944660D03*
X231591Y937467D03*
X235599Y964239D03*
Y954200D03*
X230741Y960892D03*
Y950853D03*
X235599Y977625D03*
Y970932D03*
X230741Y980971D03*
Y974278D03*
Y967585D03*
X235599Y991011D03*
X230741Y987664D03*
X235599Y984318D03*
X236391Y1002557D03*
X240521Y1000395D03*
X237841Y1000437D03*
X233891Y1002557D03*
X231391D03*
X228891D03*
X235599Y1031168D03*
X230741Y1027822D03*
Y1017782D03*
X235599D03*
Y1024475D03*
Y1044554D03*
Y1037861D03*
X230741Y1047900D03*
Y1041207D03*
Y1034515D03*
X235599Y1051247D03*
Y1057940D03*
X230741Y1054593D03*
Y1061286D03*
X234749Y1078018D03*
X235599Y1071326D03*
Y1064633D03*
X230741Y1067979D03*
X231591Y1074672D03*
X235599Y1094751D03*
X234749Y1088058D03*
X230741Y1091404D03*
Y1084711D03*
X235599Y1108137D03*
Y1101444D03*
X230741Y1111483D03*
Y1098097D03*
Y1104790D03*
X234749Y1124869D03*
X235599Y1114829D03*
X230741Y1128215D03*
Y1121522D03*
X235599Y1144948D03*
Y1138255D03*
X234749Y1131562D03*
X230741Y1141601D03*
X231591Y1134908D03*
X235599Y1151641D03*
Y1161680D03*
X230741Y1158333D03*
X231591Y1148294D03*
X235599Y1175066D03*
Y1168373D03*
X230741Y1165026D03*
Y1171719D03*
X235599Y1188452D03*
Y1181759D03*
X230741Y1185105D03*
Y1178412D03*
X235599Y1205184D03*
Y1198491D03*
X230741Y1208530D03*
Y1201837D03*
Y1195144D03*
X234749Y1225263D03*
X235599Y1218570D03*
Y1211877D03*
X230741Y1221916D03*
Y1215223D03*
X235599Y1241995D03*
X235186Y1234977D03*
X231591Y1231955D03*
Y1238648D03*
X235599Y1248688D03*
X230741Y1245341D03*
X235599Y1258727D03*
X230741Y1248688D03*
X227746Y1273364D03*
X240966Y1273143D03*
X238971Y1274353D03*
X235480Y1265406D03*
X235599Y1262074D03*
X229255Y1575686D03*
Y1580678D03*
X236359D03*
Y1575686D03*
X241315Y1580678D03*
Y1575686D03*
X237137Y1578182D03*
X240537D03*
X228477D03*
X229255Y1587598D03*
Y1592590D03*
X236359D03*
Y1587598D03*
X241315Y1592590D03*
Y1587598D03*
X229599Y1599884D03*
X234555D03*
X237137Y1590094D03*
X240537D03*
X228477D03*
X229599Y1604876D03*
Y1611796D03*
X234555Y1604876D03*
Y1611796D03*
X229599Y1616788D03*
X234555D03*
X230377Y1614292D03*
X233777D03*
X230377Y1602380D03*
X233777D03*
X233268Y1679920D03*
Y1675383D03*
X241142Y1679320D03*
X233268Y1698627D03*
Y1694093D03*
Y1689556D03*
Y1684454D03*
X241142Y1683857D03*
Y1688391D03*
Y1693493D03*
Y1698030D03*
X233268Y1712800D03*
Y1708266D03*
Y1703729D03*
X241142Y1702564D03*
Y1707666D03*
Y1712203D03*
X233268Y1717903D03*
Y1722440D03*
Y1726974D03*
X241142Y1716737D03*
Y1730911D03*
Y1726377D03*
Y1721840D03*
X251741Y766798D03*
X244299Y770144D03*
X251741Y780184D03*
Y773491D03*
X244299Y783530D03*
Y776837D03*
X251741Y803609D03*
Y796916D03*
Y790223D03*
X244299Y800263D03*
Y793570D03*
X250891Y816995D03*
X251741Y810302D03*
X245149Y820341D03*
Y813648D03*
X244299Y806955D03*
X251741Y833727D03*
X250891Y827034D03*
X244299Y830381D03*
X251741Y847113D03*
Y840420D03*
X244299Y850459D03*
Y837074D03*
Y843766D03*
X250891Y863845D03*
Y853806D03*
X245149Y867192D03*
Y857152D03*
X251741Y870538D03*
Y883924D03*
Y877231D03*
X244299Y873885D03*
Y880577D03*
Y883924D03*
X250891Y900656D03*
X251741Y890617D03*
X244299Y893963D03*
Y887270D03*
Y890617D03*
Y897310D03*
Y900656D03*
X251741Y914042D03*
Y907349D03*
X244299Y917389D03*
Y910696D03*
Y904003D03*
Y914042D03*
Y907349D03*
X250891Y927428D03*
X251741Y920735D03*
X245149Y930774D03*
X244299Y924081D03*
X251741Y944160D03*
X250891Y937467D03*
X244299Y947507D03*
X245149Y940814D03*
X251741Y960892D03*
Y950853D03*
X244299Y964239D03*
Y954200D03*
Y960892D03*
Y957546D03*
X251741D03*
Y954200D03*
Y980971D03*
Y974278D03*
Y967585D03*
X244299Y977625D03*
Y970932D03*
X251741Y987664D03*
X244299Y991011D03*
Y984318D03*
X251741Y994357D03*
X254881Y999650D03*
X257561Y999608D03*
X244299Y1031168D03*
X251741Y1027822D03*
Y1017782D03*
X244299D03*
Y1024475D03*
X251741Y1047900D03*
Y1041207D03*
Y1034515D03*
X244299Y1044554D03*
Y1037861D03*
X251741Y1061286D03*
Y1054593D03*
X244299Y1051247D03*
Y1057940D03*
Y1061286D03*
X250891Y1074672D03*
Y1067979D03*
X245149Y1078018D03*
X244299Y1071326D03*
Y1064633D03*
X251741Y1091404D03*
Y1084711D03*
X244299Y1094751D03*
X245149Y1088058D03*
X251741Y1104790D03*
X250891Y1111483D03*
X251741Y1098097D03*
X244299Y1108137D03*
Y1101444D03*
X251741Y1128215D03*
X250891Y1121522D03*
X245149Y1124869D03*
X244299Y1114829D03*
X251741Y1134908D03*
Y1141601D03*
X244299Y1144948D03*
Y1138255D03*
X245149Y1131562D03*
X251741Y1158333D03*
Y1148294D03*
X244299Y1151641D03*
Y1161680D03*
X251741Y1171719D03*
Y1165026D03*
X244299Y1175066D03*
Y1168373D03*
X251741Y1185105D03*
Y1178412D03*
X244299Y1188452D03*
Y1181759D03*
Y1185105D03*
Y1178412D03*
Y1191798D03*
X251741Y1208530D03*
Y1201837D03*
X250891Y1195144D03*
X244299Y1205184D03*
Y1198491D03*
Y1208530D03*
Y1201837D03*
Y1195144D03*
X250891Y1221916D03*
X251741Y1215223D03*
X245149Y1225263D03*
X244299Y1218570D03*
Y1211877D03*
X250891Y1231955D03*
X244299Y1241995D03*
X245149Y1235302D03*
X251741Y1238648D03*
X244299Y1248688D03*
X251741Y1245341D03*
X248047Y1259155D03*
X250467Y1259175D03*
X251707Y1252034D03*
X244789Y1260093D03*
X254897Y1274040D03*
X257197Y1273640D03*
X249603Y1266204D03*
X251699Y1265254D03*
X248419Y1575686D03*
X253375D03*
X248419Y1580678D03*
X253375D03*
X249197Y1578182D03*
X252597D03*
X248419Y1587598D03*
X253375D03*
X248419Y1592590D03*
X253375D03*
X246615Y1599884D03*
X241659D03*
X253719D03*
X249197Y1590094D03*
X252597D03*
X241659Y1616788D03*
X246615D03*
Y1604876D03*
X241659D03*
X246615Y1611796D03*
X241659D03*
X253719Y1604876D03*
Y1611796D03*
Y1616788D03*
X242437Y1614292D03*
X254497D03*
X245837D03*
X242437Y1602380D03*
X254497D03*
X245837D03*
X249016Y1675383D03*
Y1679920D03*
X256890Y1679320D03*
X249016Y1684454D03*
Y1689556D03*
Y1694093D03*
Y1698627D03*
X256890Y1683857D03*
Y1688391D03*
Y1693493D03*
Y1698030D03*
X249016Y1703729D03*
Y1708266D03*
Y1712800D03*
X256890Y1702564D03*
Y1707666D03*
Y1712203D03*
X249016Y1726974D03*
Y1722440D03*
Y1717903D03*
X256890Y1716737D03*
Y1730911D03*
Y1726377D03*
Y1721840D03*
X272529Y111053D03*
X265442D03*
X261899D03*
Y108553D03*
X265442D03*
X268985Y111053D03*
Y108553D03*
X272529D03*
X260441Y766798D03*
Y780184D03*
Y773491D03*
Y803609D03*
Y796916D03*
Y790223D03*
X261291Y816995D03*
X260441Y810302D03*
Y833727D03*
X261291Y827034D03*
X260441Y847113D03*
Y840420D03*
X261291Y863845D03*
Y853806D03*
X260441Y870538D03*
Y883924D03*
Y877231D03*
Y880577D03*
Y900656D03*
Y890617D03*
Y887270D03*
Y897310D03*
Y893963D03*
Y914042D03*
Y907349D03*
Y910696D03*
Y904003D03*
X261291Y927428D03*
X260441Y920735D03*
Y944160D03*
X261291Y937467D03*
X260441Y960892D03*
Y950853D03*
Y980971D03*
Y974278D03*
Y967585D03*
Y987664D03*
Y1027822D03*
Y1017782D03*
Y1047900D03*
Y1041207D03*
Y1034515D03*
Y1061286D03*
Y1054593D03*
Y1057940D03*
X261291Y1074672D03*
Y1067979D03*
X260441Y1091404D03*
Y1084711D03*
Y1104790D03*
X261291Y1111483D03*
X260441Y1098097D03*
Y1128215D03*
X261291Y1121522D03*
X260441Y1134908D03*
Y1141601D03*
Y1158333D03*
Y1148294D03*
Y1171719D03*
Y1165026D03*
Y1175066D03*
Y1185105D03*
Y1178412D03*
Y1181759D03*
Y1191798D03*
Y1188452D03*
Y1208530D03*
Y1201837D03*
Y1195144D03*
Y1205184D03*
Y1198491D03*
X261291Y1221916D03*
X260441Y1215223D03*
X261291Y1231955D03*
X260441Y1238648D03*
Y1245341D03*
Y1248688D03*
X260479Y1580678D03*
X265435D03*
X260479Y1575592D03*
X265435D03*
X272539Y1575686D03*
Y1580678D03*
X273317Y1578182D03*
X261257D03*
X264657D03*
X260479Y1592590D03*
X265435D03*
X260479Y1587598D03*
X265435D03*
X272539D03*
Y1592590D03*
X258675Y1599884D03*
X270735Y1599790D03*
X265779D03*
X273317Y1590094D03*
X261257D03*
X264657D03*
X258675Y1604876D03*
Y1611796D03*
Y1616788D03*
X270735D03*
X265779D03*
X270735Y1611796D03*
Y1604876D03*
X265779D03*
Y1611796D03*
X266557Y1614292D03*
X257897D03*
X269957D03*
X266557Y1602380D03*
X257897D03*
X269957D03*
X264764Y1675383D03*
Y1679920D03*
X272638Y1679320D03*
X264764Y1684454D03*
Y1689556D03*
Y1694093D03*
Y1698627D03*
X272638Y1683857D03*
Y1688391D03*
Y1693493D03*
Y1698030D03*
X264764Y1703729D03*
Y1708266D03*
Y1712800D03*
X272638Y1702564D03*
Y1707666D03*
Y1712203D03*
X264764Y1726974D03*
Y1722440D03*
Y1717903D03*
X272638Y1716737D03*
Y1730911D03*
Y1726377D03*
Y1721840D03*
X277495Y1575686D03*
Y1580678D03*
X284599D03*
X289555D03*
Y1575686D03*
X284599D03*
X285377Y1578182D03*
X288777D03*
X276717D03*
X277495Y1587598D03*
Y1592590D03*
X284599D03*
X289555D03*
X284599Y1587598D03*
X289555D03*
X282795Y1599884D03*
X277839D03*
X289899D03*
X285377Y1590094D03*
X288777D03*
X276717D03*
X282795Y1604876D03*
Y1611796D03*
X277839D03*
Y1604876D03*
X282795Y1616788D03*
X277839D03*
X289899D03*
Y1604876D03*
Y1611796D03*
X278617Y1614292D03*
X282017D03*
X278617Y1602380D03*
X282017D03*
X280512Y1675383D03*
Y1679920D03*
Y1684454D03*
Y1689556D03*
Y1694093D03*
Y1698627D03*
Y1703729D03*
Y1708266D03*
Y1712800D03*
Y1726974D03*
Y1722440D03*
Y1717903D03*
X296659Y1575686D03*
X301615D03*
X296659Y1580678D03*
X301615D03*
X297437Y1578182D03*
X300837D03*
X296659Y1587598D03*
X301615D03*
X296659Y1592590D03*
X301615D03*
X294855Y1599884D03*
X301959D03*
X297437Y1590094D03*
X300837D03*
X294855Y1616788D03*
Y1604876D03*
Y1611796D03*
X301959Y1604876D03*
Y1611796D03*
Y1616788D03*
X290677Y1614292D03*
X302737D03*
X294077D03*
X306137D03*
X290677Y1602380D03*
X302737D03*
X294077D03*
X306137D03*
X300197Y1679920D03*
Y1675383D03*
Y1698627D03*
Y1694093D03*
Y1689556D03*
Y1684454D03*
Y1712800D03*
Y1708266D03*
Y1703729D03*
Y1717903D03*
Y1722440D03*
Y1726974D03*
X308719Y1580678D03*
X313675D03*
X308719Y1575686D03*
X313675D03*
X320779D03*
Y1580678D03*
X321557Y1578182D03*
X309497D03*
X312897D03*
X308719Y1592590D03*
X313675D03*
X308719Y1587598D03*
X313675D03*
X320779D03*
Y1592590D03*
X306915Y1599884D03*
X318975D03*
X314019D03*
X321557Y1590094D03*
X309497D03*
X312897D03*
X306915Y1604876D03*
Y1611796D03*
Y1616788D03*
X318975D03*
X314019D03*
X318975Y1604876D03*
Y1611796D03*
X314019Y1604876D03*
Y1611796D03*
X314797Y1614292D03*
X318197D03*
X314797Y1602380D03*
X318197D03*
X308071Y1679320D03*
X315945Y1679920D03*
Y1675383D03*
X308071Y1683857D03*
Y1698030D03*
Y1693493D03*
Y1688391D03*
X315945Y1698627D03*
Y1694093D03*
Y1689556D03*
Y1684454D03*
X308071Y1702564D03*
Y1712203D03*
Y1707666D03*
X315945Y1712800D03*
Y1708266D03*
Y1703729D03*
X308071Y1716737D03*
Y1721840D03*
Y1726377D03*
Y1730911D03*
X315945Y1717903D03*
Y1722440D03*
Y1726974D03*
X338042Y849978D03*
X337778Y854584D03*
X335924Y857789D03*
X334079Y880219D03*
X332228Y877014D03*
X335928D03*
X337779Y880219D03*
X335928Y883423D03*
X334078Y893036D03*
X335928Y896240D03*
X337779Y893036D03*
X335928Y889832D03*
X334079Y886627D03*
X337779D03*
X332229Y902649D03*
X332228Y915466D03*
X335928D03*
X332229Y921875D03*
Y941100D03*
X332228Y934692D03*
X335928D03*
X334079Y957122D03*
X335928Y953917D03*
X332228D03*
X332229Y973143D03*
X334079Y976347D03*
X331284Y978814D03*
X335349Y985939D03*
X338210Y996480D03*
X332661Y1006093D03*
X338211Y1002888D03*
X332661Y1025318D03*
Y1018910D03*
X338211Y1015705D03*
X332661Y1044544D03*
X334511Y1041340D03*
X333834Y1062790D03*
X329632Y1092168D03*
X336360Y1082995D03*
X338211Y1111834D03*
X335344Y1097289D03*
X338211Y1124651D03*
X336361Y1115039D03*
Y1127856D03*
X338211Y1118243D03*
X336361Y1121447D03*
X338211Y1131060D03*
X325735Y1575686D03*
Y1580678D03*
X332839D03*
X337795D03*
X332839Y1575686D03*
X337795D03*
X333617Y1578182D03*
X337017D03*
X324957D03*
X325735Y1587598D03*
Y1592590D03*
X332839D03*
X337795D03*
X332839Y1587598D03*
X337795D03*
X326079Y1599884D03*
X331035D03*
X338139D03*
X333617Y1590094D03*
X337017D03*
X324957D03*
X326079Y1604876D03*
Y1611796D03*
X331035Y1604876D03*
Y1611796D03*
X326079Y1616788D03*
X331035D03*
X338139D03*
Y1604876D03*
Y1611796D03*
X330257Y1614292D03*
X338917D03*
X326857D03*
X330257Y1602380D03*
X338917D03*
X326857D03*
X323819Y1679320D03*
X331693Y1679920D03*
Y1675383D03*
X323819Y1683857D03*
Y1698030D03*
Y1693493D03*
Y1688391D03*
X331693Y1698627D03*
Y1694093D03*
Y1689556D03*
Y1684454D03*
X323819Y1702564D03*
Y1712203D03*
Y1707666D03*
X331693Y1712800D03*
Y1708266D03*
Y1703729D03*
X323819Y1716737D03*
Y1721840D03*
Y1726377D03*
Y1730911D03*
X331693Y1717903D03*
Y1722440D03*
Y1726974D03*
X345178Y854584D03*
X347028Y844971D03*
X345178Y848176D03*
X350727Y844971D03*
X347027Y851380D03*
X343327D03*
X354429D03*
X350727D03*
X354427Y844971D03*
X348878Y848176D03*
X352578D03*
X341478Y854584D03*
X339628Y857789D03*
X347029Y864197D03*
Y857789D03*
X348878Y854584D03*
X345179Y860993D03*
X343327Y857789D03*
X352579Y854584D03*
X354429Y864197D03*
X350729D03*
X348879Y867401D03*
X352579D03*
X348879Y860993D03*
X350729Y857789D03*
X352578Y860993D03*
X354429Y857789D03*
X347029Y870606D03*
X354429Y877014D03*
X339629D03*
X345179Y880219D03*
Y873810D03*
X343329Y877014D03*
X352579Y880219D03*
X350729Y877014D03*
X339629Y883423D03*
X347029D03*
X350729D03*
X341479Y880219D03*
X343329Y883423D03*
X350729Y870606D03*
X354429D03*
X352578Y873810D03*
X354429Y883423D03*
X348879Y873810D03*
X347029Y877014D03*
X348878Y880219D03*
X352578Y899445D03*
X339629Y896240D03*
Y889832D03*
X348879Y886627D03*
X347029Y889832D03*
X345179Y893036D03*
X343328Y896240D03*
X352578Y893036D03*
Y886627D03*
X345179Y899445D03*
X348878D03*
Y893036D03*
X350729Y889832D03*
X354429D03*
X341478Y893036D03*
X343328Y889832D03*
X347029Y896240D03*
X354429D03*
X341479Y886627D03*
X350729Y896240D03*
X345179Y886627D03*
X348878Y905853D03*
X352578D03*
X347029Y909057D03*
Y902649D03*
X345179Y912262D03*
X352578D03*
X339629Y915466D03*
X343329D03*
X348878Y912262D03*
X350729Y909057D03*
X354429D03*
X350729Y902649D03*
X354429D03*
X347029Y915466D03*
X354429D03*
X350729D03*
X348878Y925079D03*
X352578D03*
Y918670D03*
X347029Y928283D03*
Y921875D03*
X345179Y918670D03*
Y931488D03*
X352578D03*
X348879D03*
X350729Y928283D03*
X354429D03*
Y921875D03*
X350729D03*
X348878Y918670D03*
X352578Y944304D03*
X347029Y941100D03*
X348878Y944304D03*
X347029Y947509D03*
X352578Y937896D03*
X339629Y934692D03*
X345179Y937896D03*
X343328Y934692D03*
X350729Y941100D03*
X348878Y937896D03*
X354429Y941100D03*
X347029Y934691D03*
X354429D03*
X350729D03*
Y947509D03*
X354429D03*
X348878Y963530D03*
X347029Y960326D03*
X339629Y966735D03*
Y953917D03*
X343328D03*
X345179Y957122D03*
X352578D03*
X347029Y966735D03*
X352578Y963530D03*
X345179Y950713D03*
X352578D03*
X348878D03*
X350729Y960326D03*
X348878Y957122D03*
X354429Y960326D03*
X350729Y966735D03*
X354429D03*
X350729Y953917D03*
X354429D03*
X347030D03*
X354428Y973143D03*
X339629D03*
X345179Y976347D03*
Y969939D03*
X350729Y973143D03*
X347029Y979552D03*
X352579Y976347D03*
X352578Y969939D03*
X348878Y982756D03*
X352578D03*
X339629Y979552D03*
X343329Y973143D03*
X350729Y979552D03*
X354429D03*
X348878Y976347D03*
X347029Y973143D03*
X348878Y969939D03*
X347461Y999684D03*
X345611Y1009297D03*
X343761Y1006093D03*
X345611Y1002888D03*
X351162Y1006093D03*
X354861D03*
X353011Y1009297D03*
Y1002888D03*
X347461Y1012501D03*
Y1006093D03*
X349311Y1002888D03*
X351161Y999684D03*
X354861D03*
X351161Y1012501D03*
X349311Y1009297D03*
X354861Y1012501D03*
X343761Y999684D03*
X353011Y1028523D03*
Y1015705D03*
X341911D03*
X349311D03*
X347461Y1018910D03*
X345611Y1028523D03*
Y1022114D03*
X353011D03*
X347461Y1031727D03*
X351162D03*
X349311Y1028523D03*
X354861Y1031727D03*
X349311Y1022114D03*
X351161Y1018910D03*
X354861D03*
X347461Y1025318D03*
X354862D03*
X351162D03*
X353011Y1034931D03*
Y1047749D03*
X349311Y1034931D03*
X347461Y1038136D03*
X345611Y1041340D03*
X343761Y1044544D03*
X353011Y1041340D03*
X345611Y1047749D03*
X349311D03*
Y1041340D03*
X351161Y1038136D03*
X354861D03*
X347461Y1044544D03*
X354861D03*
X351161D03*
X349311Y1054157D03*
X353011Y1060565D03*
Y1054157D03*
X347461Y1050952D03*
Y1057361D03*
X345611Y1060565D03*
X343761Y1063770D03*
X349311Y1060565D03*
X351161Y1057361D03*
X354861D03*
X347461Y1063770D03*
X351161D03*
X354861D03*
X351161Y1050952D03*
X354861D03*
X353011Y1073383D03*
X340062Y1076587D03*
X347461D03*
Y1070178D03*
X349312Y1073383D03*
X345611Y1066974D03*
X353011D03*
X345611Y1079791D03*
X353011D03*
X354861Y1070178D03*
X351162D03*
X349311Y1066974D03*
Y1079791D03*
X351161Y1076587D03*
X354861D03*
X353011Y1086200D03*
X349310Y1092609D03*
X347461Y1089404D03*
X345610Y1086200D03*
X343760Y1082995D03*
X343707Y1091513D03*
X353011Y1092608D03*
X351161Y1089404D03*
X349311Y1086200D03*
X354861Y1089404D03*
X347461Y1082995D03*
X354861D03*
X351161D03*
X347461Y1108630D03*
X354861D03*
X353011Y1099017D03*
X340061Y1108630D03*
Y1102221D03*
X349311Y1099017D03*
X347461Y1102221D03*
X343761D03*
X349311Y1105426D03*
X341911D03*
X343762Y1108630D03*
X345611Y1111834D03*
X351161Y1102221D03*
X349312Y1111834D03*
X353011Y1105426D03*
X345611D03*
X341912Y1111834D03*
X354861Y1102221D03*
X353012Y1111834D03*
X351162Y1108630D03*
X340061Y1115039D03*
X349311Y1124651D03*
X349312Y1118243D03*
X345611D03*
X343761Y1115039D03*
X341911Y1124651D03*
X354861Y1115039D03*
X351161Y1121447D03*
Y1115039D03*
X353011Y1124651D03*
X354861Y1127856D03*
X351162D03*
X353011Y1118243D03*
X354861Y1121447D03*
X347461Y1115039D03*
X341912Y1118243D03*
X340061Y1127856D03*
X343761D03*
X347461Y1121447D03*
X340061D03*
X343761D03*
X347461Y1127856D03*
X345611Y1124651D03*
Y1137469D03*
Y1131060D03*
X349311D03*
X343761Y1134264D03*
X353011Y1137469D03*
Y1131060D03*
X349312Y1137469D03*
X351161Y1134264D03*
X347461D03*
X354861D03*
X341911Y1131060D03*
X344899Y1575686D03*
X349855D03*
X344899Y1580678D03*
X349855D03*
X345677Y1578182D03*
X349077D03*
X344899Y1587598D03*
X349855D03*
X344899Y1592590D03*
X349855D03*
X343095Y1599884D03*
X355155D03*
X350199D03*
X345677Y1590094D03*
X349077D03*
X343095Y1616788D03*
Y1604876D03*
Y1611796D03*
X355155Y1604876D03*
Y1611796D03*
X350199Y1604876D03*
Y1611796D03*
X355155Y1616788D03*
X350199D03*
X350977Y1614292D03*
X342317D03*
X354377D03*
X350977Y1602380D03*
X342317D03*
X354377D03*
X339567Y1679320D03*
X347441Y1679920D03*
Y1675383D03*
X355315Y1679320D03*
X339567Y1683857D03*
Y1698030D03*
Y1693493D03*
Y1688391D03*
X347441Y1698627D03*
Y1694093D03*
Y1689556D03*
Y1684454D03*
X355315Y1683857D03*
Y1698030D03*
Y1693493D03*
Y1688391D03*
X339567Y1702564D03*
Y1712203D03*
Y1707666D03*
X347441Y1712800D03*
Y1708266D03*
Y1703729D03*
X355315Y1702564D03*
Y1712203D03*
Y1707666D03*
X339567Y1716737D03*
Y1721840D03*
Y1726377D03*
Y1730911D03*
X347441Y1717903D03*
Y1722440D03*
Y1726974D03*
X355315Y1716737D03*
Y1721840D03*
Y1726377D03*
Y1730911D03*
X359979Y841467D03*
X367379D03*
X365529Y851380D03*
X361829D03*
X358129D03*
X369229D03*
X356278Y848176D03*
X371078D03*
X363678D03*
X356279Y841467D03*
X361827Y844971D03*
X363679Y841467D03*
X369227Y844971D03*
X371079Y841467D03*
X358127Y844971D03*
X359978Y848176D03*
X365527Y844971D03*
X367378Y848176D03*
X365529Y864197D03*
X361829D03*
X359979Y854584D03*
X358129Y864197D03*
X369229D03*
X367379Y854584D03*
X359979Y867401D03*
X367379D03*
X371078D03*
X356278D03*
X363678D03*
X356278Y860993D03*
X371078D03*
X363678D03*
X356278Y854584D03*
X358129Y857789D03*
X363678Y854584D03*
X365529Y857789D03*
X371078Y854584D03*
X359978Y860993D03*
X361829Y857789D03*
X367378Y860993D03*
X369229Y857789D03*
X365529Y877014D03*
X361829D03*
X359979Y880219D03*
X358129Y877014D03*
X369229D03*
X367379Y880219D03*
X358129Y870606D03*
X361829D03*
X365529D03*
X359978Y873810D03*
X367378D03*
X369229Y870606D03*
X356278Y880219D03*
X358129Y883423D03*
X363678Y880219D03*
X365529Y883423D03*
X371078Y880219D03*
X361829Y883423D03*
X369229D03*
X371078Y873810D03*
X356278D03*
X363678D03*
X356278Y886627D03*
X365529Y896240D03*
Y889832D03*
X361828Y896240D03*
X361829Y889832D03*
X359979Y893036D03*
X358128Y889832D03*
X369229Y896240D03*
Y889832D03*
X359979Y899445D03*
X371078D03*
X356278D03*
Y893036D03*
X358129Y896240D03*
X363678Y899445D03*
X367378D03*
X371078Y893036D03*
X363679D03*
X367379D03*
X359978Y886627D03*
X367378D03*
X363678D03*
X371078D03*
X356278Y905853D03*
X365529Y909057D03*
Y902649D03*
X359978Y912262D03*
X358128Y909057D03*
X358129Y902649D03*
X371079Y912262D03*
X365529Y915466D03*
X361828D03*
X369229D03*
X356278Y912262D03*
X358129Y915466D03*
X363678Y912262D03*
X361829Y909057D03*
X367378Y912262D03*
X369229Y909057D03*
X361829Y902649D03*
X369229D03*
X359978Y905853D03*
X367378D03*
X363678D03*
X371078D03*
X356279Y925079D03*
X365529Y928283D03*
Y921875D03*
X359979Y918670D03*
X358128Y928283D03*
X358129Y921875D03*
X371078Y918670D03*
X359978Y931488D03*
X371079D03*
X356278D03*
X363678D03*
X356278Y918670D03*
X361829Y928283D03*
X367378Y931488D03*
X369229Y928283D03*
X361829Y921875D03*
X363678Y918670D03*
X369229Y921875D03*
X367378Y918670D03*
X359978Y925079D03*
X367378D03*
X363678D03*
X371078D03*
X358128Y947509D03*
X358129Y941100D03*
X356279Y944304D03*
X365529Y947509D03*
Y941100D03*
Y934691D03*
X361828D03*
X359979Y937896D03*
X369229Y934691D03*
X371078Y937896D03*
X356278D03*
X358129Y934691D03*
X361829Y941100D03*
X363678Y937896D03*
X369229Y941100D03*
X367378Y937896D03*
X361829Y947509D03*
X369229D03*
X367378Y944304D03*
X359978D03*
X371078D03*
X363678D03*
X356279Y963530D03*
X358129Y960326D03*
X359979Y957122D03*
X358128Y966735D03*
X361829Y953917D03*
X359978Y950713D03*
X371078Y957122D03*
X371079Y950713D03*
X365529Y953917D03*
X367378Y963530D03*
X363679D03*
X365529Y960326D03*
X365528Y966735D03*
X369229Y953917D03*
X356278Y950713D03*
Y957122D03*
X358129Y953917D03*
X361829Y966735D03*
X369229D03*
X359978Y963530D03*
X363678Y950713D03*
X367378D03*
X361829Y960326D03*
X363678Y957122D03*
X369229Y960326D03*
X367378Y957122D03*
X371078Y963530D03*
X359979Y976347D03*
X358129Y979552D03*
X359978Y969939D03*
X361828Y973143D03*
X356279Y982756D03*
X371078Y976347D03*
X371079Y969939D03*
X369229Y973143D03*
X365529Y979552D03*
Y973143D03*
X359978Y982756D03*
X367378D03*
X363678D03*
X371078D03*
X369229Y979552D03*
X367378Y976347D03*
X361829Y979552D03*
X363678Y976347D03*
X356278D03*
Y969939D03*
X358129Y973143D03*
X363678Y969939D03*
X367378D03*
X365962Y999684D03*
Y1006093D03*
X362261D03*
X360411Y1009297D03*
X360412Y1002888D03*
X358562Y999684D03*
X369662Y1006093D03*
X371512Y1009297D03*
X365961Y1012501D03*
X358561D03*
X358562Y1006093D03*
X356711Y1002888D03*
Y1009297D03*
X362262Y1012501D03*
X369662D03*
X364111Y1009297D03*
X367811D03*
X364111Y1002888D03*
X362262Y999684D03*
X369662D03*
X356712Y1015705D03*
X365962Y1025318D03*
Y1018910D03*
X364112Y1015705D03*
X360411Y1028523D03*
X362261Y1025318D03*
X360412Y1022114D03*
X358562Y1018910D03*
X369662Y1025318D03*
X367811Y1015705D03*
X371511Y1028523D03*
Y1022114D03*
X365962Y1031727D03*
X358561D03*
X356711Y1028523D03*
Y1022114D03*
X362262Y1031727D03*
X364111Y1028523D03*
X369662Y1031727D03*
X367811Y1028523D03*
X358562Y1025318D03*
X360411Y1015705D03*
X371511D03*
X364111Y1022114D03*
X362262Y1018910D03*
X367811Y1022114D03*
X369662Y1018910D03*
X356712Y1034931D03*
X365962Y1044544D03*
Y1038136D03*
X362261Y1044544D03*
X360412Y1041340D03*
X358562Y1038136D03*
X369662Y1044544D03*
X371511Y1041340D03*
X360411Y1047749D03*
X371511D03*
X356711D03*
Y1041340D03*
X364111D03*
X362262Y1038136D03*
X367811Y1041340D03*
X369662Y1038136D03*
X360411Y1034931D03*
X371511D03*
X364111D03*
X358562Y1044544D03*
X367811Y1034931D03*
X364111Y1047749D03*
X367811D03*
X356712Y1054157D03*
X365962Y1057361D03*
Y1050952D03*
X360412Y1060565D03*
X358562Y1057361D03*
X358561Y1050952D03*
X371511Y1060565D03*
X365962Y1063770D03*
X362261D03*
X369662D03*
X356711Y1060565D03*
X358562Y1063770D03*
X364111Y1060565D03*
X362262Y1057361D03*
X367811Y1060565D03*
X369662Y1057361D03*
X362262Y1050952D03*
X369662D03*
X360411Y1054157D03*
X371511D03*
X364111D03*
X367811D03*
X356712Y1073383D03*
X365962Y1070178D03*
Y1076587D03*
X360411Y1066974D03*
X358561Y1070178D03*
X358562Y1076587D03*
X371512Y1066974D03*
X360412Y1079791D03*
X371511D03*
X356711Y1066974D03*
X367811Y1079791D03*
X369662Y1076587D03*
X362262Y1070178D03*
X364111Y1066974D03*
X369662Y1070178D03*
X367811Y1066974D03*
X356711Y1079791D03*
X364111D03*
X362262Y1076587D03*
X360411Y1073383D03*
X371511D03*
X364111D03*
X367811D03*
X365962Y1089404D03*
Y1082995D03*
X362261D03*
X360411Y1086200D03*
X358561Y1089404D03*
X356712Y1092608D03*
X369662Y1082995D03*
X371512Y1086200D03*
X365962Y1095813D03*
X358561D03*
X356711Y1086200D03*
X358562Y1082995D03*
X362262Y1095813D03*
X369662D03*
X362262Y1089404D03*
X364111Y1086200D03*
X369662Y1089404D03*
X367811Y1086200D03*
X360411Y1092608D03*
X367811D03*
X364111D03*
X371511D03*
X365962Y1102221D03*
X362262D03*
X360411Y1099017D03*
X356711Y1105426D03*
Y1099017D03*
X371512Y1105426D03*
Y1099017D03*
X364112Y1111834D03*
X356712D03*
X371512D03*
X364111Y1099017D03*
X367811D03*
Y1105426D03*
X369661Y1102221D03*
X358562D03*
X360412Y1105426D03*
X358561Y1108630D03*
X360412Y1111834D03*
X364112Y1105426D03*
X369661Y1108630D03*
X362261D03*
X365961D03*
X367812Y1111834D03*
X364111Y1118243D03*
X362261Y1115039D03*
X360411Y1118243D03*
X356711D03*
X367811D03*
X371511D03*
X365962Y1127856D03*
X358561D03*
Y1121447D03*
X360412Y1124651D03*
X364111D03*
X367811D03*
X371511D03*
X356712D03*
X362262Y1127856D03*
X365962Y1121447D03*
X369662Y1127856D03*
Y1121447D03*
X362261D03*
X365961Y1115039D03*
X358561D03*
X369661D03*
X365961Y1140973D03*
X364112Y1131060D03*
X360412D03*
X358561Y1140973D03*
X356712Y1131060D03*
X367811D03*
X371511D03*
X358561Y1134264D03*
X362261Y1140973D03*
X365962Y1134264D03*
X369661Y1140973D03*
X356712Y1137469D03*
X360412D03*
X364112D03*
X367812D03*
X371512D03*
X369662Y1134264D03*
X362262D03*
X356959Y1580678D03*
X361915D03*
X356959Y1575592D03*
X361915D03*
X369019Y1575686D03*
Y1580678D03*
X369797Y1578182D03*
X357737D03*
X361137D03*
X356959Y1592590D03*
X361915D03*
X356959Y1587598D03*
X361915D03*
X367215Y1599790D03*
X362259D03*
X369019Y1587598D03*
Y1592590D03*
X369797Y1590094D03*
X357737D03*
X361137D03*
X367215Y1616788D03*
X362259D03*
X367215Y1604876D03*
Y1611796D03*
X362259Y1604876D03*
Y1611796D03*
X363037Y1614292D03*
X366437D03*
X363037Y1602380D03*
X366437D03*
X382179Y841467D03*
X374779D03*
X380329Y851380D03*
X376629D03*
X372929D03*
X384029D03*
X387729D03*
X385878Y848176D03*
X378478D03*
X387727Y844971D03*
X376627D03*
X380327D03*
X384027D03*
X385879Y841467D03*
X372927Y844971D03*
X374778Y848176D03*
X378479Y841467D03*
X382178Y848176D03*
X382179Y854584D03*
X380329Y864197D03*
X376629D03*
X374779Y854584D03*
X372929Y864197D03*
X384029D03*
X387729D03*
X382179Y867401D03*
X374779D03*
X378478D03*
X385878D03*
X378478Y860993D03*
X385878D03*
X387729Y857789D03*
X372929D03*
X378478Y854584D03*
X380329Y857789D03*
X384029D03*
X374778Y860993D03*
X376629Y857789D03*
X382178Y860993D03*
X385878Y854584D03*
X382179Y880219D03*
X380329Y877014D03*
X376629D03*
X374779Y880219D03*
X372929Y877014D03*
X384029D03*
X387729D03*
Y870606D03*
X372929D03*
X380329D03*
X374778Y873810D03*
X376629Y870606D03*
X382178Y873810D03*
X384029Y870606D03*
X372929Y883423D03*
X378478Y880219D03*
X380329Y883423D03*
X385878Y880219D03*
X387729Y883423D03*
X376629D03*
X384029D03*
X378478Y873810D03*
X385878D03*
X380329Y889832D03*
X378479Y893036D03*
X376629Y889832D03*
X372929D03*
X384029D03*
X387729Y896240D03*
Y889832D03*
X378478Y899445D03*
X385879D03*
X374778D03*
X382178D03*
Y893036D03*
X374778D03*
X385878D03*
X372929Y896240D03*
X380329D03*
X376629D03*
X384029D03*
X374778Y886627D03*
X382178D03*
X378478D03*
X385878D03*
X382179Y905853D03*
X378478Y912262D03*
Y905853D03*
X374778D03*
X372929Y909057D03*
X372928Y902649D03*
X385878Y912262D03*
X384028Y909057D03*
X384029Y902649D03*
X387728Y915466D03*
X376629Y902649D03*
X380329D03*
X374778Y912262D03*
X376629Y909057D03*
X382178Y912262D03*
X380329Y909057D03*
X387729D03*
Y902649D03*
X372929Y915466D03*
X385878Y905853D03*
X380329Y915466D03*
X376629D03*
X384029D03*
X382179Y925079D03*
X378478D03*
Y918670D03*
X374778Y925079D03*
X372929Y928283D03*
X372928Y921875D03*
X385879Y918670D03*
X384028Y928283D03*
X384029Y921875D03*
X378478Y931488D03*
X385878D03*
X374778D03*
X376629Y928283D03*
X382178Y931488D03*
X380329Y928283D03*
X387729Y921875D03*
X376629D03*
X374778Y918670D03*
X380329Y921875D03*
X382178Y918670D03*
X387729Y928283D03*
X385878Y925079D03*
X384029Y941100D03*
X384028Y947509D03*
X374778Y944304D03*
X372929Y947509D03*
X372928Y941100D03*
X382179Y944304D03*
X378478D03*
Y937896D03*
X385879D03*
X387728Y934691D03*
X380329Y941100D03*
X382178Y937896D03*
X376629Y947509D03*
X380329D03*
X376629Y941100D03*
X374778Y937896D03*
X372929Y934691D03*
X380329D03*
X376629D03*
X384029D03*
X387729Y947509D03*
Y941100D03*
X385878Y944304D03*
X387729Y953917D03*
X372928Y960326D03*
X374778Y963530D03*
X372929Y966735D03*
X382179Y963530D03*
X378478D03*
Y957122D03*
X384029Y960326D03*
X385879Y957122D03*
X384028Y966735D03*
X385878Y950713D03*
X378478D03*
X376629Y960326D03*
X374778Y957122D03*
X380329Y960326D03*
X382178Y957122D03*
X374778Y950713D03*
X382178D03*
X372929Y953917D03*
X380329D03*
X376629D03*
X384029D03*
X387729Y960326D03*
Y966735D03*
X380329D03*
X376629D03*
X385878Y963530D03*
X387728Y973143D03*
X376629D03*
X380328D03*
X378479Y976347D03*
X378478Y969939D03*
X385879Y976347D03*
X384029Y979552D03*
X385878Y969939D03*
X374778Y982756D03*
X382179D03*
X378478D03*
X372928Y979552D03*
X385878Y982756D03*
X387729Y979552D03*
X376629D03*
X380329D03*
X374778Y976347D03*
X382178D03*
X372929Y973143D03*
X374778Y969939D03*
X382178D03*
X384029Y973143D03*
X375210Y996480D03*
X373361Y999684D03*
X378911Y1009297D03*
Y1002888D03*
X386311Y1009297D03*
X386312Y1002888D03*
X384462Y999684D03*
X373362Y1012501D03*
X384461D03*
X373362Y1006093D03*
X380762D03*
X377062D03*
X384462D03*
X375211Y1002888D03*
X377062Y999684D03*
X382611Y1002888D03*
X380762Y999684D03*
X377062Y1012501D03*
X375211Y1009297D03*
X380762Y1012501D03*
X382611Y1009297D03*
X382612Y1015705D03*
X378911Y1028523D03*
Y1022114D03*
Y1015705D03*
X375211D03*
X373361Y1018910D03*
X386311Y1028523D03*
X386312Y1022114D03*
X384462Y1018910D03*
X373362Y1031727D03*
X384461D03*
X377062D03*
X375211Y1028523D03*
X380762Y1031727D03*
X382611Y1028523D03*
X375211Y1022114D03*
X377062Y1018910D03*
X382611Y1022114D03*
X380762Y1018910D03*
X377062Y1025318D03*
X384462D03*
X373360D03*
X380760D03*
X386311Y1015705D03*
X382612Y1034931D03*
X378911Y1041340D03*
Y1034931D03*
X375211D03*
X373361Y1038136D03*
X386312Y1041340D03*
X384462Y1038136D03*
X378911Y1047749D03*
X386311D03*
X375211D03*
X382611D03*
X375211Y1041340D03*
X377062Y1038136D03*
X382611Y1041340D03*
X380762Y1038136D03*
X373362Y1044544D03*
X380762D03*
X377062D03*
X384462D03*
X386311Y1034931D03*
X382612Y1054157D03*
X378911Y1060565D03*
Y1054157D03*
X375211D03*
X373361Y1057361D03*
X373362Y1050952D03*
X386312Y1060565D03*
X384462Y1057361D03*
X384461Y1050952D03*
X375211Y1060565D03*
X377062Y1057361D03*
X382611Y1060565D03*
X380762Y1057361D03*
X377062Y1050952D03*
X380762D03*
X373362Y1063770D03*
X384462D03*
X377062D03*
X380762D03*
X386311Y1054157D03*
X382612Y1073383D03*
X378911D03*
Y1066974D03*
X375211Y1073383D03*
X373361Y1076587D03*
X373362Y1070178D03*
X386311Y1066974D03*
X384462Y1076587D03*
X384461Y1070178D03*
X378911Y1079791D03*
X386311D03*
X380762Y1070178D03*
X382611Y1066974D03*
X377062Y1070178D03*
X375211Y1066974D03*
Y1079791D03*
X377062Y1076587D03*
X382611Y1079791D03*
X380762Y1076587D03*
X386311Y1073383D03*
X382611Y1092608D03*
X378911D03*
Y1086200D03*
X375211Y1092608D03*
X373362Y1089404D03*
X386311Y1086200D03*
X384461Y1089404D03*
X373362Y1095813D03*
X384462D03*
X377062Y1089404D03*
X375211Y1086200D03*
X380762Y1089404D03*
X382611Y1086200D03*
X373362Y1082995D03*
X386311Y1092608D03*
X384462Y1082995D03*
X377062D03*
X380762D03*
X375211Y1099017D03*
X380762Y1095813D03*
Y1108630D03*
X378911Y1099017D03*
X377062Y1102221D03*
X373361Y1108630D03*
Y1102221D03*
X386312Y1099017D03*
X384462Y1102221D03*
X382611Y1099017D03*
X386311Y1105426D03*
X382611Y1111834D03*
X375211Y1105426D03*
X377062Y1108630D03*
X380762Y1102221D03*
X378911Y1111834D03*
X384462Y1108630D03*
X386311Y1111834D03*
X378912Y1105426D03*
X375211Y1111834D03*
X382611Y1105426D03*
Y1118243D03*
X378911D03*
X377061Y1115039D03*
X375211Y1118243D03*
X373361Y1115039D03*
X386311Y1118243D03*
X384461Y1115039D03*
X380761Y1127856D03*
X373361D03*
X375211Y1124651D03*
X378911D03*
X382611D03*
X386311D03*
X373362Y1121447D03*
X377062Y1127856D03*
X380762Y1121447D03*
X384462Y1127856D03*
Y1121447D03*
X377062D03*
X380762Y1115039D03*
X382611Y1131060D03*
X380761Y1140973D03*
X378911Y1131060D03*
X375211D03*
X373361Y1140973D03*
X386311Y1131060D03*
X373362Y1134264D03*
X377061Y1140973D03*
X380762Y1134264D03*
X384461Y1140973D03*
X375212Y1137469D03*
X378912D03*
X382612D03*
X386312D03*
X384462Y1134264D03*
X377062D03*
X380930Y1531402D03*
X384210Y1534152D03*
X373975Y1575686D03*
Y1580678D03*
X373197Y1578182D03*
X373975Y1587598D03*
Y1592590D03*
X379275Y1599884D03*
X374319D03*
X373197Y1590094D03*
X379275Y1604876D03*
Y1611796D03*
X374319Y1604876D03*
Y1611796D03*
X379275Y1616788D03*
X374319D03*
X375097Y1614292D03*
X378497D03*
X375097Y1602380D03*
X378497D03*
X396979Y841467D03*
X389579D03*
X398829Y851380D03*
X395129D03*
X391429D03*
X402529D03*
X400678Y848176D03*
X393278D03*
X391427Y844971D03*
X395127D03*
X398827D03*
X400679Y841467D03*
X389578Y848176D03*
X393279Y841467D03*
X396978Y848176D03*
X402527Y844971D03*
X398829Y864197D03*
X396979Y854584D03*
X395129Y864197D03*
X391429D03*
X389579Y854584D03*
X402529Y864197D03*
X396979Y867401D03*
X389579D03*
X400678D03*
X393278D03*
X400678Y860993D03*
X393278D03*
Y854584D03*
X395129Y857789D03*
X400678Y854584D03*
X402529Y857789D03*
X389578Y860993D03*
X391429Y857789D03*
X396978Y860993D03*
X398829Y857789D03*
Y877014D03*
X396979Y880219D03*
X395129Y877014D03*
X391429D03*
X389579Y880219D03*
X402529Y877014D03*
X391429Y870606D03*
X395129D03*
X402529D03*
X389578Y873810D03*
X396978D03*
X398829Y870606D03*
X393278Y880219D03*
X395129Y883423D03*
X400678Y880219D03*
X402529Y883423D03*
X391429D03*
X398829D03*
X393278Y873810D03*
X400678D03*
X398829Y889832D03*
X395129Y896240D03*
Y889832D03*
X391428Y896240D03*
X391429Y889832D03*
X389579Y893036D03*
X402529Y889832D03*
X396978Y899445D03*
X402529Y896240D03*
X400678Y899445D03*
X389578D03*
X393278D03*
X393279Y893036D03*
X396979D03*
X396978Y886627D03*
X389578D03*
X398829Y896240D03*
X400678Y893036D03*
X393278Y886627D03*
X400678D03*
X404378Y899445D03*
X398829Y909057D03*
X398828Y902649D03*
X396979Y912262D03*
X391429Y909057D03*
Y902649D03*
X395129Y915466D03*
X391429D03*
X400678Y905853D03*
X402529Y915466D03*
Y909057D03*
X389578Y912262D03*
X393278D03*
X395129Y909057D03*
Y902649D03*
X393278Y905853D03*
X389578D03*
X396978D03*
X406229Y915466D03*
X400678Y912262D03*
X402529Y902649D03*
X400678Y931488D03*
X402529Y928283D03*
Y921875D03*
X398829Y928283D03*
X398828Y921875D03*
X396978Y918670D03*
X391429Y928283D03*
Y921875D03*
X400678Y925079D03*
X396979Y931488D03*
X393278D03*
X395129Y928283D03*
X389578Y918670D03*
X395129Y921875D03*
X393278Y918670D03*
X389578Y931488D03*
X393278Y925079D03*
X389578D03*
X396978D03*
X398829Y934691D03*
X402529D03*
X398828Y941100D03*
X396978Y937896D03*
X395129Y934691D03*
X391429Y941100D03*
Y934691D03*
X400678Y937896D03*
X398829Y947509D03*
X391429D03*
X395129D03*
X389578Y937896D03*
X395129Y941100D03*
X393278Y937896D03*
Y944304D03*
X389578D03*
X396978D03*
X402529Y941100D03*
X400679Y944304D03*
X402529Y947509D03*
X398828Y960326D03*
X396978Y957122D03*
X396979Y950713D03*
X395129Y953917D03*
X391429Y960326D03*
Y953917D03*
X400678Y957122D03*
X398829Y966735D03*
X391429D03*
X400678Y963530D03*
X389578Y957122D03*
X395129Y960326D03*
X393278Y957122D03*
X395129Y966735D03*
X389578Y950713D03*
X393278D03*
X396978Y963530D03*
X393278D03*
X389578D03*
X402529Y966735D03*
Y960326D03*
X398829Y953917D03*
X402529D03*
X400680Y950713D03*
X398828Y979552D03*
X396978Y976347D03*
X396979Y969939D03*
X395129Y973143D03*
X391429Y979552D03*
Y973143D03*
X400678Y982756D03*
Y969939D03*
X398829Y973143D03*
X400678Y976347D03*
X402529Y979552D03*
Y973143D03*
X393278Y982756D03*
X389578D03*
X396978D03*
X393278Y976347D03*
X395129Y979552D03*
X389579Y976347D03*
X389578Y969939D03*
X393278D03*
X397412Y1009297D03*
X397411Y1002888D03*
X395562Y1006093D03*
X391862D03*
Y999684D03*
X388161Y1006093D03*
X401111Y1002888D03*
X399262Y1012501D03*
X391861D03*
X399262Y1006093D03*
X402962D03*
X390011Y1002888D03*
X388162Y999684D03*
X393711Y1002888D03*
X395562Y999684D03*
X399262D03*
X402962D03*
X388162Y1012501D03*
X395562D03*
X390011Y1009297D03*
X393711D03*
X401111D03*
X402962Y1012501D03*
Y1031727D03*
X399261Y1018910D03*
X397411Y1028523D03*
Y1022114D03*
X395562Y1025318D03*
X393711Y1015705D03*
X391862Y1025318D03*
Y1018910D03*
X390012Y1015705D03*
X388161Y1025318D03*
X399262Y1031727D03*
X391862D03*
X397411Y1015705D03*
X388162Y1031727D03*
X390011Y1028523D03*
X395562Y1031727D03*
X393711Y1028523D03*
X390011Y1022114D03*
X388162Y1018910D03*
X393711Y1022114D03*
X395562Y1018910D03*
X401111Y1028523D03*
Y1022114D03*
X402960Y1018910D03*
X402962Y1025318D03*
X399262D03*
X401111Y1015705D03*
X399261Y1038136D03*
X397411Y1041340D03*
X395562Y1044544D03*
X391862D03*
Y1038136D03*
X388161Y1044544D03*
X397411Y1047749D03*
X390011Y1041340D03*
X388162Y1038136D03*
X393711Y1041340D03*
X395562Y1038136D03*
X390011Y1047749D03*
X393711D03*
Y1034931D03*
X390011D03*
X397411D03*
X401111Y1047749D03*
X399262Y1044544D03*
X402962D03*
X401111Y1041340D03*
X402962Y1038136D03*
X406662Y1057361D03*
X399261D03*
X399262Y1050952D03*
X397411Y1060565D03*
X391862Y1057361D03*
Y1050952D03*
X395562Y1063770D03*
X391862D03*
X388161D03*
X390011Y1060565D03*
X388162Y1057361D03*
X393711Y1060565D03*
X395562Y1057361D03*
X388162Y1050952D03*
X395562D03*
X393711Y1054157D03*
X390011D03*
X397411D03*
X402962Y1057361D03*
Y1063770D03*
X401113Y1060565D03*
X399262Y1063770D03*
X401111Y1054157D03*
X402962Y1050952D03*
Y1076587D03*
Y1070178D03*
X399261Y1076587D03*
X399262Y1070178D03*
X397412Y1066974D03*
X391862Y1076587D03*
Y1070178D03*
X401111Y1073383D03*
X397411Y1079791D03*
X401111D03*
X390011D03*
X388162Y1076587D03*
X393711Y1079791D03*
X395562Y1076587D03*
X388162Y1070178D03*
X390011Y1066974D03*
X395562Y1070178D03*
X393711Y1066974D03*
Y1073383D03*
X390011D03*
X397411D03*
X401112Y1066974D03*
X399262Y1089404D03*
X397412Y1086200D03*
X395562Y1082995D03*
X391862Y1089404D03*
Y1082995D03*
X388161D03*
X401112Y1092608D03*
X401111Y1086200D03*
X399261Y1095813D03*
X391862D03*
X402962D03*
X395562D03*
X388162Y1089404D03*
X390011Y1086200D03*
X395562Y1089404D03*
X393711Y1086200D03*
X388162Y1095813D03*
X393711Y1092608D03*
X390011D03*
X397411D03*
X399262Y1082995D03*
X402962D03*
X402961Y1089404D03*
X399262Y1102221D03*
X397412Y1099017D03*
X395562Y1102221D03*
X390011Y1105426D03*
X388162Y1108630D03*
Y1102221D03*
X401111Y1105426D03*
X397411Y1111834D03*
X390011D03*
X393711Y1099017D03*
X390011D03*
X391862Y1102221D03*
X393711Y1105426D03*
X401111Y1099017D03*
X391862Y1108630D03*
X393711Y1111834D03*
X397411Y1105426D03*
X402962Y1108630D03*
Y1102221D03*
X395562Y1108630D03*
X399262D03*
X401111Y1111834D03*
X397411Y1118243D03*
X395561Y1115039D03*
X393711Y1118243D03*
X390011D03*
X388161Y1115039D03*
X401111Y1118243D03*
X395561Y1127856D03*
X388161D03*
X402961D03*
X390011Y1124651D03*
X395562Y1121447D03*
X397411Y1124651D03*
X401111D03*
X391862Y1127856D03*
X393711Y1124651D03*
X399262Y1127856D03*
X402962Y1121447D03*
X388162D03*
X391862D03*
X399262Y1115039D03*
X391862D03*
X402962D03*
X399262Y1121447D03*
X397411Y1131060D03*
X395561Y1140973D03*
X393711Y1131060D03*
X390011D03*
X388161Y1140973D03*
X402961D03*
X401111Y1131060D03*
X391861Y1140973D03*
X395562Y1134264D03*
X399261Y1140973D03*
X402962Y1134264D03*
X388162D03*
X390012Y1137469D03*
X393712D03*
X397412D03*
X401112D03*
X391862Y1134264D03*
X399262D03*
X419179Y841467D03*
X404379D03*
X411779D03*
X413629Y851380D03*
X409929D03*
X406229D03*
X417329D03*
X408078Y848176D03*
X415478D03*
X406227Y844971D03*
X409927D03*
X413627D03*
X417327D03*
X404378Y848176D03*
X408079Y841467D03*
X411778Y848176D03*
X415479Y841467D03*
X419178Y848176D03*
X404379Y854584D03*
X413629Y864197D03*
X411779Y854584D03*
X409929Y864197D03*
X406229D03*
X419179Y854584D03*
X417329Y864197D03*
X404379Y867401D03*
X411779D03*
X419179D03*
X408078D03*
X415478D03*
Y860993D03*
X408078D03*
Y854584D03*
X409929Y857789D03*
X415478Y854584D03*
X417329Y857789D03*
X404378Y860993D03*
X406229Y857789D03*
X411778Y860993D03*
X413629Y857789D03*
X419178Y860993D03*
X404379Y880219D03*
X413629Y877014D03*
X411779Y880219D03*
X409929Y877014D03*
Y870606D03*
X406229Y877014D03*
X419179Y880219D03*
X417329Y877014D03*
X404378Y873810D03*
X406229Y870606D03*
X408078Y880219D03*
X409929Y883423D03*
X406229D03*
X419178Y873810D03*
X417329Y870606D03*
X411778Y873810D03*
X413629Y870606D03*
X417329Y883423D03*
X415478Y880219D03*
X413629Y883423D03*
X415478Y873810D03*
X408078D03*
X413629Y889832D03*
X411779Y893036D03*
X409929Y889832D03*
X408079Y893036D03*
X406229Y889832D03*
X419179Y893036D03*
X417329Y889832D03*
X404378Y886627D03*
X411778D03*
X419178D03*
X404378Y893036D03*
X415478Y886627D03*
X408078D03*
X406229Y896240D03*
X408078Y899445D03*
X415478D03*
X409929Y896240D03*
X415478Y893036D03*
X417329Y896240D03*
X422878Y893036D03*
X411778Y899445D03*
X413629Y896240D03*
X419178Y899445D03*
X422878Y912262D03*
X413629Y902649D03*
X409929Y909057D03*
Y902649D03*
X404378Y912262D03*
Y905853D03*
X419178Y912262D03*
X419179Y905853D03*
X417329Y902649D03*
X409929Y915466D03*
X417329Y909057D03*
X406229D03*
X413629D03*
Y915466D03*
X411778Y905853D03*
X408078D03*
Y912262D03*
X406229Y902649D03*
X415478Y905853D03*
X411778Y912262D03*
X415478D03*
X417329Y915466D03*
X411779Y918670D03*
X406229Y921875D03*
X409929D03*
X404378Y918670D03*
X418229Y926896D03*
X419178Y918670D03*
X405048Y930812D03*
X408078Y918670D03*
X408569Y929108D03*
X406308Y928626D03*
X417329Y921875D03*
X411872Y925264D03*
X415479Y918670D03*
X405145Y946239D03*
Y948539D03*
X414093Y942098D03*
X405048Y938046D03*
Y935746D03*
X416393Y942098D03*
X418693D03*
X407589Y942164D03*
X405289D03*
X409889D03*
X405122Y965896D03*
Y963596D03*
X415185Y956620D03*
X411685D03*
X409385D03*
X417685D03*
X414365Y971140D03*
X416755D03*
X404861Y981269D03*
Y978969D03*
X404785Y971100D03*
X407085D03*
X409385D03*
X411685D03*
X420205D03*
X404861Y986421D03*
X405101Y992971D03*
Y995271D03*
X404861Y988721D03*
X415185Y985580D03*
X417575D03*
X412365Y985610D03*
X410065D03*
X420145Y985550D03*
X415185Y1014540D03*
X417575D03*
X405227Y1007156D03*
X405231Y1004848D03*
X417575Y1000060D03*
X415185D03*
X409385Y1014540D03*
X407085D03*
X411685D03*
X412385Y1000080D03*
X410085D03*
X420215Y1000040D03*
X420405Y1014470D03*
X404986Y1022427D03*
X404998Y1026821D03*
X414461Y1028855D03*
X411961D03*
X416961D03*
X419461D03*
X408325Y1031971D03*
Y1034271D03*
X408511Y1041340D03*
X417762Y1044544D03*
X412211Y1047749D03*
X404811D03*
X415911D03*
X419611D03*
X406662Y1044544D03*
X410362D03*
X408511Y1047749D03*
X414062Y1044544D03*
X404811Y1041340D03*
X412211D03*
X415911D03*
X419611D03*
X406662Y1050952D03*
X415911Y1060565D03*
Y1054157D03*
X412211Y1060565D03*
X410361Y1050952D03*
X408511Y1054157D03*
X404811Y1060565D03*
X417761Y1050952D03*
X414060D03*
X417762Y1057361D03*
X421462Y1050952D03*
X419611Y1054157D03*
X406662Y1063770D03*
X408511Y1060565D03*
X410362Y1063770D03*
X412211Y1054157D03*
X404811D03*
X414062Y1057361D03*
X410362D03*
X417762Y1063770D03*
X414062D03*
X419611Y1060565D03*
Y1079791D03*
X408511Y1073383D03*
X406662Y1070178D03*
X404811Y1073383D03*
X415911Y1066974D03*
X410362Y1076587D03*
Y1070178D03*
X406661Y1076587D03*
X404811Y1066974D03*
X419611Y1073383D03*
X412211Y1079791D03*
X404811D03*
X417762Y1076587D03*
X408511Y1066974D03*
X415911Y1079791D03*
X412211Y1073383D03*
X415911D03*
X414062Y1070178D03*
X417762D03*
X412211Y1066974D03*
X419611D03*
X408511Y1079791D03*
X415911Y1092608D03*
X415912Y1086200D03*
X412211Y1092608D03*
X408511Y1086200D03*
X417761Y1089404D03*
Y1082995D03*
X410362Y1095813D03*
X406662D03*
X419612Y1099017D03*
X404811Y1092608D03*
X417762Y1095813D03*
X414061D03*
X406662Y1089404D03*
X410362D03*
X404811Y1086200D03*
X419611D03*
X414062Y1082995D03*
X410362D03*
X406662D03*
X408511Y1092608D03*
X414062Y1089404D03*
X419611Y1092608D03*
X412211Y1086200D03*
X415912Y1099017D03*
X414062Y1108630D03*
X412211Y1099017D03*
X410362Y1102221D03*
X406661Y1108630D03*
Y1102221D03*
X404812Y1105426D03*
X417762Y1102221D03*
X404812Y1111834D03*
X404811Y1099017D03*
X408511Y1105426D03*
X412211Y1111834D03*
X415911D03*
X414062Y1102221D03*
X417762Y1108630D03*
X419611Y1105426D03*
X408511Y1099017D03*
X410362Y1108630D03*
X408511Y1111834D03*
X412211Y1105426D03*
X419611Y1111834D03*
X415911Y1105426D03*
Y1118243D03*
X414061Y1121447D03*
X412211Y1124651D03*
Y1118243D03*
X410361Y1115039D03*
X408511Y1118243D03*
X406661Y1115039D03*
X404811Y1118243D03*
X417761Y1115039D03*
X410361Y1127856D03*
X404811Y1124651D03*
X408511D03*
X406662Y1127856D03*
X410362Y1121447D03*
X415912Y1124651D03*
X419612D03*
Y1118243D03*
X417761Y1121447D03*
Y1127856D03*
X414062Y1115039D03*
X406661Y1121447D03*
X414062Y1127856D03*
Y1134264D03*
X412212Y1131060D03*
X410361Y1140973D03*
X408511Y1131060D03*
X404811D03*
X406661Y1140973D03*
X410362Y1134264D03*
X404812Y1137469D03*
X408512D03*
X406662Y1134264D03*
X415912Y1137469D03*
Y1131060D03*
X414061Y1140973D03*
X419612Y1137469D03*
Y1131060D03*
X417761Y1134264D03*
Y1140973D03*
X412212Y1137469D03*
X432128Y844671D03*
X426579Y841467D03*
X432129Y851380D03*
X428429D03*
X424729D03*
X421029D03*
X435829D03*
X422878Y848176D03*
X421027Y844971D03*
X424727D03*
X428427D03*
X433978Y848176D03*
X435829Y844671D03*
X422879Y841467D03*
X426578Y848176D03*
X430278D03*
X432129Y864197D03*
X428429D03*
X426579Y854584D03*
X424729Y864197D03*
X421029D03*
X433979Y854584D03*
X435829Y864197D03*
X426579Y867401D03*
X433979D03*
X430278D03*
X422878D03*
X430278Y860993D03*
X422878D03*
Y854584D03*
X424729Y857789D03*
X430278Y854584D03*
X433979Y860993D03*
X421029Y857789D03*
X426578Y860993D03*
X428429Y857789D03*
X432129D03*
X435829D03*
X432129Y877014D03*
X428429D03*
X426579Y880219D03*
X424729Y877014D03*
X421029D03*
X433979Y880219D03*
X435829Y877014D03*
X432129Y870606D03*
X426578Y873810D03*
X424729Y870606D03*
X433979Y873810D03*
X428429Y870606D03*
X421029D03*
X435829D03*
X432129Y883423D03*
X430278Y880219D03*
X424729Y883423D03*
X422878Y880219D03*
X428429Y883423D03*
X421029D03*
X435829D03*
X422878Y873810D03*
X430278D03*
X432129Y889832D03*
X428429D03*
X426579Y893036D03*
X424729Y889832D03*
X421029D03*
X433979Y893036D03*
X435829Y889832D03*
X433978Y886627D03*
X426578D03*
X422878D03*
X430278D03*
Y899445D03*
X422878D03*
X424729Y896240D03*
X430278Y893036D03*
X432129Y896240D03*
X437678Y893036D03*
X421029Y896240D03*
X426578Y899445D03*
X428429Y896240D03*
X433978Y899445D03*
X435829Y896240D03*
X424729Y915466D03*
X426578Y912262D03*
X424729Y902649D03*
X432129D03*
X428429Y909057D03*
Y902649D03*
X421029D03*
X435829D03*
X428429Y915466D03*
X430278Y912262D03*
X432129Y915466D03*
X421029Y909057D03*
X435829D03*
Y915466D03*
X432128Y909057D03*
X433978Y905853D03*
X424728Y909057D03*
X422878Y905853D03*
X430278D03*
X426578D03*
X421029Y915466D03*
X433979Y912262D03*
X430278Y918670D03*
X433980Y925079D03*
Y931487D03*
X428429Y921875D03*
X432129D03*
X433979Y918670D03*
X435829Y921875D03*
X424927Y927255D03*
X423176Y929465D03*
X422427Y927255D03*
X425676Y929465D03*
X424729Y921875D03*
X422878Y918670D03*
X421029Y921875D03*
X426578Y918670D03*
X430279Y925079D03*
X432130Y928283D03*
X430279Y931487D03*
X432130Y934692D03*
X435830Y928283D03*
X430279Y937897D03*
X433979D03*
X426875Y947199D03*
Y949499D03*
X427875Y936470D03*
X433980Y944305D03*
X427875Y941930D03*
Y944230D03*
X430280Y944305D03*
X432130Y941101D03*
X435830D03*
X432129Y947510D03*
X435830D03*
Y934692D03*
X426905Y965935D03*
Y963635D03*
X433980Y957123D03*
Y950714D03*
Y963531D03*
X427875Y956373D03*
Y954073D03*
X422685Y956620D03*
X425185D03*
X430280Y957123D03*
X432129Y960327D03*
Y953918D03*
X430280Y950714D03*
X435830Y960327D03*
Y953918D03*
X432129Y966736D03*
X430280Y963531D03*
X435830Y966736D03*
X426905Y980336D03*
Y978036D03*
X433980Y976348D03*
Y969940D03*
Y982757D03*
X430268Y976348D03*
X432129Y973144D03*
X430280Y969940D03*
X427875Y971267D03*
X422685Y971100D03*
X427875Y968967D03*
X435830Y973144D03*
X430280Y982757D03*
X432129Y979553D03*
X427875Y983111D03*
X435830Y979553D03*
X426905Y994722D03*
Y992422D03*
X422685Y985580D03*
X427875Y985411D03*
Y997521D03*
X426905Y1006875D03*
Y1009175D03*
X434411Y1009298D03*
X434412Y1002889D03*
X430712Y1009298D03*
X427875Y1012152D03*
X430712Y1002889D03*
X427875Y999821D03*
X422685Y1000060D03*
X436263Y1006094D03*
Y999685D03*
X432562Y1006094D03*
Y999685D03*
X427875Y1014452D03*
X423015Y1014470D03*
X436263Y1012502D03*
X432562D03*
X426905Y1021963D03*
Y1019663D03*
X434411Y1028524D03*
Y1022115D03*
X434412Y1015706D03*
X421961Y1028855D03*
X430712Y1022115D03*
Y1015706D03*
X427875Y1026704D03*
X430712Y1028524D03*
X436263Y1018911D03*
X432562D03*
Y1025319D03*
X436263D03*
X427875Y1029004D03*
Y1031304D03*
X436263Y1031728D03*
X432562D03*
X428862Y1044544D03*
X434412Y1034932D03*
X430712Y1047749D03*
X423311D03*
X427011D03*
X427012Y1041340D03*
X423312D03*
X425162Y1044544D03*
X423285Y1036884D03*
X430711Y1041340D03*
X430712Y1034932D03*
X427875Y1033604D03*
X423285Y1032284D03*
Y1034584D03*
X436262Y1038137D03*
X436261Y1044544D03*
X432562Y1038137D03*
X434412Y1041340D03*
X432561Y1044544D03*
X434412Y1047749D03*
X421462Y1044544D03*
X427011Y1054157D03*
X430711D03*
X425162Y1057361D03*
X432561Y1050952D03*
X434411Y1060565D03*
Y1054157D03*
X421462Y1063770D03*
X428861Y1057361D03*
X432561D03*
X421462D03*
X425162Y1050952D03*
X423311Y1054157D03*
X428862Y1050952D03*
X436262Y1057361D03*
Y1050952D03*
Y1063770D03*
X425162D03*
X423311Y1060565D03*
X427011D03*
X428861Y1063770D03*
X430711Y1060565D03*
X423311Y1073383D03*
X432560Y1070178D03*
X421462Y1076587D03*
X430711Y1073383D03*
X427011D03*
Y1066974D03*
X425162Y1076587D03*
X423311Y1066974D03*
X432561Y1076587D03*
X434411Y1073383D03*
Y1066974D03*
X427012Y1079791D03*
X434411D03*
X423311D03*
X436262Y1070178D03*
Y1076587D03*
X421462Y1070178D03*
X425162D03*
X428862D03*
X430711Y1066974D03*
X428861Y1076587D03*
X430711Y1079791D03*
X428861Y1082995D03*
X425162Y1089404D03*
X421462Y1082995D03*
X432561Y1089404D03*
Y1082995D03*
X434411Y1092608D03*
Y1086200D03*
X428861Y1095813D03*
X421462D03*
X432561D03*
X436262Y1082995D03*
Y1089404D03*
X436261Y1095813D03*
X421462Y1089404D03*
X423311Y1092608D03*
X427011D03*
X430710Y1086200D03*
X425162Y1082995D03*
Y1095813D03*
X430711Y1092608D03*
X423311Y1086200D03*
X428861Y1089404D03*
X427012Y1086200D03*
X427011Y1099017D03*
X425161Y1102221D03*
X423311Y1105426D03*
X421462Y1108630D03*
X434411Y1105426D03*
X423311Y1111834D03*
X434411D03*
X421462Y1102221D03*
X423311Y1099017D03*
X428861Y1108630D03*
X427012Y1105426D03*
X425162Y1108630D03*
X430711Y1105426D03*
Y1099017D03*
X428861Y1102221D03*
X436262Y1108630D03*
Y1102221D03*
X432561Y1108630D03*
Y1102221D03*
X434412Y1099017D03*
X430711Y1111834D03*
X427012D03*
X423311Y1124651D03*
Y1118243D03*
X421462Y1115039D03*
X434411Y1124651D03*
Y1118243D03*
X430711Y1124651D03*
X428861Y1121447D03*
X427012Y1124651D03*
X425162Y1121447D03*
X421461D03*
X430711Y1118243D03*
X428861Y1115039D03*
X427012Y1118243D03*
X425162Y1115039D03*
X436262Y1121447D03*
Y1115039D03*
X432561Y1121447D03*
Y1115039D03*
X428861Y1127856D03*
X425162D03*
X421461D03*
X436262D03*
X432561D03*
X423312Y1137469D03*
X423311Y1131060D03*
X434412Y1137769D03*
X434411Y1131060D03*
X430711Y1137769D03*
X427012Y1137569D03*
X430711Y1131060D03*
X428861Y1134264D03*
X427012Y1131060D03*
X425162Y1134264D03*
X421461D03*
X428861Y1140973D03*
X425161D03*
X421461D03*
X436261Y1134264D03*
X432561D03*
X452478Y848176D03*
X445078D03*
X441378D03*
X439529Y844671D03*
X446929Y851380D03*
X443228D03*
X439529D03*
X450629D03*
X450628Y844971D03*
X446927Y844671D03*
X452479Y841467D03*
X448778Y848176D03*
X443227Y844671D03*
X437678Y848176D03*
X448779Y854584D03*
X446929Y864197D03*
X443229D03*
X441379Y854584D03*
X439529Y864197D03*
X439528Y857789D03*
X437680Y860992D03*
X450629Y864197D03*
X448779Y867401D03*
X441379D03*
X452478D03*
X445078D03*
X437678D03*
X445078Y860993D03*
X452479D03*
X437679Y854584D03*
X452478D03*
X450629Y857789D03*
X445078Y854584D03*
X443229Y857789D03*
X448779Y860993D03*
X446929Y857789D03*
X441378Y860993D03*
X448779Y880219D03*
X446929Y877014D03*
X443229D03*
X441379Y880219D03*
X439529Y877014D03*
X450629D03*
X448779Y873810D03*
X446929Y870606D03*
X441378Y873810D03*
X439529Y870606D03*
X450629D03*
X443229D03*
X452479Y880219D03*
X446929Y883423D03*
X445078Y880219D03*
X439529Y883423D03*
X437678Y880219D03*
X450629Y883423D03*
X443229D03*
X437679Y873810D03*
X452479D03*
X445078D03*
X448779Y893036D03*
X446929Y889832D03*
X443229D03*
X441379Y893036D03*
X439529Y896240D03*
Y889832D03*
X437678Y886627D03*
X450629Y889832D03*
X437679Y899445D03*
X448778Y886627D03*
X441378D03*
X452478D03*
X445078D03*
X452478Y899445D03*
X441378D03*
X445078Y893036D03*
X446929Y896240D03*
X452479Y893036D03*
X445078Y899445D03*
X443229Y896240D03*
X448778Y899445D03*
X450630Y896240D03*
X446929Y909057D03*
Y902649D03*
X443229D03*
X439528D03*
X437678Y912262D03*
X437679Y905853D03*
X450629Y902649D03*
X446929Y915466D03*
X443229Y909057D03*
X439529Y915466D03*
X445079Y905853D03*
X441379D03*
X450630Y909057D03*
X452479Y905853D03*
X448779D03*
X448780Y912262D03*
X441380D03*
X439529Y909057D03*
X445080Y912262D03*
X443229Y915466D03*
X450629D03*
X452478Y912262D03*
X448779Y918670D03*
X454329Y915466D03*
X439529Y921875D03*
X446930Y928283D03*
X441379Y925079D03*
Y931487D03*
X446929Y921875D03*
X437678Y918670D03*
X441378D03*
X450629Y921875D03*
X445078Y918670D03*
X443229Y921875D03*
X452478Y918670D03*
X446930Y934692D03*
X443230Y928283D03*
X448780Y931487D03*
X437679D03*
X450630Y928283D03*
X448780Y925079D03*
X445079Y931487D03*
X439530Y934692D03*
X445079Y925079D03*
X439530Y928283D03*
X437679Y925079D03*
X441379Y937897D03*
X445079D03*
X437679D03*
X448779D03*
X446929Y941101D03*
X446930Y947510D03*
X437680Y944305D03*
X441380D03*
X443230Y941101D03*
X445079Y944305D03*
X439530Y941101D03*
X450630D03*
X448780Y944305D03*
X443229Y947510D03*
X439529D03*
X450630D03*
X443230Y934692D03*
X446930Y960327D03*
Y953918D03*
Y966736D03*
X445079Y957123D03*
X437680D03*
X441380D03*
X439529Y960327D03*
X443229D03*
Y953918D03*
X439529D03*
X437680Y950714D03*
X441380D03*
X445079D03*
X448780Y957123D03*
X450630Y953918D03*
Y960327D03*
X448780Y950714D03*
X445079Y963531D03*
X437680D03*
X441380D03*
X439529Y966736D03*
X443229D03*
X448780Y963531D03*
X450630Y966736D03*
X446930Y979553D03*
Y973144D03*
X445079Y976348D03*
Y969940D03*
X439529Y973144D03*
X443229D03*
X437680Y976348D03*
X441380D03*
X437680Y969940D03*
X441380D03*
X450630Y973144D03*
X448780Y976348D03*
Y969940D03*
X445079Y982757D03*
X437680D03*
X441380D03*
X439529Y979553D03*
X443229D03*
X448780Y982757D03*
X450630Y979553D03*
X447362Y1006094D03*
Y999685D03*
Y1012502D03*
X439962Y1006094D03*
X443662D03*
X445511Y1009298D03*
X438113D03*
X441813D03*
X445512Y1002889D03*
X438113D03*
X441813D03*
X439962Y999685D03*
X443662D03*
X451062Y1006094D03*
X449213Y1009298D03*
Y1002889D03*
X451062Y999685D03*
X439962Y1012502D03*
X443662D03*
X451062D03*
X447362Y1025319D03*
Y1018911D03*
Y1031728D03*
X445511Y1022115D03*
X438113D03*
X441813D03*
X445512Y1015706D03*
X438113D03*
X439962Y1018911D03*
X441813Y1015706D03*
X443662Y1018911D03*
Y1025319D03*
X439962D03*
X445511Y1028524D03*
X441813D03*
X438113D03*
X449213Y1022115D03*
X451062Y1018911D03*
X449213Y1015706D03*
X451062Y1025319D03*
X449213Y1028524D03*
X439962Y1031728D03*
X443662D03*
X451062D03*
X447360Y1038136D03*
X452911Y1041340D03*
X451061Y1044544D03*
X449211Y1047749D03*
X452911D03*
X439962Y1038137D03*
X443662D03*
X438112Y1041340D03*
X439961Y1044544D03*
X441812Y1041340D03*
X443661Y1044544D03*
X447361D03*
X445511Y1041340D03*
X445512Y1034932D03*
X438113D03*
X441813D03*
X451062Y1038137D03*
X449211Y1041340D03*
X449213Y1034932D03*
X445510Y1047749D03*
X441812D03*
X438112D03*
X447361Y1057361D03*
Y1050952D03*
X452911Y1060565D03*
X447361Y1063770D03*
X449211Y1054157D03*
X449213Y1060565D03*
X438112D03*
Y1054157D03*
X439961Y1057361D03*
X441812Y1054157D03*
Y1060565D03*
X443661Y1057361D03*
X445511Y1060565D03*
Y1054157D03*
X439961Y1050952D03*
X443661D03*
X439961Y1063770D03*
X443661D03*
X451061D03*
X452911Y1054157D03*
X451062Y1050952D03*
X454762D03*
Y1057361D03*
X451062D03*
X451061Y1076587D03*
X452911Y1073383D03*
X447361Y1076587D03*
Y1070178D03*
X449211Y1073383D03*
X452911Y1079791D03*
X449211D03*
X439961Y1076587D03*
Y1070178D03*
X441812Y1073383D03*
X438112D03*
X443661Y1070178D03*
Y1076587D03*
X445511Y1073383D03*
X441812Y1066974D03*
X438112D03*
X445511D03*
X441812Y1079791D03*
X438112D03*
X445511D03*
X452911Y1066974D03*
X449211D03*
X451062Y1070178D03*
X447361Y1082995D03*
X452911Y1092608D03*
X451062Y1089404D03*
X449212Y1086200D03*
X451062Y1095813D03*
X452911Y1086200D03*
X443661Y1082995D03*
X439961D03*
X441812Y1086200D03*
X445511D03*
X439961Y1089404D03*
X441812Y1092608D03*
X438112D03*
X443661Y1089404D03*
X445511Y1092608D03*
X447361Y1089404D03*
X438112Y1086200D03*
X449211Y1092608D03*
X439961Y1095813D03*
X443661D03*
X447361D03*
X451060Y1082995D03*
X447361Y1108630D03*
Y1102221D03*
X452911Y1099017D03*
X441812Y1105426D03*
X438112D03*
X439961Y1108630D03*
X443661D03*
X445511Y1105426D03*
X439961Y1102221D03*
X441812Y1099017D03*
X438112D03*
X443661Y1102221D03*
X445511Y1099017D03*
X452912Y1105426D03*
X451061Y1108630D03*
X449212Y1105426D03*
X451061Y1102221D03*
X449212Y1099017D03*
X441812Y1111834D03*
X438112D03*
X445511D03*
X452912D03*
X449212D03*
X447361Y1121447D03*
Y1115039D03*
Y1127856D03*
X438112Y1124651D03*
X439961Y1121447D03*
X441812Y1124651D03*
X445511D03*
X443661Y1121447D03*
X438112Y1118243D03*
X441812D03*
X439961Y1115039D03*
X445511Y1118243D03*
X443661Y1115039D03*
X452912Y1124651D03*
Y1118243D03*
X451061Y1121447D03*
X449212Y1124651D03*
Y1118243D03*
X451061Y1115039D03*
X439961Y1127856D03*
X443661D03*
X451061D03*
X447361Y1134264D03*
X441812Y1137769D03*
X438112D03*
X445511D03*
X443661Y1134264D03*
X441812Y1131060D03*
X439961Y1134264D03*
X438112Y1131060D03*
X445511D03*
X452912Y1137769D03*
Y1131060D03*
X449212Y1137769D03*
Y1131060D03*
X451061Y1134264D03*
X461729Y851380D03*
X458029D03*
X454328D03*
X456179Y841467D03*
X463579D03*
X469129Y851380D03*
X465429D03*
X459878Y848176D03*
X467278D03*
X467279Y841467D03*
X463578Y848176D03*
X459879Y841467D03*
X458027Y844971D03*
X454327D03*
X469127D03*
X465427D03*
X461727D03*
X456178Y848176D03*
X456179Y854584D03*
X463579D03*
X461729Y864197D03*
X458029D03*
X454329D03*
X469129D03*
X465429D03*
X456179Y867401D03*
X463579D03*
X467278D03*
X459878D03*
Y860993D03*
X467278D03*
Y854584D03*
X465429Y857789D03*
X459878Y854584D03*
X458029Y857789D03*
X469129D03*
X463578Y860993D03*
X461729Y857789D03*
X456178Y860993D03*
X454329Y857789D03*
X461729Y877014D03*
X458029D03*
X456179Y880219D03*
X454329Y877014D03*
X463579Y880219D03*
X469129Y877014D03*
X465429D03*
X469129Y870606D03*
X463578Y873810D03*
X461729Y870606D03*
X456178Y873810D03*
X454329Y870606D03*
X465429D03*
X458029D03*
X469129Y883423D03*
X467278Y880219D03*
X461729Y883423D03*
X459878Y880219D03*
X454329Y883423D03*
X465429D03*
X458029D03*
X467278Y873810D03*
X459878D03*
X461729Y889832D03*
X458029D03*
X456179Y893036D03*
X454329Y889832D03*
X463579Y893036D03*
X469129Y896240D03*
Y889832D03*
X465429D03*
X463578Y886627D03*
X456178D03*
X459878D03*
X467278D03*
X459878Y899445D03*
X467278D03*
X454329Y896240D03*
X459878Y893036D03*
X461729Y896240D03*
X467278Y893036D03*
X456178Y899445D03*
X458029Y896240D03*
X463578Y899445D03*
X465429Y896240D03*
X470978Y899445D03*
X463578Y905853D03*
X470980Y912262D03*
X461729Y902649D03*
X458029D03*
X456178Y912262D03*
Y905853D03*
X454329Y902649D03*
X465429D03*
Y909057D03*
Y915466D03*
X469129Y902649D03*
X454329Y909057D03*
X470978Y918670D03*
X467278Y912262D03*
X469129Y915466D03*
X458029Y909057D03*
X459878Y905853D03*
X461729Y915466D03*
X467278Y905853D03*
X461729Y909057D03*
X458029Y915466D03*
X459878Y918670D03*
X463578Y912262D03*
X459878D03*
X469129Y909057D03*
X454103Y931359D03*
Y933659D03*
X461729Y921875D03*
X456178Y918670D03*
X467278D03*
X454329Y921875D03*
X468236Y928349D03*
X465936D03*
X463636D03*
X461336D03*
X459036D03*
X469129Y921875D03*
X463578Y918670D03*
X465429Y921875D03*
X458029D03*
X462261Y942152D03*
X464561D03*
X466861D03*
X454423Y949139D03*
X469251Y942246D03*
X453585Y942238D03*
Y939938D03*
Y944538D03*
X454393Y963829D03*
Y966129D03*
X463874Y956540D03*
X466272D03*
X454423Y951439D03*
X453403Y956999D03*
X461424Y956620D03*
X458404D03*
X453403Y959299D03*
X468904Y956620D03*
X466272Y971100D03*
X463874Y971140D03*
X454263Y981209D03*
Y978909D03*
X468904Y971100D03*
X458404D03*
X461424Y971140D03*
X453403Y973099D03*
Y970799D03*
X454463Y995299D03*
Y992999D03*
X466272Y985580D03*
X463874D03*
X453403Y986899D03*
X461424Y985580D03*
X458404D03*
X453403Y984599D03*
X468904Y985580D03*
X453403Y998399D03*
X466272Y1014540D03*
X463874D03*
X454443Y1009409D03*
Y1007109D03*
X466272Y1000060D03*
X463874D03*
X468895Y1014550D03*
X453403Y1012199D03*
X458404Y1000080D03*
X461424D03*
X453403Y1000699D03*
X468904Y1000080D03*
X458404Y1014540D03*
X461295Y1014510D03*
X453403Y1014499D03*
X454434Y1022186D03*
Y1019886D03*
X465680Y1028855D03*
X463180D03*
X460680D03*
X458180D03*
X457942Y1031909D03*
X467711Y1047750D03*
X460311D03*
Y1041340D03*
X467372Y1036874D03*
X465861Y1044544D03*
X456611Y1047749D03*
X464011D03*
X471411Y1041340D03*
X467711D03*
X454762Y1044544D03*
Y1038136D03*
X460971Y1037069D03*
X463271D03*
X458671D03*
X457942Y1034409D03*
X456611Y1041340D03*
X464011D03*
X462162Y1044544D03*
X458462D03*
X464011Y1054157D03*
X465860Y1050952D03*
X456611Y1060565D03*
X462161Y1057361D03*
X456611Y1054157D03*
X462162Y1050952D03*
X465862Y1057361D03*
X458462Y1063770D03*
X465862D03*
X462161D03*
X460312Y1054157D03*
X458462Y1057361D03*
X467712Y1054157D03*
Y1060565D03*
X454761Y1063770D03*
X464012Y1060565D03*
X458460Y1050952D03*
X460311Y1060565D03*
X454761Y1076587D03*
X456611Y1073383D03*
X454762Y1070178D03*
X462162D03*
X467711Y1073383D03*
Y1066974D03*
X456612Y1079791D03*
X467711D03*
X460311Y1073383D03*
X458460Y1070178D03*
X460311Y1066974D03*
X464011D03*
X465860Y1070178D03*
X469560D03*
X464012Y1079791D03*
X460312D03*
X462162Y1076587D03*
X456611Y1066974D03*
X465862Y1076587D03*
X464011Y1073383D03*
X458462Y1076587D03*
X458461Y1082995D03*
X456611Y1086200D03*
X460311Y1092608D03*
X464011Y1086200D03*
X467712D03*
Y1092608D03*
X465862Y1082995D03*
X462162D03*
X462161Y1095812D03*
X458461D03*
X465861Y1089403D03*
X456612Y1092607D03*
X454761Y1089403D03*
X460311Y1086200D03*
X454760Y1082995D03*
X465861Y1095812D03*
X464012Y1092607D03*
X454761Y1095812D03*
X458461Y1089403D03*
X462161D03*
X460312Y1105426D03*
X458462Y1102221D03*
X456611Y1099017D03*
X464012Y1105426D03*
Y1099017D03*
X462162Y1108630D03*
X465861D03*
Y1102221D03*
X464012Y1111834D03*
X467711Y1105426D03*
Y1111834D03*
Y1099017D03*
X462162Y1102221D03*
X458461Y1108630D03*
X456612Y1105426D03*
X454761Y1108630D03*
Y1102221D03*
X460312Y1111834D03*
X456611D03*
X460312Y1099016D03*
X458462Y1121447D03*
Y1115039D03*
X467712Y1124651D03*
X467711Y1118243D03*
X465862Y1121447D03*
Y1115039D03*
X458462Y1127856D03*
X464012Y1124651D03*
X462161Y1121447D03*
X460312Y1124651D03*
X456611D03*
X454761Y1121447D03*
X464011Y1118243D03*
X462161Y1115039D03*
X460312Y1118243D03*
X456611D03*
X454761Y1115039D03*
X462161Y1127856D03*
X454761D03*
X465861D03*
X458462Y1134264D03*
X464012Y1137469D03*
X460312D03*
X456612D03*
X464012Y1131060D03*
X462161Y1134264D03*
X460312Y1131060D03*
X456611D03*
X454761Y1134264D03*
X462161Y1140973D03*
X458461D03*
X454761D03*
X467712Y1137469D03*
X465861Y1134264D03*
X467712Y1131060D03*
X465861Y1140973D03*
X478379Y841467D03*
X470979D03*
X476529Y851380D03*
X480229D03*
X472829D03*
X483929D03*
X474678Y848176D03*
X482078D03*
X483927Y844971D03*
X480227D03*
X476527D03*
X470978Y848176D03*
X482079Y841467D03*
X478378Y848176D03*
X474679Y841467D03*
X472827Y844971D03*
X480229Y864197D03*
X478379Y854584D03*
X476529Y864197D03*
X470979Y854584D03*
X472829Y864197D03*
X483929D03*
X478379Y867401D03*
X470979D03*
X474678D03*
X482078D03*
X474678Y860993D03*
X482078D03*
Y854584D03*
X480229Y857789D03*
X474678Y854584D03*
X472829Y857789D03*
X483929D03*
X478378Y860993D03*
X476529Y857789D03*
X470978Y860993D03*
X480229Y877014D03*
X478379Y880219D03*
X476529Y877014D03*
X472829D03*
X472828Y870606D03*
X470979Y880219D03*
Y873810D03*
X483929Y877014D03*
X480229Y870606D03*
X476529D03*
X478378Y873810D03*
X483929Y870606D03*
X474678Y880219D03*
X476529Y883423D03*
X482078Y880219D03*
X483929Y883423D03*
X472829D03*
X480229D03*
X474678Y873810D03*
X482078D03*
X480228Y896240D03*
X480229Y889832D03*
X478379Y893036D03*
X470979D03*
X476529Y889832D03*
X472829D03*
X483929D03*
X474678Y899445D03*
X482078D03*
X474678Y893036D03*
X472829Y896240D03*
X482078Y893036D03*
X483929Y896240D03*
X470978Y886627D03*
X478378D03*
Y899445D03*
X474678Y886627D03*
X482078D03*
X476529Y896240D03*
Y915466D03*
X478380Y912262D03*
X478379Y918670D03*
X480229Y902649D03*
X474678Y912262D03*
Y905853D03*
X483929Y909057D03*
X482079Y912262D03*
X483928Y902649D03*
X483929Y915466D03*
X480229D03*
X472828D03*
X472829Y902649D03*
X480228Y909057D03*
X482078Y905853D03*
X476529Y902649D03*
X470978Y905853D03*
X478378D03*
X472829Y909057D03*
X476529D03*
X480229Y928283D03*
X478378Y931488D03*
Y925079D03*
X482078D03*
X476285Y930126D03*
X480229Y921875D03*
X476528D03*
X474678Y918670D03*
X483929Y928283D03*
X482078Y918670D03*
X483928Y921875D03*
X482079Y931488D03*
X472829Y921875D03*
X470536Y928349D03*
X478378Y937896D03*
X480229Y941100D03*
X476285Y934726D03*
X476180Y945355D03*
Y947655D03*
X478378Y944304D03*
X480229Y934691D03*
X483928Y941100D03*
X482079Y944304D03*
X482078Y937896D03*
X483928Y947509D03*
X483929Y934691D03*
X480229Y947509D03*
X471550Y942152D03*
X473851Y942246D03*
X476285Y962326D03*
Y960026D03*
Y964626D03*
X483928Y960326D03*
X482078Y957122D03*
X482079Y950713D03*
X483929Y966735D03*
X478378Y963530D03*
X483929Y953917D03*
X480228Y960326D03*
X478378Y950713D03*
X480229Y953917D03*
X478378Y957122D03*
X471404Y956620D03*
X480229Y966735D03*
X482078Y963529D03*
X476285Y966926D03*
X476192Y977670D03*
X476335Y980737D03*
X482079Y969939D03*
X483928Y979552D03*
X482078Y976347D03*
X483929Y973143D03*
X482078Y982756D03*
X478379Y969939D03*
X476285Y973826D03*
Y971526D03*
X471404Y971100D03*
X473904D03*
X480229Y979552D03*
X478378Y982756D03*
X480229Y973143D03*
X478378Y976347D03*
X476285Y996826D03*
Y994526D03*
Y989926D03*
Y987626D03*
X471404Y985580D03*
X476295Y1010500D03*
X476285Y1012926D03*
Y1006026D03*
Y1003726D03*
X471204Y1014540D03*
X484361Y999684D03*
X482512Y1009297D03*
X482511Y1002888D03*
X484362Y1012501D03*
X480662Y999684D03*
X478811Y1002888D03*
Y1009297D03*
X480662Y1012501D03*
X484362Y1006093D03*
X471404Y1000080D03*
X476275Y1022636D03*
X476285Y1017526D03*
X482511Y1028523D03*
Y1022114D03*
X484361Y1018910D03*
Y1031727D03*
X484362Y1025318D03*
X480662Y1031727D03*
X482511Y1015705D03*
X480661Y1018910D03*
X478811Y1022114D03*
Y1028523D03*
Y1015705D03*
X476325Y1031795D03*
Y1027195D03*
Y1029495D03*
X470724Y1028827D03*
X480662Y1025318D03*
X471282Y1036526D03*
X473507Y1035928D03*
X475111Y1041340D03*
X482511D03*
X482512Y1034931D03*
X484361Y1038136D03*
X471411Y1047749D03*
X482511D03*
X484362Y1044544D03*
X475111Y1047749D03*
X469562Y1044544D03*
X478811Y1034931D03*
X480662Y1038136D03*
X478811Y1041340D03*
X480662Y1044544D03*
X473262D03*
X476962D03*
X478811Y1047749D03*
X480662Y1050952D03*
X475111Y1060565D03*
X471411Y1054157D03*
X484361Y1057361D03*
X482511Y1060565D03*
X484362Y1050952D03*
Y1063770D03*
X473261Y1057361D03*
X471412Y1060565D03*
X475112Y1054157D03*
X469562Y1063770D03*
X469561Y1057361D03*
X473262Y1063770D03*
X469561Y1050952D03*
X473262D03*
X482511Y1054157D03*
X480662Y1063770D03*
X480661Y1057361D03*
X478812Y1060565D03*
X476962Y1063770D03*
Y1057361D03*
X478812Y1054157D03*
X476961Y1050952D03*
X478811Y1066974D03*
X475111D03*
X473262Y1070178D03*
X478811Y1073383D03*
X484361Y1076587D03*
X484362Y1070178D03*
X482512Y1066974D03*
X478812Y1079791D03*
X475111D03*
X482511D03*
X471411Y1066974D03*
X476962Y1076587D03*
X480662D03*
Y1070178D03*
X476962D03*
X473262Y1076587D03*
X469562D03*
X471411Y1073383D03*
Y1079791D03*
X475111Y1073383D03*
X482511D03*
X480662Y1082995D03*
X476962Y1089404D03*
X473262Y1082995D03*
X469561Y1089404D03*
X482512Y1086200D03*
X484362Y1089404D03*
X480661Y1095813D03*
X469562D03*
X484362D03*
Y1082995D03*
X473262Y1095813D03*
X469562Y1082995D03*
X480662Y1089404D03*
X478812Y1092607D03*
X475112D03*
X473261Y1089403D03*
X471412Y1086199D03*
X476961Y1082994D03*
X482512Y1092607D03*
X476961Y1095812D03*
X471412Y1092607D03*
X475112Y1086199D03*
X478812D03*
X480662Y1108630D03*
X478811Y1099017D03*
X473262Y1108630D03*
X476962Y1102221D03*
X475112Y1099017D03*
X471411D03*
X469562Y1102221D03*
X482511Y1105426D03*
Y1111834D03*
X484362Y1108630D03*
X475111Y1111834D03*
X471411D03*
X478811Y1105426D03*
X469562Y1108630D03*
X473262Y1102221D03*
X482511Y1099017D03*
X478811Y1111834D03*
X476962Y1108630D03*
X471411Y1105426D03*
X475111D03*
X484362Y1102221D03*
X480662D03*
X480661Y1115039D03*
X478811Y1118243D03*
X476961Y1115039D03*
X475111Y1118243D03*
X471411D03*
X469561Y1115039D03*
X482511Y1118243D03*
X476961Y1127856D03*
X469562D03*
X484361D03*
X484362Y1115039D03*
X473262D03*
X484362Y1121447D03*
X480662Y1127856D03*
X476962Y1121447D03*
X473262Y1127856D03*
X469562Y1121447D03*
X482511Y1124651D03*
X478811D03*
X475111D03*
X471411D03*
X473262Y1121447D03*
X480662D03*
X478811Y1131060D03*
X476961Y1140973D03*
X475111Y1131060D03*
X471412Y1137469D03*
Y1131060D03*
X469561Y1140973D03*
X473261Y1134264D03*
X482511Y1131060D03*
X484361Y1140973D03*
X484362Y1134264D03*
X482512Y1137469D03*
X476962Y1134264D03*
X475112Y1137469D03*
X480661Y1140973D03*
X478812Y1137469D03*
X473261Y1140973D03*
X480662Y1134264D03*
X469561D03*
X484333Y1575686D03*
Y1580678D03*
X477229D03*
X472273D03*
Y1575686D03*
X477229D03*
X476451Y1578182D03*
X485111D03*
X473051D03*
X482529Y1599884D03*
X477573D03*
X484333Y1587598D03*
Y1592590D03*
X472273D03*
X477229D03*
Y1587598D03*
X472273D03*
X476451Y1590094D03*
X485111D03*
X473051D03*
X482529Y1616788D03*
X477573D03*
Y1611796D03*
X482529D03*
X477573Y1604876D03*
X482529D03*
X478351Y1614292D03*
X481751D03*
X478351Y1602380D03*
X481751D03*
X493179Y841467D03*
X485779D03*
X500579D03*
X495029Y851380D03*
X491329D03*
X487629D03*
X498729D03*
X489478Y848176D03*
X496878D03*
X493178D03*
X489478Y841467D03*
X487627Y844971D03*
X500578Y848176D03*
X496878Y841467D03*
X495027Y844971D03*
X491327D03*
X485778Y848176D03*
X498727Y844971D03*
X495029Y864197D03*
X493179Y854584D03*
X491329Y864197D03*
X487629D03*
X485779Y854584D03*
X498729Y864197D03*
X500579Y854584D03*
X493179Y867401D03*
X485779D03*
X500579D03*
X489478D03*
X496878D03*
X489478Y860993D03*
X496878D03*
X489478Y854584D03*
X487629Y857789D03*
X500578Y860993D03*
X498729Y857789D03*
X495029D03*
X491329D03*
X485778Y860993D03*
X496878Y854584D03*
X493178Y860993D03*
X495029Y877014D03*
X493179Y880219D03*
X491329Y877014D03*
X487629D03*
X485779Y880219D03*
X500579D03*
X498729Y877014D03*
X487629Y870606D03*
X495029D03*
X485778Y873810D03*
X491329Y870606D03*
X493178Y873810D03*
X498729Y870606D03*
X500578Y873810D03*
X489478Y880219D03*
X491329Y883423D03*
X496878Y880219D03*
X498729Y883423D03*
X487629D03*
X495029D03*
X496878Y873810D03*
X489478D03*
X489479Y893036D03*
X495029Y889832D03*
X491329D03*
X487629D03*
X498729D03*
X500579Y893036D03*
X498729Y896240D03*
X496879Y899445D03*
X489478D03*
X500578D03*
X485778D03*
X493178D03*
Y893036D03*
X496878D03*
X485778D03*
X491329Y896240D03*
X487629D03*
X495029D03*
X485778Y886627D03*
X493178D03*
X500578D03*
X489478D03*
X496878D03*
Y912262D03*
X495029Y909057D03*
X489478Y912262D03*
Y905853D03*
X495029Y902649D03*
X493179Y905853D03*
X485778D03*
X498728Y915466D03*
X485778Y912262D03*
X487629Y909057D03*
X493178Y912262D03*
X491329Y909057D03*
X500578Y912262D03*
X498729Y909057D03*
Y902649D03*
X487629D03*
X491329D03*
X487629Y915466D03*
X500578Y905853D03*
X495029Y915466D03*
X496878Y905853D03*
X491329Y915466D03*
X495028Y928283D03*
X493179Y925079D03*
X489478D03*
Y918670D03*
X485778Y925079D03*
X496879Y918670D03*
X495029Y921875D03*
X496878Y931488D03*
X489478D03*
X500578D03*
X498729Y921875D03*
X500578Y918670D03*
X498729Y928283D03*
X496878Y925079D03*
X500578D03*
X491329Y921875D03*
X493178Y918670D03*
X485778Y931488D03*
X491329Y928283D03*
X493178Y931488D03*
X487629Y928283D03*
Y921875D03*
X485778Y918670D03*
X496879Y937896D03*
X495029Y941100D03*
X493179Y944304D03*
X489478D03*
Y937896D03*
X485778Y944304D03*
X498729Y934691D03*
X495028Y947509D03*
X498729D03*
Y941100D03*
X500578Y937896D03*
X496878Y944304D03*
X500578D03*
X487629Y947509D03*
X491329D03*
X487629Y941100D03*
X485778Y937896D03*
X491329Y941100D03*
X493178Y937896D03*
X487629Y934691D03*
X495029D03*
X491329D03*
X496879Y957122D03*
X495029Y960326D03*
X489478Y957122D03*
Y950713D03*
X496878D03*
X498729Y953917D03*
X495028Y966735D03*
X493179Y963530D03*
X485778D03*
X489478D03*
X500579D03*
X500578Y950713D03*
X487629Y966735D03*
X491329D03*
X498729D03*
X496878Y963530D03*
X485778Y950713D03*
X493178D03*
X491329Y960326D03*
X493178Y957122D03*
X487629Y960326D03*
X485778Y957122D03*
X500578D03*
X498729Y960326D03*
X495029Y953917D03*
X487629D03*
X491329D03*
X496879Y976347D03*
X496878Y969939D03*
X489478Y976347D03*
Y969939D03*
X495029Y979552D03*
X498728Y973143D03*
X493179Y982756D03*
X489478D03*
X485778D03*
X487629Y979552D03*
X485778Y976347D03*
X491329Y979552D03*
X493178Y976347D03*
X500578Y982756D03*
X496878D03*
X498729Y979552D03*
X500578Y976347D03*
X495029Y973143D03*
X487629D03*
X491329D03*
X485778Y969939D03*
X493178D03*
X500578D03*
X497311Y1009297D03*
X497312Y1002888D03*
X495462Y999684D03*
X489911Y1009297D03*
X489912Y1002888D03*
X491761Y1006093D03*
X488062D03*
X499161D03*
X495461Y1012501D03*
X501011Y1002888D03*
X499162Y999684D03*
Y1012501D03*
X501011Y1009297D03*
X495462Y1006093D03*
X486211Y1002888D03*
X493611D03*
X488062Y999684D03*
X491762D03*
X491761Y1012501D03*
X493611Y1009297D03*
X488062Y1012501D03*
X486211Y1009297D03*
X497311Y1028523D03*
X489911D03*
Y1022114D03*
Y1015705D03*
X497311Y1022114D03*
X495462Y1018910D03*
X493612Y1015705D03*
X486211D03*
X501012D03*
X499161Y1025318D03*
X495461Y1031727D03*
X497311Y1015705D03*
X499162Y1031727D03*
X501011Y1028523D03*
Y1022114D03*
X499162Y1018910D03*
X488062Y1031727D03*
X486211Y1028523D03*
X491762Y1031727D03*
X493611Y1028523D03*
X486211Y1022114D03*
X488062Y1018910D03*
X493611Y1022114D03*
X491762Y1018910D03*
X488062Y1025318D03*
X495462D03*
X491762D03*
X497312Y1041340D03*
X489911D03*
Y1034931D03*
X495462Y1038136D03*
X493612Y1034931D03*
X486211D03*
X499161Y1044544D03*
X489911Y1047749D03*
X497311D03*
X501011Y1041340D03*
X499162Y1038136D03*
X501011Y1047749D03*
Y1034931D03*
X497311D03*
X486211Y1047749D03*
X493611D03*
X486211Y1041340D03*
X488062Y1038136D03*
X493611Y1041340D03*
X491762Y1038136D03*
X488062Y1044544D03*
X495462D03*
X491762D03*
X497311Y1060565D03*
X495462Y1057361D03*
X489911Y1060565D03*
Y1054157D03*
X495461Y1050952D03*
X493611Y1054157D03*
X486211D03*
X499162Y1063770D03*
X501011Y1060565D03*
X499162Y1057361D03*
Y1050952D03*
X501011Y1054157D03*
X497311D03*
X486211Y1060565D03*
X488062Y1057361D03*
X493611Y1060565D03*
X491762Y1057361D03*
X488062Y1050952D03*
X491762D03*
X488062Y1063770D03*
X495462D03*
X491762D03*
X495462Y1076587D03*
X493612Y1073383D03*
X489911Y1066974D03*
X486211Y1073383D03*
X497311Y1066974D03*
X495461Y1070178D03*
X489911Y1073383D03*
X497312Y1079791D03*
X489911D03*
X499162Y1070178D03*
X501011Y1066974D03*
Y1079791D03*
X499162Y1076587D03*
X497311Y1073383D03*
X501011D03*
X486211Y1079791D03*
X488062Y1076587D03*
X493611Y1079791D03*
X491762Y1076587D03*
X488062Y1070178D03*
X486211Y1066974D03*
X491762Y1070178D03*
X493611Y1066974D03*
X497311Y1086200D03*
X493612Y1092608D03*
X489911D03*
Y1086200D03*
X486211Y1092608D03*
X495461Y1089404D03*
X499161Y1082995D03*
X495462Y1095813D03*
X499162D03*
X491762D03*
Y1089404D03*
X493611Y1086200D03*
X499162Y1089404D03*
X501011Y1086200D03*
X488062Y1089404D03*
X486211Y1086200D03*
X497311Y1092608D03*
X495462Y1082995D03*
X501011Y1092608D03*
X488062Y1082995D03*
X491762D03*
X488062Y1095813D03*
X497312Y1105426D03*
X493611D03*
X491762Y1102221D03*
X488061D03*
X486211Y1105426D03*
X486212Y1099017D03*
X499161Y1108630D03*
Y1102221D03*
X497312Y1111834D03*
X489911D03*
Y1099017D03*
X495462Y1102221D03*
X501011Y1099017D03*
X493611D03*
X497311D03*
X495462Y1108630D03*
X489911Y1105426D03*
X486211Y1111834D03*
X493611D03*
X491762Y1108630D03*
X488062D03*
X501012Y1105426D03*
Y1111833D03*
X497311Y1118243D03*
X495462Y1121447D03*
X493612Y1118243D03*
X489911D03*
X486211D03*
X501011D03*
X499161Y1115039D03*
X491761Y1127856D03*
X499161D03*
X491762Y1115039D03*
X495462D03*
X488062Y1127856D03*
X499162Y1121447D03*
X495462Y1127856D03*
X491762Y1121447D03*
X489911Y1124651D03*
X486211D03*
X501011D03*
X497311D03*
X493611D03*
X488062Y1115039D03*
Y1121447D03*
X497311Y1131060D03*
X493611D03*
X489911D03*
X486211D03*
X491761Y1140973D03*
X501011Y1131060D03*
X499161Y1140973D03*
X493612Y1137469D03*
X488061Y1140973D03*
X501012Y1137469D03*
X495461Y1140973D03*
X491762Y1134264D03*
X489912Y1137469D03*
X486212D03*
X499162Y1134264D03*
X497312Y1137469D03*
X495462Y1134264D03*
X488062D03*
X501349Y1580678D03*
X496393D03*
Y1575686D03*
X501349D03*
X489289D03*
Y1580678D03*
X500571Y1578182D03*
X488511D03*
X497171D03*
X501693Y1599884D03*
X494589D03*
X489633D03*
X501349Y1592590D03*
X496393D03*
X501349Y1587598D03*
X496393D03*
X489289D03*
Y1592590D03*
X500571Y1590094D03*
X488511D03*
X497171D03*
X501693Y1611796D03*
Y1604876D03*
Y1616788D03*
X489633Y1611796D03*
X494589Y1604876D03*
X489633D03*
X494589Y1611796D03*
X489633Y1616788D03*
X494589D03*
X490411Y1614292D03*
X493811D03*
X490411Y1602380D03*
X493811D03*
X497441Y1675383D03*
Y1679920D03*
Y1684454D03*
Y1689556D03*
Y1694093D03*
Y1698627D03*
Y1703729D03*
Y1708266D03*
Y1712800D03*
Y1726974D03*
Y1722440D03*
Y1717903D03*
X507979Y841467D03*
X515379D03*
X506129Y851380D03*
X502429D03*
X513529D03*
X509829D03*
X517229D03*
X511678Y848176D03*
X504278D03*
X517227Y844971D03*
X511679Y841467D03*
X509827Y844971D03*
X504279Y841467D03*
X515378Y848176D03*
X513527Y844971D03*
X507978Y848176D03*
X506127Y844971D03*
X502427D03*
X513529Y864197D03*
X509829D03*
X506129D03*
X502429D03*
X507979Y854584D03*
X515379D03*
X517229Y864197D03*
X507979Y867401D03*
X515379D03*
X511678D03*
X504278D03*
X511678Y860993D03*
X504278D03*
X517229Y857789D03*
X513529D03*
X509829D03*
X506129D03*
X515378Y860993D03*
X511678Y854584D03*
X507978Y860993D03*
X504278Y854584D03*
X502429Y857789D03*
X509829Y877014D03*
X507979Y880219D03*
X502429Y877014D03*
X513529D03*
X506129D03*
X515379Y880219D03*
X517229Y877014D03*
Y870606D03*
X502429D03*
X509829D03*
X513529D03*
X515378Y873810D03*
X506129Y870606D03*
X507978Y873810D03*
X511678Y880219D03*
X513529Y883423D03*
X504278Y880219D03*
X506129Y883423D03*
X509829D03*
X517229D03*
X502429D03*
X511678Y873810D03*
X504278D03*
X506129Y889832D03*
X502428Y896240D03*
X502429Y889832D03*
X513529D03*
X509829D03*
X506128Y896240D03*
X504279Y893036D03*
X515379D03*
X517229Y889832D03*
X507978Y899445D03*
X515378D03*
X511678D03*
Y893036D03*
X507978D03*
X509829Y896240D03*
X517229D03*
X513529D03*
X504278Y899445D03*
X515378Y886627D03*
X507978D03*
X511678D03*
X504278D03*
X511678Y905853D03*
X509829Y909057D03*
X507979Y912262D03*
X502429Y909057D03*
Y902649D03*
X509828D03*
X515378Y912262D03*
Y905853D03*
X502429Y915466D03*
X506129D03*
X513529Y902649D03*
X517229D03*
X511678Y912262D03*
X513529Y909057D03*
X517229D03*
X513529Y915466D03*
X509829D03*
X517229D03*
X504278Y912262D03*
X506129Y909057D03*
Y902649D03*
X507978Y905853D03*
X504278D03*
X511678Y925079D03*
X509829Y928283D03*
X502429D03*
Y921875D03*
X509828D03*
X507978Y918670D03*
X515378Y925079D03*
Y918670D03*
X507979Y931488D03*
X515378D03*
X511678D03*
X513529Y928283D03*
X517229D03*
X506129D03*
Y921875D03*
X504278Y918670D03*
X513529Y921875D03*
X511678Y918670D03*
X517229Y921875D03*
X504278Y931488D03*
Y925079D03*
X507978D03*
X511678Y944304D03*
X509828Y941100D03*
X507978Y937896D03*
X506129Y934691D03*
X502429Y941100D03*
Y934691D03*
X515378Y944304D03*
Y937896D03*
X509829Y947509D03*
X502429D03*
X513529Y941100D03*
X511678Y937896D03*
X517229Y941100D03*
X513529Y934691D03*
X509829D03*
X517229D03*
X513529Y947509D03*
X517229D03*
X506129D03*
Y941100D03*
X504278Y937896D03*
X507978Y944304D03*
X504278D03*
X509828Y960326D03*
X507978Y957122D03*
X506129Y953917D03*
X502429Y960326D03*
Y953917D03*
X507979Y950713D03*
X515378Y957122D03*
Y950713D03*
X509829Y966735D03*
X502428D03*
X511678Y963530D03*
X504278D03*
X515378D03*
X511678Y950713D03*
X513529Y960326D03*
X511678Y957122D03*
X517229Y960326D03*
Y966735D03*
X513529D03*
X504278Y950713D03*
X513529Y953917D03*
X517229D03*
X509829D03*
X506129Y966735D03*
X504278Y957122D03*
X506129Y960326D03*
X507978Y963530D03*
Y976347D03*
X507979Y969939D03*
X502429Y979552D03*
Y973143D03*
X513529D03*
X509828Y979552D03*
X506129Y973143D03*
X515379Y976347D03*
X515378Y969939D03*
X517228Y973143D03*
X511678Y982756D03*
X515378D03*
X507978D03*
X504278D03*
Y976347D03*
X506129Y979552D03*
X513529D03*
X517229D03*
X511678Y976347D03*
X509829Y973143D03*
X511678Y969939D03*
X504278D03*
X510261Y999684D03*
X508411Y1002888D03*
X506562Y1006093D03*
X502862Y999684D03*
X502861Y1012501D03*
X508412Y1009297D03*
X510262Y1012501D03*
X515811Y1009297D03*
Y1002888D03*
X517662Y1006093D03*
X513962D03*
X510262D03*
X517662Y1012501D03*
X504711Y1002888D03*
X506561Y999684D03*
X513962Y1012501D03*
X512111Y1009297D03*
X506562Y1012501D03*
X504711Y1009297D03*
X517661Y999684D03*
X512111Y1002888D03*
X513962Y999684D03*
X508411Y1028523D03*
X502862Y1025318D03*
Y1018910D03*
X510261D03*
X508411Y1022114D03*
X506562Y1025318D03*
X504711Y1015705D03*
X515811Y1028523D03*
Y1022114D03*
X510262Y1031727D03*
X502862D03*
X515811Y1015705D03*
X512111D03*
X513962Y1031727D03*
X512111Y1028523D03*
X517662Y1031727D03*
X512111Y1022114D03*
X513962Y1018910D03*
X517662D03*
X513962Y1025318D03*
X510262D03*
X517662D03*
X508411Y1015705D03*
X506562Y1031727D03*
X504711Y1028523D03*
Y1022114D03*
X506562Y1018910D03*
X502862Y1044544D03*
Y1038136D03*
X512111Y1034931D03*
X510261Y1038136D03*
X508411Y1041340D03*
X506562Y1044544D03*
X515811Y1034931D03*
Y1041340D03*
X508411Y1047749D03*
X515811D03*
X504711Y1041340D03*
X506562Y1038136D03*
X512111Y1047749D03*
Y1041340D03*
X513962Y1038136D03*
X517662D03*
X504711Y1047749D03*
X510262Y1044544D03*
X508411Y1034931D03*
X513962Y1044544D03*
X517662D03*
X504711Y1034931D03*
X510262Y1057361D03*
X508411Y1060565D03*
X502862Y1057361D03*
Y1050952D03*
X512111Y1054157D03*
X510262Y1050952D03*
X515811Y1054157D03*
Y1060565D03*
X502862Y1063770D03*
X506562D03*
X512111Y1060565D03*
X513962Y1057361D03*
X517662D03*
X510262Y1063770D03*
X513962D03*
X517662D03*
X513962Y1050952D03*
X517662D03*
X504711Y1060565D03*
X506562Y1057361D03*
Y1050952D03*
X508411Y1054157D03*
X504711D03*
X510262Y1076587D03*
Y1070178D03*
X502862Y1076587D03*
Y1070178D03*
X512111Y1073383D03*
X508411Y1066974D03*
X515811Y1073383D03*
Y1066974D03*
X508411Y1079791D03*
X515811D03*
X517662Y1070178D03*
X513962D03*
X512111Y1066974D03*
X504711Y1079791D03*
X506562Y1076587D03*
Y1070178D03*
X504711Y1066974D03*
X512111Y1079791D03*
X513962Y1076587D03*
X517662D03*
X508411Y1073383D03*
X504711D03*
X512112Y1092608D03*
X510262Y1089404D03*
X508412Y1086200D03*
X506562Y1082995D03*
X502862Y1089404D03*
Y1082995D03*
X515812Y1092608D03*
X515811Y1086200D03*
X513961Y1095813D03*
X502862D03*
X517662D03*
X513962Y1089404D03*
X512111Y1086200D03*
X517662Y1089404D03*
X513962Y1082995D03*
X510262D03*
X517662D03*
X510262Y1095813D03*
X506561D03*
X506562Y1089404D03*
X504711Y1086200D03*
X508411Y1092608D03*
X504711D03*
X513962Y1108630D03*
Y1102221D03*
X512112Y1099017D03*
X508411D03*
X506562Y1108630D03*
X504711Y1099017D03*
X502862Y1102221D03*
X515811Y1105426D03*
Y1111834D03*
X517662Y1108630D03*
Y1102221D03*
X515811Y1099017D03*
X510262Y1102221D03*
X502861Y1108629D03*
X512112Y1105426D03*
X508412Y1111833D03*
X506561Y1102220D03*
X504712Y1111833D03*
Y1105426D03*
X510261Y1108630D03*
X512112Y1111833D03*
X508412Y1105426D03*
X513961Y1115039D03*
X512111Y1118243D03*
X508411D03*
X504711D03*
X510261Y1115039D03*
X515811Y1118243D03*
X513961Y1127856D03*
X506561D03*
X517662Y1115039D03*
Y1127856D03*
X513962Y1121447D03*
X510262Y1127856D03*
X506562Y1121447D03*
X502862Y1127856D03*
X515811Y1124651D03*
X512111D03*
X508411D03*
X504711D03*
X502862Y1115039D03*
X510262Y1121447D03*
X502862D03*
X517662D03*
X506561Y1115038D03*
X513961Y1140973D03*
X512111Y1131060D03*
X508411D03*
X504711D03*
X506561Y1140973D03*
X515811Y1131060D03*
X517661Y1140973D03*
X513962Y1134264D03*
X512112Y1137469D03*
X506562Y1134264D03*
X504712Y1137469D03*
X515812D03*
X510261Y1140973D03*
X508412Y1137469D03*
X502861Y1140973D03*
X510262Y1134264D03*
X502862D03*
X517662D03*
X508453Y1575686D03*
X513409D03*
X508453Y1580678D03*
X513409D03*
X512631Y1578182D03*
X509231D03*
X513753Y1599884D03*
X506649D03*
X508453Y1587598D03*
X513409D03*
X508453Y1592590D03*
X513409D03*
X512631Y1590094D03*
X509231D03*
X513753Y1616788D03*
Y1604876D03*
Y1611796D03*
X506649D03*
Y1604876D03*
Y1616788D03*
X514531Y1614292D03*
X502471D03*
X517931D03*
X505871D03*
X514531Y1602380D03*
X502471D03*
X517931D03*
X505871D03*
X513189Y1675383D03*
Y1679920D03*
X505315Y1679320D03*
X513189Y1684454D03*
Y1689556D03*
Y1694093D03*
Y1698627D03*
X505315Y1688391D03*
Y1693493D03*
Y1698030D03*
Y1683857D03*
X513189Y1703729D03*
Y1708266D03*
Y1712800D03*
X505315Y1707666D03*
Y1712203D03*
Y1702564D03*
X513189Y1726974D03*
Y1722440D03*
Y1717903D03*
X505315Y1730911D03*
Y1726377D03*
Y1721840D03*
Y1716737D03*
X528329Y844671D03*
X522779Y841467D03*
X528329Y851380D03*
X524629D03*
X520929D03*
X532029D03*
X519078Y848176D03*
X532028Y844671D03*
X526478Y848176D03*
X524627Y844971D03*
X519079Y841467D03*
X533878Y848176D03*
X530178D03*
X522778D03*
X520927Y844971D03*
X528329Y864197D03*
X524629D03*
X520929D03*
X530179Y860993D03*
Y854584D03*
X522779D03*
X532028Y857789D03*
X533879Y860993D03*
X530178Y867401D03*
X522779D03*
X533879D03*
X532029Y864197D03*
X533879Y854584D03*
X519078Y867401D03*
X526479D03*
Y860993D03*
X519078D03*
X528329Y857789D03*
X522778Y860993D03*
X520929Y857789D03*
X526478Y854584D03*
X524629Y857789D03*
X519078Y854584D03*
X528329Y877014D03*
X522779Y880219D03*
X520929Y877014D03*
X530179Y880219D03*
X524629Y877014D03*
X532029D03*
X533879Y880219D03*
Y873810D03*
X532028Y883423D03*
X524629Y870606D03*
X532029D03*
X520929D03*
X522778Y873810D03*
X528329Y870606D03*
X530178Y873810D03*
X519078Y880219D03*
X520929Y883423D03*
X526479Y880219D03*
X528329Y883423D03*
X524629D03*
X526479Y873810D03*
X519078D03*
X528329Y896240D03*
Y889832D03*
X524629D03*
X526479Y893036D03*
X524629Y896240D03*
X520929Y889832D03*
X532029D03*
Y896240D03*
X533879Y893036D03*
X522779Y899445D03*
X533879D03*
X526479D03*
X530178D03*
X519078D03*
Y893036D03*
X522778D03*
X520929Y896240D03*
X530178Y893036D03*
X522778Y886627D03*
X530179D03*
X526479D03*
X519078D03*
X533879D03*
X528329Y902649D03*
X522778Y912262D03*
X520928Y909057D03*
X519079Y905853D03*
X520929Y902649D03*
X528329Y915466D03*
X524628D03*
X532029D03*
X528329Y909057D03*
X533879Y912262D03*
X530179D03*
X532029Y909057D03*
X524629Y902649D03*
X532029D03*
X526479Y912262D03*
X524629Y909057D03*
X526479Y905853D03*
X533879D03*
X522778D03*
X530179D03*
X519078Y912262D03*
X520929Y915466D03*
X528329Y921875D03*
X520928Y928283D03*
X519079Y925079D03*
X522779Y918670D03*
X520929Y921875D03*
X522778Y931488D03*
X528329Y928283D03*
X533879Y918670D03*
X533878Y931488D03*
X526479D03*
X524629Y928283D03*
X530179Y931488D03*
X532029Y928283D03*
X524629Y921875D03*
X526479Y918670D03*
X532029Y921875D03*
X530179Y918670D03*
X526479Y925079D03*
X533879D03*
X522778D03*
X530179D03*
X519078Y931488D03*
Y918670D03*
X528329Y941100D03*
Y934691D03*
X524628D03*
X522779Y937896D03*
X520929Y941100D03*
X519079Y944304D03*
X520928Y947509D03*
X532029Y934691D03*
X533879Y937896D03*
X528329Y947509D03*
X524629Y941100D03*
X526479Y937896D03*
X532029Y941100D03*
X530179Y937896D03*
X524629Y947509D03*
X532029D03*
X519078Y937896D03*
X533879Y944304D03*
X520929Y934691D03*
X526479Y944304D03*
X530178D03*
X522778D03*
X528329Y960326D03*
Y953917D03*
X524629D03*
X522779Y957122D03*
X520929Y960326D03*
X522778Y950713D03*
X520928Y966735D03*
X526479Y963530D03*
X519079D03*
X533879Y957122D03*
X532029Y953917D03*
X533879Y950713D03*
X530178Y963530D03*
X528329Y966735D03*
X524629D03*
X532029D03*
X522778Y963530D03*
X526479Y950713D03*
X530178D03*
X532029Y960326D03*
X530178Y957122D03*
X524629Y960326D03*
X526479Y957122D03*
X533879Y963530D03*
X519078Y950713D03*
Y957122D03*
X520929Y953917D03*
X528329Y979552D03*
Y973143D03*
X522779Y976347D03*
X522778Y969939D03*
X524628Y973143D03*
X520929Y979552D03*
X533879Y976347D03*
X519079Y982756D03*
X533901Y980606D03*
X533879Y969939D03*
X532029Y973143D03*
X526479Y969939D03*
X530179D03*
X519078Y976347D03*
Y969939D03*
X520929Y973143D03*
X521361Y1012501D03*
Y999684D03*
X528762Y1006093D03*
Y999684D03*
X525061Y1006093D03*
X523211Y1009297D03*
X523212Y1002888D03*
X534311Y1009297D03*
Y1002888D03*
X532461Y1006093D03*
X528761Y1012501D03*
X521362Y1006093D03*
X525062Y1012501D03*
X532461D03*
X526911Y1009297D03*
X530611D03*
X519511D03*
X519513Y1002888D03*
X530611D03*
X532461Y999684D03*
X526911Y1002888D03*
X525062Y999684D03*
X528762Y1025318D03*
X523211Y1028523D03*
X525061Y1025318D03*
X528762Y1031727D03*
X521361D03*
X519512Y1015705D03*
X521362Y1018910D03*
X523211Y1022114D03*
X526912Y1015705D03*
X528762Y1018910D03*
X530611Y1015705D03*
X534311Y1028523D03*
X534310Y1022114D03*
X532461Y1025318D03*
X523211Y1015705D03*
X534311D03*
X525062Y1031727D03*
X526911Y1028523D03*
X532461Y1031727D03*
X530611Y1028523D03*
Y1022114D03*
X532461Y1018910D03*
X526911Y1022114D03*
X525062Y1018910D03*
X519511Y1028523D03*
Y1022114D03*
X521362Y1025318D03*
X528762Y1044544D03*
X525061D03*
X523212Y1041340D03*
X521362Y1038136D03*
X519512Y1034931D03*
X532462Y1044544D03*
X523211Y1047749D03*
X528762Y1038136D03*
X534311Y1041340D03*
Y1047749D03*
X526911Y1041340D03*
X525062Y1038136D03*
X530611Y1041340D03*
X532461Y1038136D03*
X526911Y1047749D03*
X530611D03*
X526911Y1034931D03*
X534311D03*
X523211D03*
X530611D03*
X519511Y1047749D03*
Y1041340D03*
X521362Y1044544D03*
X528762Y1057361D03*
Y1050952D03*
X523212Y1060565D03*
X521362Y1057361D03*
X521361Y1050952D03*
X519512Y1054157D03*
X528762Y1063770D03*
X525061D03*
X534311Y1060565D03*
X532462Y1063770D03*
X519511Y1060565D03*
X526911D03*
X525062Y1057361D03*
X530611Y1060565D03*
X532462Y1057361D03*
X525061Y1050952D03*
X532462Y1050953D03*
X523211Y1054157D03*
X521362Y1063770D03*
X534311Y1054157D03*
X526911D03*
X530611D03*
X528762Y1076587D03*
Y1070178D03*
X521362Y1076587D03*
X521361Y1070178D03*
X519512Y1073383D03*
X523211Y1066974D03*
X523212Y1079791D03*
X534311Y1066974D03*
Y1079791D03*
X530611D03*
X532462Y1076587D03*
X525062Y1070178D03*
X526911Y1066974D03*
X532462Y1070178D03*
X530611Y1066974D03*
X526911Y1079791D03*
X525062Y1076587D03*
X523211Y1073383D03*
X534311D03*
X526911D03*
X530611D03*
X519511Y1066974D03*
Y1079791D03*
X523211Y1086200D03*
X521361Y1089404D03*
X519511Y1092608D03*
X528762Y1089404D03*
Y1082995D03*
X525061D03*
X532462Y1082996D03*
X534311Y1086200D03*
X528761Y1095813D03*
X521362D03*
X532461D03*
X525062D03*
Y1089404D03*
X526911Y1086200D03*
X532462Y1089404D03*
X530611Y1086200D03*
X526911Y1092608D03*
X534310D03*
X523211D03*
X530611D03*
X519511Y1086200D03*
X521362Y1082995D03*
X526911Y1105426D03*
X521361Y1102221D03*
X519511Y1105426D03*
X519512Y1099017D03*
X532461Y1108630D03*
X530612Y1111834D03*
X523211D03*
X526911Y1099017D03*
X534311D03*
X532460Y1102221D03*
X521362Y1108630D03*
X525062D03*
X534311Y1111834D03*
X523211Y1105426D03*
X534311D03*
X528762Y1108630D03*
X519511Y1111834D03*
X526911D03*
X530611Y1099017D03*
X528762Y1102221D03*
X525062D03*
X523212Y1099017D03*
X530611Y1105426D03*
Y1124651D03*
Y1118243D03*
X528762Y1121447D03*
X523211Y1118243D03*
X521361Y1115039D03*
X519511Y1118243D03*
X532461Y1115039D03*
X528761Y1127856D03*
X521361D03*
X525062Y1115039D03*
X528762D03*
X526911Y1124651D03*
X521362Y1121447D03*
X525062Y1127856D03*
X523211Y1124651D03*
X519511D03*
X526911Y1118243D03*
X525062Y1121447D03*
X534311Y1118243D03*
X532461Y1121446D03*
X534311Y1124650D03*
X532461Y1127855D03*
X530612Y1137469D03*
Y1131060D03*
X526912D03*
X523211D03*
X519511D03*
X528761Y1134264D03*
X521361Y1140973D03*
X534311Y1131060D03*
X532462Y1134264D03*
X525061Y1140973D03*
X523212Y1137469D03*
X534312D03*
X526912D03*
X521362Y1134264D03*
X519512Y1137469D03*
X525062Y1134264D03*
X528761Y1140973D03*
X532461D03*
X532573Y1575686D03*
Y1580678D03*
X520513D03*
X525469D03*
X520513Y1575686D03*
X525469D03*
X524691Y1578182D03*
X533351D03*
X521291D03*
X525813Y1599884D03*
X530769D03*
X518709D03*
X532573Y1587598D03*
Y1592590D03*
X525469D03*
X520513D03*
Y1587598D03*
X525469D03*
X524691Y1590094D03*
X533351D03*
X521291D03*
X525813Y1611796D03*
X530769D03*
X525813Y1604876D03*
X530769D03*
Y1616788D03*
X525813D03*
X518709D03*
Y1604876D03*
Y1611796D03*
X526591Y1614292D03*
X529991D03*
X526591Y1602380D03*
X529991D03*
X528937Y1675383D03*
Y1679920D03*
X521063Y1679320D03*
X528937Y1684454D03*
Y1689556D03*
Y1694093D03*
Y1698627D03*
X521063Y1688391D03*
Y1693493D03*
Y1698030D03*
Y1683857D03*
X528937Y1703729D03*
Y1708266D03*
Y1712800D03*
X521063Y1707666D03*
Y1712203D03*
Y1702564D03*
X528937Y1726974D03*
Y1722440D03*
Y1717903D03*
X521063Y1730911D03*
Y1726377D03*
Y1721840D03*
Y1716737D03*
X537580Y848176D03*
X535729Y844671D03*
Y851380D03*
X543129D03*
X539429D03*
X544979Y860993D03*
Y854584D03*
X539428Y864197D03*
X537579Y854584D03*
Y860993D03*
X544979Y867401D03*
X541279D03*
X537579D03*
X535729Y864197D03*
X543128D03*
X546828D03*
X535729Y857789D03*
X543130D03*
X539429D03*
X541279Y860993D03*
Y854584D03*
X546829Y870606D03*
X541279Y873810D03*
X535729Y870606D03*
Y883423D03*
X541279Y880219D03*
X546829Y883423D03*
X539429D03*
X537578Y880219D03*
X543129Y883423D03*
X544979Y880219D03*
X537578Y873810D03*
X539429Y870606D03*
X544979Y873810D03*
X543129Y870606D03*
X539428Y877014D03*
X546828D03*
X535729D03*
X543129D03*
X541279Y886627D03*
X544979D03*
X537579D03*
X535729Y889832D03*
X550529D03*
X548679Y912262D03*
X537579Y905853D03*
X535729Y909057D03*
Y902649D03*
X548679Y905853D03*
X537578Y925079D03*
X535729Y928283D03*
Y921875D03*
X548678Y925079D03*
Y931488D03*
X537578Y944304D03*
X535729Y941100D03*
X548678Y944304D03*
X535729Y947509D03*
X549278Y949619D03*
X549719Y962436D03*
X535729Y960326D03*
Y966735D03*
X537579Y963530D03*
X548146Y965640D03*
X537579Y982756D03*
X541279Y969939D03*
X539429Y973143D03*
X543729Y984866D03*
X536161Y999684D03*
X549254Y1000648D03*
X536161Y1012501D03*
X541712Y1015705D03*
X545412D03*
X538012D03*
X536161Y1018910D03*
X549112Y1015705D03*
X536161Y1031727D03*
X545412Y1034931D03*
X541711D03*
X538011D03*
X536161Y1038136D03*
X549112Y1034931D03*
X541711Y1054157D03*
X538011D03*
X536161Y1057361D03*
X545411Y1054157D03*
X536161Y1050952D03*
X549422Y1064850D03*
X545411Y1066974D03*
X536161Y1076587D03*
X536162Y1070178D03*
X538011Y1073383D03*
X547262Y1070178D03*
X538011Y1092608D03*
X536161Y1089404D03*
X545411Y1092608D03*
X547262Y1082996D03*
X543561Y1095813D03*
X536161D03*
X547261D03*
X545412Y1105426D03*
X541711D03*
X539861Y1108630D03*
Y1102221D03*
X536161D03*
X541711Y1111834D03*
X545411D03*
X538011Y1105426D03*
X536161Y1108630D03*
X538011Y1111834D03*
X543561Y1108630D03*
X545411Y1124651D03*
Y1118243D03*
X543562Y1115039D03*
X539862D03*
X538011Y1124651D03*
X536161Y1115039D03*
X541711Y1118243D03*
X538010Y1118242D03*
X543561Y1121446D03*
X539861Y1127855D03*
X536161D03*
Y1121446D03*
X539861D03*
X541711Y1124650D03*
X543561Y1127855D03*
X541711Y1131060D03*
X536162Y1134264D03*
X538012Y1131059D03*
X549589Y1580678D03*
X544633D03*
X549589Y1575592D03*
X544633D03*
X537529Y1575686D03*
Y1580678D03*
X536751Y1578182D03*
X548811D03*
X545411D03*
X549933Y1599790D03*
X537873Y1599884D03*
X542829D03*
X549589Y1592590D03*
X544633D03*
X549589Y1587598D03*
X544633D03*
X537529D03*
Y1592590D03*
X536751Y1590094D03*
X548811D03*
X545411D03*
X549933Y1611796D03*
Y1604876D03*
Y1616788D03*
X542829D03*
X537873D03*
Y1604876D03*
X542829D03*
X537873Y1611796D03*
X542829D03*
X538651Y1614292D03*
X542051D03*
X538651Y1602380D03*
X542051D03*
X544685Y1675383D03*
Y1679920D03*
X536811Y1679320D03*
X544685Y1684454D03*
Y1689556D03*
Y1694093D03*
Y1698627D03*
X536811Y1688391D03*
Y1693493D03*
Y1698030D03*
Y1683857D03*
X544685Y1703729D03*
Y1708266D03*
Y1712800D03*
X536811Y1707666D03*
Y1712203D03*
Y1702564D03*
X544685Y1726974D03*
Y1722440D03*
Y1717903D03*
X536811Y1730911D03*
Y1726377D03*
Y1721840D03*
Y1716737D03*
X551429Y979057D03*
X550701Y972608D03*
X550961Y1031727D03*
X556693Y1575686D03*
X561649D03*
X556693Y1580678D03*
X561649D03*
X560871Y1578182D03*
X557471D03*
X561993Y1599884D03*
X554889Y1599790D03*
X556693Y1587598D03*
X561649D03*
Y1592590D03*
X556693D03*
X560871Y1590094D03*
X557471D03*
X561993Y1616788D03*
Y1604876D03*
Y1611796D03*
X554889D03*
Y1604876D03*
Y1616788D03*
X562771Y1614292D03*
X550711D03*
X566171D03*
X554111D03*
X562771Y1602380D03*
X550711D03*
X566171D03*
X554111D03*
X552559Y1679320D03*
X564370Y1675383D03*
Y1679920D03*
X552559Y1688391D03*
Y1693493D03*
Y1698030D03*
Y1683857D03*
X564370Y1684454D03*
Y1689556D03*
Y1694093D03*
Y1698627D03*
X552559Y1707666D03*
Y1712203D03*
Y1702564D03*
X564370Y1703729D03*
Y1708266D03*
Y1712800D03*
X552559Y1730911D03*
Y1726377D03*
Y1721840D03*
Y1716737D03*
X564370Y1726974D03*
Y1722440D03*
Y1717903D03*
X580813Y1575686D03*
Y1580678D03*
X573709D03*
X568753D03*
Y1575686D03*
X573709D03*
X572931Y1578182D03*
X581591D03*
X569531D03*
X579009Y1599884D03*
X574053D03*
X566949D03*
X580813Y1587598D03*
Y1592590D03*
X573709D03*
X568753D03*
X573709Y1587598D03*
X568753D03*
X572931Y1590094D03*
X581591D03*
X569531D03*
X574053Y1616788D03*
X579009D03*
Y1611796D03*
X574053D03*
X579009Y1604876D03*
X574053D03*
X566949Y1616788D03*
Y1604876D03*
Y1611796D03*
X574831Y1614292D03*
X578231D03*
X574831Y1602380D03*
X578231D03*
X580118Y1675383D03*
Y1679920D03*
X572244Y1679320D03*
X580118Y1684454D03*
Y1689556D03*
Y1694093D03*
Y1698627D03*
X572244Y1688391D03*
Y1693493D03*
Y1698030D03*
Y1683857D03*
X580118Y1703729D03*
Y1708266D03*
Y1712800D03*
X572244Y1707666D03*
Y1712203D03*
Y1702564D03*
X580118Y1726974D03*
Y1722440D03*
Y1717903D03*
X572244Y1730911D03*
Y1726377D03*
Y1721840D03*
Y1716737D03*
X597829Y1580678D03*
X592873D03*
X597829Y1575686D03*
X592873D03*
X585769D03*
Y1580678D03*
X597051Y1578182D03*
X584991D03*
X593651D03*
X598173Y1599884D03*
X586113D03*
X591069D03*
X597829Y1592590D03*
X592873D03*
X597829Y1587598D03*
X592873D03*
X585769D03*
Y1592590D03*
X597051Y1590094D03*
X584991D03*
X593651D03*
X598173Y1616788D03*
Y1611796D03*
Y1604876D03*
X586113D03*
X591069D03*
X586113Y1611796D03*
X591069D03*
Y1616788D03*
X586113D03*
X598951Y1614292D03*
X586891D03*
X590291D03*
X598951Y1602380D03*
X586891D03*
X590291D03*
X595866Y1675383D03*
Y1679920D03*
X587992Y1679320D03*
X595866Y1684454D03*
Y1689556D03*
Y1694093D03*
Y1698627D03*
X587992Y1688391D03*
Y1693493D03*
Y1698030D03*
Y1683857D03*
X595866Y1703729D03*
Y1708266D03*
Y1712800D03*
X587992Y1707666D03*
Y1712203D03*
Y1702564D03*
X595866Y1726974D03*
Y1722440D03*
Y1717903D03*
X587992Y1730911D03*
Y1726377D03*
Y1721840D03*
Y1716737D03*
X609889Y1575686D03*
X604933D03*
X609889Y1580678D03*
X604933D03*
X609111Y1578182D03*
X605711D03*
X615189Y1599884D03*
X610233D03*
X603129D03*
X609889Y1587598D03*
X604933D03*
X609889Y1592590D03*
X604933D03*
X609111Y1590094D03*
X605711D03*
X615189Y1604876D03*
X610233D03*
X615189Y1611796D03*
X610233D03*
X615189Y1616788D03*
X610233D03*
X603129D03*
Y1611796D03*
Y1604876D03*
X611011Y1614292D03*
X614411D03*
X602351D03*
X611011Y1602380D03*
X614411D03*
X602351D03*
X611614Y1675383D03*
Y1679920D03*
X603740Y1679320D03*
X611614Y1684454D03*
Y1689556D03*
Y1694093D03*
Y1698627D03*
X603740Y1688391D03*
Y1693493D03*
Y1698030D03*
Y1683857D03*
X611614Y1703729D03*
Y1708266D03*
Y1712800D03*
X603740Y1707666D03*
Y1712203D03*
Y1702564D03*
X611614Y1726974D03*
Y1722440D03*
Y1717903D03*
X603740Y1730911D03*
Y1726377D03*
Y1721840D03*
Y1716737D03*
X629599Y770144D03*
X620899D03*
X629658Y766478D03*
X629599Y783530D03*
X620899D03*
X629599Y776837D03*
X620899D03*
X620846Y800263D03*
X629599D03*
Y793570D03*
X620899D03*
Y820341D03*
X629599D03*
X620076Y813648D03*
X630593D03*
X619632Y806955D03*
X630792D03*
X620899Y830381D03*
X629599D03*
X620005Y850459D03*
X630754D03*
X620899Y843766D03*
X629599D03*
Y837074D03*
X620899D03*
Y867192D03*
X629599D03*
X620058Y857152D03*
X630481D03*
X620899Y880577D03*
X629599D03*
X620899Y873885D03*
X629599D03*
X620799Y883924D03*
X630756Y893963D03*
X620899D03*
X629599Y887270D03*
X620899D03*
X620799Y890617D03*
Y897310D03*
Y900656D03*
X620899Y910696D03*
X629599D03*
Y917389D03*
X620899D03*
X629599Y904003D03*
X620899D03*
X620799Y914042D03*
Y907349D03*
X630399Y930697D03*
X619905Y930774D03*
X620899Y924081D03*
X629599D03*
Y947507D03*
X620899D03*
X619964Y940814D03*
X630777D03*
X629599Y964239D03*
X620899D03*
X629599Y954200D03*
X620899D03*
X620799Y960892D03*
Y957546D03*
X620899Y977625D03*
X629599D03*
Y970932D03*
X620899D03*
Y991011D03*
X629599D03*
Y984318D03*
X620899D03*
X623347Y999665D03*
X625780Y1000198D03*
X620899Y1031168D03*
X629599D03*
X620899Y1017782D03*
X629599D03*
X620899Y1024475D03*
X629599D03*
X620899Y1044554D03*
X629599D03*
X620899Y1037861D03*
X629599D03*
X620899Y1057940D03*
X629599D03*
Y1051247D03*
X620899D03*
Y1061286D03*
Y1078018D03*
X629599D03*
X630399Y1071326D03*
X619999D03*
X620899Y1064633D03*
X629599D03*
X620899Y1088058D03*
X629599D03*
Y1094751D03*
X620899D03*
Y1108137D03*
X629599D03*
Y1101444D03*
X620899D03*
X630363Y1124674D03*
X620369Y1124969D03*
X630399Y1114829D03*
X620099D03*
X620899Y1131562D03*
X629599D03*
Y1144948D03*
X620899D03*
X629599Y1138255D03*
X620899D03*
X620511Y1161680D03*
X629833Y1161581D03*
X629599Y1151641D03*
X620899D03*
X629599Y1175066D03*
X620899D03*
X629599Y1168373D03*
X620899D03*
X630623Y1188452D03*
X620899D03*
X629599Y1181759D03*
X620899D03*
X620799Y1185105D03*
Y1178412D03*
Y1191798D03*
X629599Y1205184D03*
X620899D03*
Y1198491D03*
X629599D03*
X620799Y1208530D03*
Y1201837D03*
Y1195144D03*
X620899Y1225263D03*
X629599D03*
Y1218570D03*
X620899D03*
X629599Y1211877D03*
X620899D03*
X629599Y1241995D03*
X620899D03*
X630922Y1235302D03*
X620036D03*
X620899Y1248688D03*
X629599D03*
X629931Y1258727D03*
X632080Y1262074D03*
X629699Y1255381D03*
X625246Y1273164D03*
X627646D03*
X631270Y1264942D03*
X629053Y1575686D03*
Y1580678D03*
X621949D03*
X616993D03*
X621949Y1575686D03*
X616993D03*
X621171Y1578182D03*
X629831D03*
X617771D03*
X622293Y1599884D03*
X627249D03*
X629053Y1587598D03*
Y1592590D03*
X621949D03*
X616993D03*
X621949Y1587598D03*
X616993D03*
X621171Y1590094D03*
X629831D03*
X617771D03*
X627249Y1616788D03*
X622293D03*
Y1611796D03*
X627249D03*
X622293Y1604876D03*
X627249D03*
X623071Y1614292D03*
X626471D03*
X623071Y1602380D03*
X626471D03*
X619488Y1679320D03*
Y1688391D03*
Y1693493D03*
Y1698030D03*
Y1683857D03*
Y1707666D03*
Y1712203D03*
Y1702564D03*
Y1730911D03*
Y1726377D03*
Y1721840D03*
Y1716737D03*
X637041Y766798D03*
X645741D03*
X650599D03*
X645741Y773491D03*
X637041D03*
X645741Y780184D03*
X637041D03*
Y803609D03*
X645741D03*
X637041Y796916D03*
X645741D03*
Y790223D03*
X637041D03*
X636221Y810302D03*
X646844D03*
X646774Y816995D03*
X637041D03*
X645741Y833727D03*
X637041D03*
Y827034D03*
X645741D03*
X637041Y847113D03*
X645801D03*
X637041Y840420D03*
X645741D03*
X646819Y853806D03*
X636332Y853955D03*
X645918Y863845D03*
X636266D03*
X637041Y877231D03*
X645741D03*
X637041Y870538D03*
X645741D03*
Y883924D03*
X637041D03*
X636941Y880577D03*
X637041Y900656D03*
X645741D03*
X637041Y890617D03*
X645741D03*
X636941Y887270D03*
Y897310D03*
Y893963D03*
X637041Y914042D03*
X645741D03*
Y907349D03*
X637041D03*
X636941Y910696D03*
Y904003D03*
X646393Y927526D03*
X636026Y927428D03*
X645741Y920735D03*
X637041D03*
X645741Y944160D03*
X637041D03*
X636170Y937467D03*
X646703D03*
X645741Y960892D03*
X637041D03*
Y950853D03*
X645741D03*
X636941Y957546D03*
Y954200D03*
X637041Y980971D03*
X645741D03*
X637041Y974278D03*
X645741D03*
X637041Y967585D03*
X645741D03*
X637041Y987664D03*
X645741D03*
X644347Y1003135D03*
X640327D03*
X640467Y1000735D03*
X647447Y1002865D03*
X647397Y1000135D03*
X644257Y1000325D03*
X637041Y1027822D03*
X645741D03*
Y1017782D03*
X637041D03*
X645741Y1047900D03*
X637041D03*
Y1041207D03*
X645741D03*
X637041Y1034515D03*
X645741D03*
X637041Y1061286D03*
X645741D03*
Y1054593D03*
X637041D03*
X636141Y1074672D03*
X646541D03*
X645741Y1067979D03*
X636841D03*
X637041Y1091404D03*
X645741D03*
Y1084711D03*
X636241D03*
X645741Y1111483D03*
X637041D03*
X645741Y1098097D03*
X637041D03*
X645741Y1104790D03*
X637041D03*
Y1121522D03*
X645741D03*
X637041Y1128915D03*
X645741Y1128215D03*
X646584Y1135108D03*
X635744Y1134908D03*
X645741Y1141601D03*
X637041D03*
X645741Y1148294D03*
X637041D03*
X645741Y1158333D03*
X637041D03*
Y1171719D03*
X645741D03*
Y1165026D03*
X637041D03*
X636941Y1175066D03*
X637041Y1185105D03*
X645741D03*
Y1178412D03*
X637041D03*
X636941Y1181759D03*
Y1191798D03*
Y1188451D03*
X645741Y1208530D03*
X637041D03*
X645741Y1201837D03*
X637041D03*
Y1195144D03*
X645741D03*
X636941Y1205184D03*
Y1198491D03*
X636005Y1221916D03*
X646570D03*
X645741Y1215223D03*
X637041D03*
X645741Y1238648D03*
X637041D03*
X635995Y1231862D03*
X646539Y1231955D03*
X645741Y1245341D03*
X637041D03*
X634213Y1258679D03*
X636946Y1258414D03*
X647690Y1260812D03*
X637041Y1252034D03*
X645897Y1248785D03*
X647877Y1254076D03*
X642746Y1273364D03*
X639946D03*
X636877Y1261235D03*
X646069Y1580678D03*
X641113D03*
X646069Y1575592D03*
X641113D03*
X634009Y1575686D03*
Y1580678D03*
X645291Y1578182D03*
X633231D03*
X641891D03*
X646413Y1599790D03*
X639309Y1599884D03*
X634353D03*
X646069Y1592590D03*
X641113D03*
X646069Y1587598D03*
X641113D03*
X634009D03*
Y1592590D03*
X645291Y1590094D03*
X633231D03*
X641891D03*
X646413Y1616788D03*
Y1611796D03*
Y1604876D03*
X639309D03*
X634353D03*
X639309Y1611796D03*
X634353D03*
Y1616788D03*
X639309D03*
X647191Y1614292D03*
X635131D03*
X638531D03*
X647191Y1602380D03*
X635131D03*
X638531D03*
X667677Y441636D03*
X650599Y770144D03*
X659299D03*
X650599Y783530D03*
X659299D03*
X650599Y776837D03*
X659299D03*
Y800263D03*
X650599D03*
Y793570D03*
X659299D03*
Y806955D03*
X650599D03*
X660432Y813648D03*
X650599D03*
X660199Y820341D03*
X650599D03*
X659299Y830381D03*
X650599D03*
X659299Y850459D03*
X650599D03*
X659299Y843766D03*
X650599D03*
Y837074D03*
X659299D03*
Y857152D03*
X650599D03*
X649563Y867192D03*
X660299D03*
X659299Y873885D03*
X650599D03*
Y880577D03*
X659299D03*
X650599Y893963D03*
X659299D03*
X650599Y887270D03*
X659299D03*
Y917389D03*
X650599D03*
X659299Y910696D03*
X650599D03*
Y904003D03*
X659299D03*
X660504Y924081D03*
X650599D03*
X660174Y930774D03*
X649661D03*
X659299Y947507D03*
X650599D03*
X659299Y940814D03*
X650599D03*
X659299Y964239D03*
X650599D03*
Y954200D03*
X659299D03*
X650499Y960892D03*
Y957546D03*
X659299Y977625D03*
X650599D03*
X659299Y970932D03*
X650599D03*
X659299Y991011D03*
X650599D03*
X659299Y984318D03*
X650599D03*
X650107Y1002825D03*
X659299Y1031168D03*
X650599D03*
X659299Y1017782D03*
X650599D03*
X659299Y1024475D03*
X650599D03*
X659299Y1044554D03*
X650599D03*
X659299Y1037861D03*
X650599D03*
X659299Y1051247D03*
X650599D03*
Y1057940D03*
X659299D03*
X660099Y1078018D03*
X649799D03*
X659299Y1071326D03*
X650599D03*
X659299Y1064633D03*
X650599D03*
X659299Y1094751D03*
X650599D03*
X660099Y1088058D03*
X649799D03*
X650599Y1108137D03*
X659299D03*
X650599Y1101444D03*
X659299D03*
X660199Y1124869D03*
X649932Y1124640D03*
X659299Y1114829D03*
X650599D03*
X659299Y1130762D03*
X650599D03*
X659299Y1138255D03*
X650599D03*
X659299Y1144948D03*
X650599D03*
X659299Y1151641D03*
X650599D03*
Y1161680D03*
X659299D03*
X650599Y1175066D03*
X659299D03*
X650599Y1168373D03*
X659299D03*
X650599Y1188452D03*
X659299D03*
X650599Y1181759D03*
X659299D03*
X650599Y1205184D03*
X659299D03*
X650599Y1198491D03*
X659299D03*
X660070Y1225263D03*
X649913D03*
X659299Y1218570D03*
X650599D03*
X659299Y1211877D03*
X650599D03*
X659299Y1241995D03*
X650599D03*
X660234Y1235302D03*
X649701D03*
X650599Y1248688D03*
X659299D03*
X659546Y1257664D03*
X650599Y1258727D03*
X666741Y1255381D03*
X664630Y1259442D03*
X656446Y1273364D03*
X653646D03*
X649587Y1266766D03*
X661400Y1263522D03*
X654606Y1431203D03*
X653173Y1575686D03*
X658129D03*
X653173Y1580678D03*
X658129D03*
X657351Y1578182D03*
X653951D03*
X663429Y1599884D03*
X658473D03*
X651369Y1599790D03*
X653173Y1587598D03*
X658129D03*
X653173Y1592590D03*
X658129D03*
X657351Y1590094D03*
X653951D03*
X663429Y1604876D03*
X658473D03*
X663429Y1611796D03*
X658473D03*
Y1616788D03*
X663429D03*
X651369D03*
Y1611796D03*
Y1604876D03*
X662651Y1614292D03*
X659251D03*
X650591D03*
X662651Y1602380D03*
X659251D03*
X650591D03*
X668329Y411714D03*
X674628Y424313D03*
X671479Y421163D03*
X667660Y429037D03*
X674628Y427462D03*
Y414864D03*
X677778D03*
Y424313D03*
X671479Y414864D03*
X674628Y421163D03*
Y418013D03*
X677778D03*
Y421163D03*
X668329D03*
X677778Y427462D03*
Y430612D03*
X674628Y436911D03*
Y443210D03*
X671479Y430612D03*
Y436911D03*
X677778Y433761D03*
X668329Y436911D03*
X677778Y440061D03*
X674628D03*
X677778Y436911D03*
Y443210D03*
X680928Y440061D03*
X674628Y430612D03*
X671479Y443211D03*
Y462108D03*
X677778Y449510D03*
X668329Y452659D03*
X674628D03*
X671479D03*
X677778D03*
X668329Y455809D03*
X671479Y458959D03*
X674628D03*
X668329D03*
X677778D03*
Y455809D03*
X674628D03*
X668067Y462090D03*
X677778Y462108D03*
X671479Y455809D03*
X680928Y458959D03*
X674628Y449510D03*
Y462108D03*
X677778Y477856D03*
Y471557D03*
Y474707D03*
X671479Y465258D03*
X674628D03*
X668329D03*
X677778D03*
Y468407D03*
X671479Y481006D03*
X667350Y470680D03*
X671479Y474707D03*
X674628Y484006D03*
X668329Y481006D03*
X680299Y770144D03*
X675441Y766798D03*
X666741D03*
X680299D03*
Y783530D03*
Y776837D03*
X666741Y773491D03*
X675441D03*
X666741Y780184D03*
X675441D03*
X680299D03*
Y773491D03*
Y786877D03*
X675441Y803609D03*
X666741D03*
X680299Y800263D03*
Y793570D03*
X666741Y796916D03*
X675441D03*
X666741Y790223D03*
X675441D03*
X680299Y803609D03*
Y796916D03*
Y790223D03*
X676403Y816995D03*
X665803D03*
X675441Y810302D03*
X666741D03*
X680299Y820341D03*
Y813648D03*
Y806955D03*
Y816995D03*
Y810302D03*
X675441Y833727D03*
X666741D03*
X676625Y827034D03*
X665876D03*
X680299Y830381D03*
Y833727D03*
Y823688D03*
Y827034D03*
X675441Y847113D03*
X666741D03*
X680299Y850459D03*
Y843766D03*
Y837074D03*
X666741Y840420D03*
X675441D03*
X680299Y847113D03*
Y840420D03*
X676417Y853806D03*
X665890D03*
X680299Y867192D03*
Y857152D03*
X665916Y863845D03*
X676600D03*
X680299Y853806D03*
Y860499D03*
Y863845D03*
X675441Y877231D03*
X666741D03*
X675441Y870538D03*
X666741D03*
Y883924D03*
X675441D03*
X680299Y880577D03*
Y873885D03*
Y883924D03*
Y877231D03*
Y870538D03*
X666741Y900656D03*
X675441D03*
X680299Y893963D03*
Y887270D03*
X666741Y890617D03*
X675441D03*
X680299D03*
Y897310D03*
Y900656D03*
X675441Y914042D03*
X666741D03*
X680299Y917389D03*
Y910696D03*
Y904003D03*
X666741Y907349D03*
X675441D03*
X680299Y914042D03*
Y907349D03*
X676488Y927428D03*
X665896D03*
X675441Y920735D03*
X666741D03*
X680299Y930774D03*
Y924081D03*
Y927428D03*
Y920735D03*
Y934121D03*
X675441Y944160D03*
X666741D03*
X676359Y937467D03*
X665923D03*
X680299Y947507D03*
Y940814D03*
Y944160D03*
Y937467D03*
Y964239D03*
X675441Y960892D03*
X666741D03*
X680299Y954200D03*
X666741Y950853D03*
X675441D03*
X680299Y960892D03*
Y950853D03*
Y957546D03*
X666641D03*
Y954200D03*
X675441Y980971D03*
X666741D03*
X680299Y970932D03*
X675441Y974278D03*
X666741D03*
X675441Y967585D03*
X666741D03*
X680299Y977625D03*
Y980971D03*
Y974278D03*
Y967585D03*
X675441Y987664D03*
X666741D03*
X680299Y991011D03*
Y984318D03*
Y994357D03*
Y987664D03*
X672063Y998632D03*
X680299Y1031168D03*
Y1024475D03*
X675441Y1027822D03*
X666741D03*
X675441Y1017782D03*
X666741D03*
X680299D03*
X679999Y1027822D03*
X680299Y1021129D03*
X675441Y1047900D03*
X666741D03*
X680299Y1037861D03*
X675441Y1041207D03*
X666741D03*
X675441Y1034515D03*
X666741D03*
X680299Y1044554D03*
X679999Y1047900D03*
Y1041207D03*
Y1034514D03*
X680299Y1057940D03*
Y1051247D03*
X675441Y1054593D03*
X666741D03*
Y1061286D03*
X675441D03*
X680299D03*
X679999Y1054593D03*
X676341Y1074672D03*
X665841D03*
X675441Y1067979D03*
X666741D03*
X680299Y1078018D03*
Y1071326D03*
Y1064633D03*
Y1074672D03*
Y1067979D03*
X675441Y1091404D03*
X666741D03*
X676241Y1084711D03*
X665941D03*
X680299Y1094751D03*
Y1088058D03*
Y1091404D03*
Y1081365D03*
Y1084711D03*
X666741Y1111483D03*
X675441D03*
X680299Y1108137D03*
Y1101444D03*
X666741Y1104790D03*
X675441D03*
X666741Y1098097D03*
X675441D03*
X680299D03*
Y1111483D03*
Y1104790D03*
X666741Y1128215D03*
X675441D03*
X680299Y1124869D03*
Y1114829D03*
X666741Y1121522D03*
X675441D03*
X680299Y1128215D03*
Y1118176D03*
Y1121522D03*
Y1144948D03*
Y1138255D03*
Y1131562D03*
X666741Y1141601D03*
X675441D03*
X666741Y1134908D03*
X675441D03*
X680299Y1141601D03*
Y1134908D03*
X676652Y1148294D03*
X665602D03*
X676241Y1158333D03*
X665941D03*
X680299Y1161680D03*
Y1151641D03*
Y1148294D03*
Y1154987D03*
Y1158333D03*
X675441Y1165026D03*
X666741D03*
X680299Y1175066D03*
Y1168373D03*
X666741Y1171719D03*
X675441D03*
X680299D03*
Y1165026D03*
Y1188452D03*
Y1181759D03*
X666741Y1185105D03*
X675441D03*
X666741Y1178412D03*
X675441D03*
X680299Y1185105D03*
Y1178412D03*
Y1191798D03*
Y1205184D03*
Y1198491D03*
X666741Y1208530D03*
X675441D03*
X666741Y1201837D03*
X675441D03*
X666741Y1195144D03*
X675441D03*
X680299Y1208530D03*
Y1201837D03*
Y1195144D03*
Y1218570D03*
Y1225263D03*
X676448Y1221916D03*
X665651D03*
X675441Y1215223D03*
X666741D03*
X680299Y1211877D03*
Y1221916D03*
Y1215223D03*
X675441Y1238648D03*
X666741D03*
X676462Y1231955D03*
X665912D03*
X680299Y1241995D03*
Y1235302D03*
Y1238648D03*
Y1228609D03*
Y1231955D03*
X675441Y1245341D03*
X666741D03*
X676046Y1257964D03*
X680299Y1248688D03*
Y1245341D03*
Y1258727D03*
X666741Y1252034D03*
X675537Y1248885D03*
X677980Y1262074D03*
X672446Y1273364D03*
X669646D03*
X666741Y1262074D03*
X666646Y1264464D03*
X680046Y1264964D03*
X695055Y112678D03*
Y115178D03*
X684077Y414864D03*
X680928Y424313D03*
X687227Y414864D03*
X690376Y421163D03*
Y418013D03*
Y414864D03*
X693526Y427462D03*
X687227Y424313D03*
X690376Y427462D03*
X680928Y414864D03*
Y418013D03*
X684077Y421163D03*
X680928Y427462D03*
X684077Y418013D03*
Y427462D03*
X680928Y421163D03*
X684077Y424313D03*
X687227Y427462D03*
X696676D03*
X693526Y421163D03*
Y424313D03*
X690376D03*
X696676Y421163D03*
Y424313D03*
Y418013D03*
Y436911D03*
X693526Y443210D03*
Y440061D03*
Y436911D03*
X690376Y440061D03*
Y433761D03*
X680928Y436911D03*
Y433761D03*
X693526Y430612D03*
X696676Y440061D03*
Y443210D03*
X684077Y430612D03*
Y440061D03*
X687227Y436911D03*
Y443210D03*
X684077D03*
Y436911D03*
X680928Y443210D03*
X690376Y436911D03*
Y443210D03*
X687227Y440061D03*
X693526Y433761D03*
X696676D03*
X684077D03*
X687227Y430612D03*
X690376D03*
X696676D03*
X687227Y433761D03*
X680928Y430612D03*
X687227Y462108D03*
X693526Y452659D03*
Y449510D03*
X696676Y455809D03*
X693526D03*
X690376Y452659D03*
Y458959D03*
X680928Y455809D03*
X693526Y462108D03*
X680928Y449510D03*
X687227D03*
X690376Y462108D03*
X684077Y449510D03*
X680928Y452659D03*
X684077D03*
X687227Y455809D03*
X684077D03*
X680928Y462108D03*
X696676Y449510D03*
Y452659D03*
X690376Y449510D03*
Y455809D03*
X687227Y452659D03*
X693526Y458959D03*
X696676D03*
Y462108D03*
X687227Y458959D03*
X684077D03*
Y468407D03*
X687227Y471557D03*
Y474707D03*
Y477856D03*
X684077Y471557D03*
X690376Y465258D03*
X684077D03*
X680928Y471557D03*
Y474707D03*
Y477856D03*
X696676D03*
X684077D03*
X680928Y468407D03*
X693526Y465258D03*
Y471557D03*
X690376Y468407D03*
Y477856D03*
Y471557D03*
X687227Y465258D03*
X690376Y474707D03*
X687227Y468407D03*
X693526D03*
X684077Y474707D03*
X696676Y465258D03*
Y474707D03*
Y468407D03*
X693526Y474707D03*
X696676Y471557D03*
X693526Y477856D03*
X696441Y766798D03*
X688999Y770144D03*
X696441D03*
Y773491D03*
Y780184D03*
X688999Y783530D03*
Y776837D03*
X696441D03*
Y786877D03*
Y783530D03*
Y803609D03*
Y796916D03*
Y790223D03*
X688999Y800263D03*
Y793570D03*
X696441Y800263D03*
Y793570D03*
Y816995D03*
Y810302D03*
X689888Y820341D03*
X688999Y813648D03*
Y806955D03*
X696441Y813648D03*
Y806955D03*
Y820341D03*
Y833727D03*
Y827034D03*
X688999Y830381D03*
X696441D03*
Y823688D03*
Y847113D03*
X688999Y850459D03*
X696441Y840420D03*
X688999Y843766D03*
Y837074D03*
X696441Y850459D03*
Y843766D03*
Y837074D03*
Y863845D03*
Y853806D03*
X688999Y867192D03*
X689896Y857152D03*
X696441Y867192D03*
Y860499D03*
Y857152D03*
Y883924D03*
Y877231D03*
Y870538D03*
X688999Y880577D03*
Y873885D03*
X696441D03*
Y880577D03*
Y900656D03*
Y890617D03*
X688999Y893963D03*
Y887270D03*
X696441D03*
Y897310D03*
Y893963D03*
Y914042D03*
Y907349D03*
X688999Y917389D03*
Y910696D03*
Y904003D03*
X696441Y917389D03*
Y910696D03*
Y904003D03*
Y927428D03*
Y920735D03*
X690104Y930774D03*
X688999Y924081D03*
X696441D03*
Y934121D03*
Y930774D03*
Y944160D03*
Y937467D03*
X688999Y947507D03*
Y940814D03*
X696441Y947507D03*
Y940814D03*
Y960892D03*
Y950853D03*
X688999Y964239D03*
Y954200D03*
X696441Y964239D03*
Y957546D03*
Y954200D03*
Y980971D03*
Y974278D03*
Y967585D03*
X688999Y970932D03*
Y977625D03*
X696441D03*
Y970932D03*
Y987664D03*
X688999Y991011D03*
Y984318D03*
X696441Y991011D03*
Y984318D03*
Y994357D03*
Y1027822D03*
Y1017782D03*
X688999Y1031168D03*
Y1024475D03*
Y1017782D03*
X696441Y1021129D03*
Y1024475D03*
Y1031168D03*
Y1047900D03*
Y1041207D03*
Y1034515D03*
X688999Y1037861D03*
Y1044554D03*
X696141D03*
Y1037861D03*
X696441Y1054593D03*
Y1061286D03*
X688999Y1057940D03*
Y1051247D03*
X696441D03*
Y1074672D03*
Y1067979D03*
X688999Y1077118D03*
Y1071326D03*
Y1064633D03*
X696441Y1071325D03*
Y1064633D03*
Y1078018D03*
Y1091404D03*
Y1084711D03*
X688999Y1094751D03*
Y1088058D03*
X696441Y1094751D03*
Y1088058D03*
Y1081365D03*
Y1111483D03*
Y1104790D03*
Y1098097D03*
X688999Y1108137D03*
Y1101444D03*
X696441Y1108136D03*
Y1101444D03*
Y1128215D03*
Y1121522D03*
X688999Y1124869D03*
Y1114829D03*
X696441Y1124869D03*
Y1118176D03*
Y1114829D03*
Y1141601D03*
Y1134908D03*
X688999Y1144948D03*
Y1138255D03*
Y1131562D03*
X696441Y1144947D03*
Y1138255D03*
Y1131562D03*
Y1158333D03*
Y1148294D03*
X688999Y1161680D03*
X689999Y1151641D03*
X696441Y1161680D03*
Y1154987D03*
Y1151640D03*
Y1171719D03*
Y1165026D03*
X688999Y1175066D03*
Y1168373D03*
X696441Y1175066D03*
Y1168373D03*
Y1185105D03*
Y1178412D03*
X688999Y1188452D03*
Y1181759D03*
X696441Y1181758D03*
Y1191798D03*
Y1188451D03*
Y1208530D03*
Y1201837D03*
Y1195144D03*
X688999Y1205184D03*
Y1198491D03*
X696441Y1205184D03*
Y1198491D03*
Y1221916D03*
Y1215223D03*
X688999Y1218570D03*
X689799Y1225263D03*
X688999Y1211877D03*
X696441Y1218569D03*
Y1211877D03*
Y1225262D03*
Y1238648D03*
Y1231955D03*
X688999Y1241995D03*
Y1235302D03*
X696441Y1241995D03*
Y1235302D03*
Y1228609D03*
X688916Y1256964D03*
X696441Y1245341D03*
X688999Y1248688D03*
X696441Y1255381D03*
X694100Y1261562D03*
X696441Y1248688D03*
X692233Y1252480D03*
X686146Y1273364D03*
X683346D03*
X696046Y1263764D03*
X698598Y115178D03*
X705685D03*
X702141D03*
X698598Y112678D03*
X705685D03*
X702141D03*
X706125Y421163D03*
X702975Y414864D03*
X706125Y418013D03*
X712424Y424313D03*
X699825Y427462D03*
X699826Y414864D03*
X699825Y424313D03*
X709274Y436911D03*
X706125Y440061D03*
Y436911D03*
X699825Y440061D03*
Y436911D03*
X712424Y443210D03*
Y440061D03*
Y436911D03*
Y430612D03*
X709274Y440061D03*
Y443210D03*
X706125D03*
X699825D03*
X709274Y433761D03*
X712424D03*
X699825D03*
X706125D03*
X699825Y430612D03*
X706125Y462108D03*
X709274D03*
X712424D03*
Y455809D03*
X709274D03*
X706125D03*
Y452659D03*
X699825Y455809D03*
Y452659D03*
X712424D03*
Y449510D03*
X709274D03*
X699825D03*
X706125D03*
X709274Y452659D03*
X699825Y458959D03*
X706125D03*
X709274D03*
X712424D03*
X699825Y462108D03*
X709274Y474707D03*
Y471557D03*
Y465258D03*
Y468407D03*
X712424Y474707D03*
Y468407D03*
Y465258D03*
X709274Y477856D03*
X699825Y468407D03*
X706125Y471557D03*
Y468407D03*
X699825Y471557D03*
Y474707D03*
X706125Y477856D03*
X699825Y465258D03*
X712424Y471557D03*
X706125Y481006D03*
X709999Y770144D03*
X705141Y766798D03*
X709899D03*
X709999Y783530D03*
Y776837D03*
X705141Y773491D03*
Y780184D03*
X709999Y800263D03*
Y793570D03*
X705141Y803609D03*
Y796916D03*
Y790223D03*
X709999Y820341D03*
Y813648D03*
Y806955D03*
X705141Y816995D03*
Y810302D03*
X709999Y830381D03*
X705141Y833727D03*
Y827034D03*
Y847113D03*
X709999Y850459D03*
Y843766D03*
Y837074D03*
X705141Y840420D03*
Y863845D03*
Y853806D03*
X709999Y867192D03*
Y857152D03*
X705141Y883924D03*
Y877231D03*
Y870538D03*
X709999Y880577D03*
Y873885D03*
X705141Y900656D03*
Y890617D03*
X709999Y893963D03*
Y887270D03*
X705141Y914042D03*
Y907349D03*
X709999Y917389D03*
Y910696D03*
Y904003D03*
X705141Y927428D03*
Y920735D03*
X709999Y930774D03*
Y924081D03*
X705141Y944160D03*
Y937467D03*
X709999Y947507D03*
Y940814D03*
X705141Y960892D03*
Y950853D03*
X709999Y964239D03*
Y954200D03*
X709899Y960892D03*
Y957546D03*
X705141Y980971D03*
Y974278D03*
Y967585D03*
X709999Y977625D03*
Y970932D03*
Y967585D03*
X705141Y987664D03*
X709999Y991011D03*
Y984318D03*
X705141Y1027822D03*
Y1017782D03*
X709999Y1031168D03*
Y1024475D03*
Y1017782D03*
X705141Y1047900D03*
Y1041207D03*
Y1034515D03*
X709999Y1044554D03*
Y1037861D03*
X705141Y1054593D03*
Y1061286D03*
X709999Y1057940D03*
Y1051247D03*
Y1054593D03*
X705141Y1074672D03*
Y1067979D03*
X709999Y1078018D03*
Y1071326D03*
Y1064633D03*
X705141Y1091404D03*
Y1084711D03*
X709999Y1094751D03*
Y1088058D03*
X705141Y1111483D03*
Y1104790D03*
Y1098097D03*
X709999Y1108137D03*
Y1101444D03*
X705141Y1128215D03*
Y1121522D03*
X709999Y1124869D03*
Y1114829D03*
X705141Y1141601D03*
Y1134908D03*
X709999Y1144948D03*
Y1138255D03*
Y1131562D03*
X705141Y1158333D03*
Y1148294D03*
X709999Y1161680D03*
Y1151641D03*
X705141Y1171719D03*
Y1165026D03*
X709999Y1175066D03*
Y1168373D03*
X705141Y1185105D03*
Y1178412D03*
X709999Y1188452D03*
Y1181759D03*
X705141Y1208530D03*
Y1201837D03*
Y1195144D03*
X709999Y1205184D03*
Y1198491D03*
X705141Y1221916D03*
Y1215223D03*
X709999Y1225263D03*
Y1218570D03*
Y1211877D03*
X705141Y1238648D03*
Y1231955D03*
X709999Y1241995D03*
Y1235302D03*
X705141Y1245341D03*
X709999Y1248688D03*
Y1258727D03*
X708090Y1262074D03*
X705037Y1252034D03*
X706493Y1256563D03*
X713046Y1273364D03*
X702146D03*
X699346D03*
X705167Y1262074D03*
X709977Y1264985D03*
X721873Y427462D03*
X725022D03*
X728172Y418013D03*
X725022Y414864D03*
X718723Y418013D03*
X715574Y427462D03*
X728172Y421163D03*
X718723Y414864D03*
X725022Y424313D03*
X721873D03*
X725022Y421163D03*
X728172Y427462D03*
X731322Y421163D03*
X725022Y418013D03*
X718723Y427462D03*
Y424313D03*
Y421163D03*
X715574Y424313D03*
Y421163D03*
Y418013D03*
X728172Y424313D03*
X718723Y436911D03*
X721873Y433761D03*
Y436911D03*
Y440061D03*
Y430612D03*
X718723Y433761D03*
Y440061D03*
X725022Y436911D03*
Y433761D03*
X728172D03*
X715574D03*
X718723Y430612D03*
X715574D03*
X725022D03*
X728172Y436911D03*
X715574D03*
Y440061D03*
Y443210D03*
X728172D03*
Y430612D03*
X725022Y440061D03*
X718723Y443210D03*
X721873D03*
X725022D03*
X728172Y440061D03*
X731322D03*
X728172Y455809D03*
Y458959D03*
X718723Y455809D03*
X721873Y458959D03*
X715574D03*
X728172Y449510D03*
X721873Y452659D03*
X725022D03*
X728172D03*
X715574Y462108D03*
X725022Y458959D03*
X721873Y455809D03*
X725022Y462108D03*
X718723Y452659D03*
X715574Y449510D03*
Y452659D03*
Y455809D03*
X728172Y462108D03*
X718723Y449510D03*
X721873D03*
X725022D03*
X718723Y458959D03*
X721873Y462108D03*
X718723D03*
X725022Y468407D03*
X721873Y465258D03*
Y477856D03*
X725022D03*
X718723Y468407D03*
X715574Y474707D03*
Y471557D03*
Y468407D03*
Y465258D03*
X718723Y474707D03*
Y471557D03*
X728172Y477856D03*
X721873Y471557D03*
X725022D03*
X718723Y465258D03*
X728172D03*
X725022Y474707D03*
X728172Y468407D03*
X721873Y474707D03*
Y468407D03*
X728172Y474707D03*
Y471557D03*
X725022Y465258D03*
X718723Y477856D03*
X725132Y481116D03*
X728272Y481006D03*
X726141Y766798D03*
X718699Y770144D03*
X726141Y773491D03*
Y780184D03*
X718699Y783530D03*
Y776837D03*
X726141Y803609D03*
Y796916D03*
Y790223D03*
X718699Y800263D03*
Y793570D03*
X726141Y816995D03*
Y810302D03*
X718699Y820341D03*
Y813648D03*
Y806955D03*
X726141Y833727D03*
Y827034D03*
X718699Y830381D03*
X726141Y847113D03*
Y840420D03*
X718699Y850459D03*
Y843766D03*
Y837074D03*
X726141Y863845D03*
Y853806D03*
X718699Y867192D03*
Y857152D03*
X726141Y883924D03*
Y877231D03*
Y870538D03*
X718699Y880577D03*
Y873885D03*
X726141Y900656D03*
Y890617D03*
X718699Y893963D03*
Y887270D03*
X726141Y914042D03*
Y907349D03*
X718699Y917389D03*
Y910696D03*
Y904003D03*
X726141Y927428D03*
Y920735D03*
X718699Y930774D03*
Y924081D03*
X726141Y944160D03*
Y937467D03*
X718699Y947507D03*
Y940814D03*
X726141Y960892D03*
Y950853D03*
X718699Y964239D03*
Y954200D03*
X726141Y964239D03*
X726041Y957546D03*
Y954200D03*
X726141Y980971D03*
Y974278D03*
Y967585D03*
X718699Y977625D03*
Y970932D03*
X726141Y987664D03*
X718699Y991011D03*
Y984318D03*
X726041Y994357D03*
X726141Y1027822D03*
Y1017782D03*
X718699Y1031168D03*
Y1024475D03*
Y1017782D03*
X726141Y1021129D03*
Y1024475D03*
Y1047900D03*
Y1041207D03*
Y1034515D03*
X718699Y1044554D03*
Y1037861D03*
X726141Y1061286D03*
Y1054593D03*
X718699Y1057940D03*
Y1051247D03*
X726141D03*
Y1057940D03*
Y1074672D03*
Y1067979D03*
X718699Y1078018D03*
Y1071326D03*
Y1064633D03*
X726141Y1091404D03*
Y1084711D03*
X718699Y1094751D03*
Y1088058D03*
X726141Y1111483D03*
Y1104790D03*
Y1098097D03*
X718699Y1108137D03*
Y1101444D03*
X726141Y1128215D03*
Y1121522D03*
X718699Y1124869D03*
Y1114829D03*
X726141Y1141601D03*
Y1134908D03*
X718699Y1144948D03*
Y1138255D03*
Y1131562D03*
X726141Y1158333D03*
Y1148294D03*
X718699Y1161680D03*
Y1151641D03*
X726141Y1171719D03*
Y1165026D03*
X718699Y1175066D03*
Y1168373D03*
X726141Y1185105D03*
Y1178412D03*
X718699Y1188452D03*
Y1181759D03*
X726141Y1208530D03*
Y1201837D03*
Y1195144D03*
X718699Y1205184D03*
Y1198491D03*
X726141Y1221916D03*
Y1215223D03*
X718699Y1225263D03*
Y1218570D03*
Y1211877D03*
X726141Y1238648D03*
Y1231955D03*
X718699Y1241995D03*
Y1235302D03*
X726141Y1245341D03*
X719046Y1257064D03*
X718699Y1248688D03*
X726141Y1255381D03*
X723700Y1258727D03*
X726141Y1248688D03*
X729046Y1273364D03*
X715846D03*
X726141Y1262074D03*
X726107Y1265420D03*
X737621Y411714D03*
X734471Y418013D03*
X731322Y427462D03*
Y418013D03*
X734471Y421163D03*
X731322Y424313D03*
X734471D03*
X737621D03*
X731322Y414864D03*
Y433761D03*
Y430612D03*
X734471Y436911D03*
X731322D03*
X734471Y443210D03*
X737621D03*
X731322D03*
Y455809D03*
X737621Y458959D03*
X731322D03*
Y462108D03*
X734471Y452659D03*
X731322D03*
Y449510D03*
X734471Y458959D03*
X731322Y465258D03*
Y477856D03*
X737621Y471557D03*
X734471Y468407D03*
X731322D03*
X731321Y474707D03*
X731322Y471557D03*
X737621Y481006D03*
X734471D03*
X739699Y770144D03*
X734841Y766798D03*
X739699D03*
Y783530D03*
Y776837D03*
X734841Y773491D03*
Y780184D03*
X739699D03*
Y773491D03*
Y786877D03*
Y800263D03*
Y793570D03*
X734841Y803609D03*
Y796916D03*
Y790223D03*
X739699Y803609D03*
Y796916D03*
Y790223D03*
Y820341D03*
Y813648D03*
Y806955D03*
X734841Y816995D03*
Y810302D03*
X739699Y816995D03*
Y810302D03*
Y830381D03*
X734841Y833727D03*
Y827034D03*
X739699Y833727D03*
Y823688D03*
Y827034D03*
Y850459D03*
Y843766D03*
Y837074D03*
X734841Y847113D03*
Y840420D03*
X739699Y847113D03*
Y840420D03*
Y867192D03*
Y857152D03*
X734841Y863845D03*
Y853806D03*
X739699D03*
Y860499D03*
Y863845D03*
Y880577D03*
Y873885D03*
X734841Y883924D03*
Y877231D03*
Y870538D03*
X739699Y883924D03*
Y877231D03*
Y870538D03*
Y893963D03*
Y887270D03*
X734841Y900656D03*
Y890617D03*
X739699D03*
Y897310D03*
Y900656D03*
Y917389D03*
Y910696D03*
Y904003D03*
X734841Y914042D03*
Y907349D03*
X739699Y914042D03*
Y907349D03*
Y930774D03*
Y924081D03*
X734841Y927428D03*
Y920735D03*
X739699Y927428D03*
Y920735D03*
Y934121D03*
Y947507D03*
Y940814D03*
X734841Y944160D03*
Y937467D03*
X739699Y944160D03*
Y937467D03*
Y964239D03*
Y954200D03*
X734841Y960892D03*
Y950853D03*
X739699Y960892D03*
Y950853D03*
Y957546D03*
Y977625D03*
Y970932D03*
X734841Y980971D03*
Y974278D03*
Y967585D03*
X739699Y980971D03*
Y974278D03*
Y967585D03*
Y991011D03*
Y984318D03*
X734841Y987664D03*
X739699Y994357D03*
Y987664D03*
Y1031168D03*
Y1024475D03*
Y1017782D03*
X734841Y1027822D03*
Y1017782D03*
X739699Y1027822D03*
Y1021129D03*
Y1044554D03*
Y1037861D03*
X734841Y1047900D03*
Y1041207D03*
Y1034515D03*
X739699Y1047900D03*
Y1041207D03*
Y1034514D03*
Y1057940D03*
Y1051247D03*
X734841Y1061286D03*
Y1054593D03*
X739699Y1061286D03*
Y1054593D03*
Y1078018D03*
Y1071326D03*
Y1064633D03*
X734841Y1074672D03*
Y1067979D03*
X739699Y1074672D03*
Y1067979D03*
Y1094751D03*
Y1088058D03*
X734841Y1091404D03*
Y1084711D03*
X739699Y1091404D03*
Y1081365D03*
Y1084711D03*
Y1108137D03*
Y1101444D03*
X734841Y1111483D03*
Y1104790D03*
Y1098097D03*
X739699D03*
Y1111483D03*
Y1104790D03*
Y1124869D03*
Y1114829D03*
X734841Y1128215D03*
Y1121522D03*
X739699Y1128215D03*
Y1118176D03*
Y1121522D03*
Y1144948D03*
Y1138255D03*
Y1131562D03*
X734841Y1141601D03*
Y1134908D03*
X739699Y1141601D03*
Y1134908D03*
Y1161680D03*
Y1151641D03*
X734841Y1158333D03*
Y1148294D03*
X739699D03*
Y1154987D03*
Y1158333D03*
Y1175066D03*
Y1168373D03*
X734841Y1171719D03*
Y1165026D03*
X739699Y1171719D03*
Y1165026D03*
Y1188452D03*
Y1181759D03*
X734841Y1185105D03*
Y1178412D03*
X739699Y1185105D03*
Y1178412D03*
Y1191798D03*
Y1205184D03*
Y1198491D03*
X734841Y1208530D03*
Y1201837D03*
Y1195144D03*
X739699Y1208530D03*
Y1201837D03*
Y1195144D03*
Y1225263D03*
Y1218570D03*
Y1211877D03*
X734841Y1221916D03*
Y1215223D03*
X739699Y1221916D03*
Y1215223D03*
Y1241995D03*
Y1235302D03*
X734841Y1238648D03*
Y1231955D03*
X739699Y1238648D03*
Y1228609D03*
Y1231955D03*
Y1248688D03*
X734841Y1245341D03*
X739699D03*
Y1258727D03*
X734967Y1252034D03*
X737580Y1262074D03*
X745546Y1273364D03*
X742746D03*
X731372Y1273464D03*
X739697Y1265420D03*
X755841Y766798D03*
X748399Y770144D03*
X755841D03*
Y780184D03*
Y773491D03*
X748399Y783530D03*
Y776837D03*
X755841D03*
Y786877D03*
Y783530D03*
Y803609D03*
Y796916D03*
Y790223D03*
X748399Y800263D03*
Y793570D03*
X755841Y800263D03*
Y793570D03*
Y816995D03*
Y810302D03*
X748399Y820341D03*
Y813648D03*
Y806955D03*
X755841Y813648D03*
Y806955D03*
Y820341D03*
Y833727D03*
Y827034D03*
X748399Y830381D03*
X755841D03*
Y823688D03*
Y847113D03*
Y840420D03*
X748399Y850459D03*
Y843766D03*
Y837074D03*
X755841Y850459D03*
Y843766D03*
Y837074D03*
Y863845D03*
Y853806D03*
X748399Y867192D03*
Y857152D03*
X755841Y867192D03*
Y860499D03*
Y857152D03*
Y883924D03*
Y877231D03*
Y870538D03*
X748399Y880577D03*
Y873885D03*
X755841D03*
Y880577D03*
Y900656D03*
Y890617D03*
X748399Y893963D03*
Y887270D03*
X755841D03*
Y897310D03*
Y893963D03*
Y914042D03*
Y907349D03*
X748399Y917389D03*
Y910696D03*
Y904003D03*
X755841Y917389D03*
Y910696D03*
Y904003D03*
Y927428D03*
Y920735D03*
X748399Y930774D03*
Y924081D03*
X755841D03*
Y934121D03*
Y930774D03*
Y944160D03*
Y937467D03*
X748399Y947507D03*
Y940814D03*
X755841Y947507D03*
Y940814D03*
Y960892D03*
Y950853D03*
X748399Y964239D03*
Y954200D03*
X755841Y964239D03*
Y957546D03*
Y954200D03*
Y980971D03*
Y974278D03*
Y967585D03*
X748399Y977625D03*
Y970932D03*
X755841Y977625D03*
X755741Y970932D03*
X755841Y987664D03*
X748399Y991011D03*
Y984318D03*
X755841Y991011D03*
Y984318D03*
Y994357D03*
Y1027822D03*
Y1017782D03*
X748399Y1031168D03*
Y1024475D03*
Y1017782D03*
X755841Y1021129D03*
Y1024475D03*
Y1031168D03*
Y1047900D03*
Y1041207D03*
Y1034515D03*
X748399Y1044554D03*
Y1037861D03*
X755541Y1044554D03*
Y1037861D03*
X755841Y1054593D03*
Y1061286D03*
X748399Y1057940D03*
Y1051247D03*
X755841D03*
X755541Y1057940D03*
X755841Y1067979D03*
Y1074672D03*
X748399Y1078018D03*
Y1071326D03*
Y1064633D03*
X755676Y1071326D03*
X755741Y1064633D03*
X755841Y1078018D03*
Y1084711D03*
Y1091404D03*
X748399Y1094751D03*
Y1088058D03*
X755841Y1094751D03*
Y1088058D03*
Y1081365D03*
Y1111483D03*
Y1104790D03*
Y1098097D03*
X748399Y1108137D03*
Y1101444D03*
X755676Y1108137D03*
X755841Y1101444D03*
Y1128215D03*
Y1121522D03*
X748399Y1124869D03*
Y1114829D03*
X755841Y1124869D03*
Y1118176D03*
Y1114829D03*
Y1141601D03*
Y1134908D03*
X748399Y1144948D03*
Y1138255D03*
Y1131562D03*
X755841Y1144947D03*
Y1138255D03*
Y1131562D03*
Y1158333D03*
Y1148294D03*
X748399Y1161680D03*
Y1151641D03*
X755841Y1161680D03*
Y1154987D03*
Y1151640D03*
Y1171719D03*
Y1165026D03*
X748399Y1175066D03*
Y1168373D03*
X755841Y1175066D03*
Y1168373D03*
Y1185105D03*
Y1178412D03*
X748399Y1188452D03*
Y1181759D03*
X755676D03*
X755841Y1191798D03*
X755676Y1188452D03*
X755841Y1208530D03*
Y1201837D03*
Y1195144D03*
X748399Y1205184D03*
Y1198491D03*
X755841Y1205184D03*
Y1198491D03*
Y1221916D03*
Y1215223D03*
X748399Y1225263D03*
Y1218570D03*
Y1211877D03*
X755841Y1218569D03*
Y1211877D03*
Y1225262D03*
Y1238648D03*
Y1231955D03*
X748399Y1241995D03*
Y1235302D03*
X755841Y1241995D03*
Y1235302D03*
Y1228609D03*
Y1245341D03*
X748283Y1256964D03*
X748399Y1248688D03*
X750890Y1248500D03*
X755890Y1255381D03*
X753000Y1261352D03*
X755841Y1252034D03*
Y1248688D03*
X750040Y1254179D03*
X758746Y1273364D03*
X761546D03*
X755841Y1262074D03*
X755797Y1265420D03*
X769399Y770144D03*
X778099D03*
X764541Y766798D03*
X769399D03*
Y783530D03*
X778099D03*
X769399Y776837D03*
X778099D03*
X764541Y780184D03*
Y773491D03*
X769399Y800263D03*
X778099D03*
X769399Y793570D03*
X778099D03*
X764541Y803609D03*
Y796916D03*
Y790223D03*
X769399Y820341D03*
X778099D03*
X769399Y813648D03*
X778099D03*
X769399Y806955D03*
X778099D03*
X764541Y816995D03*
Y810302D03*
X769399Y830381D03*
X778099D03*
X764541Y833727D03*
Y827034D03*
X769399Y850459D03*
X778099D03*
Y843766D03*
X769399D03*
Y837074D03*
X778099D03*
X764541Y847113D03*
Y840420D03*
X778099Y867192D03*
X769399D03*
Y857152D03*
X778099D03*
X764541Y863845D03*
Y853806D03*
X769399Y880577D03*
X778099D03*
X769399Y873885D03*
X778099D03*
X764541Y883924D03*
Y877231D03*
Y870538D03*
X778099Y893963D03*
X769399D03*
Y887270D03*
X778099D03*
X764541Y900656D03*
Y890617D03*
X769399Y917389D03*
X778099D03*
X769399Y910696D03*
X778099D03*
X769399Y904003D03*
X778099D03*
X764541Y914042D03*
Y907349D03*
X769399Y930774D03*
X778099D03*
X769399Y924081D03*
X778099D03*
X764541Y927428D03*
Y920735D03*
X769399Y947507D03*
X778099D03*
X769399Y940814D03*
X778099D03*
X764541Y944160D03*
Y937467D03*
X769399Y964239D03*
X778099D03*
X769399Y954200D03*
X778099D03*
X764541Y960892D03*
Y950853D03*
X769399Y960892D03*
Y957546D03*
Y977625D03*
X778099D03*
X769399Y970932D03*
X778099D03*
X764541Y980971D03*
Y974278D03*
Y967585D03*
X769399D03*
Y991011D03*
X778099D03*
X769399Y984318D03*
X778099D03*
X764541Y987664D03*
X769399Y1031168D03*
X778099D03*
X769399Y1024475D03*
X778099D03*
X769399Y1017782D03*
X778099D03*
X764541Y1027822D03*
Y1017782D03*
X778099Y1044554D03*
X769399D03*
Y1037861D03*
X778099D03*
X764541Y1047900D03*
Y1041207D03*
Y1034515D03*
X769399Y1057940D03*
X778099D03*
X769399Y1051247D03*
X778099D03*
X764541Y1054593D03*
Y1061286D03*
X769399Y1054593D03*
X778099Y1078018D03*
X769399D03*
X778099Y1071326D03*
X769399D03*
Y1064633D03*
X778099D03*
X764541Y1067979D03*
Y1074672D03*
X778099Y1094751D03*
X769399D03*
X778099Y1088058D03*
X769399D03*
X764541Y1084711D03*
Y1091404D03*
X778099Y1108137D03*
X769399D03*
X778099Y1101444D03*
X769399D03*
X764541Y1111483D03*
Y1104790D03*
Y1098097D03*
X778099Y1124869D03*
X769399D03*
X778099Y1114829D03*
X769399D03*
X764541Y1128215D03*
Y1121522D03*
X778099Y1144948D03*
X769399D03*
X778099Y1138255D03*
X769399D03*
X778099Y1131562D03*
X769399D03*
X764541Y1141601D03*
Y1134908D03*
X778099Y1161680D03*
X769399D03*
X778099Y1151641D03*
X769399D03*
X764541Y1158333D03*
Y1148294D03*
X778099Y1175066D03*
X769399D03*
X778099Y1168373D03*
X769399D03*
X764541Y1171719D03*
Y1165026D03*
X778099Y1188452D03*
X769399D03*
X778099Y1181759D03*
X769399D03*
X764541Y1185105D03*
Y1178412D03*
X769399Y1205184D03*
X778099D03*
Y1198491D03*
X769399D03*
X764541Y1208530D03*
Y1201837D03*
Y1195144D03*
X778099Y1225263D03*
X769399D03*
X778099Y1218570D03*
X769399D03*
Y1211877D03*
X778099D03*
X764541Y1221916D03*
Y1215223D03*
X778099Y1241995D03*
X769399D03*
X778099Y1235302D03*
X769399D03*
X764541Y1238648D03*
Y1231955D03*
X778346Y1257264D03*
X778099Y1248688D03*
X769399D03*
X764541Y1245341D03*
X769399Y1258727D03*
X767080Y1262074D03*
X766148Y1255882D03*
X772446Y1273364D03*
X775246D03*
X769399Y1265420D03*
X785541Y766798D03*
X794241D03*
X785541Y773491D03*
X794241D03*
X785541Y780184D03*
X794241D03*
X785541Y803609D03*
X794241D03*
X785541Y790223D03*
X794241D03*
X785541Y796916D03*
X794241D03*
X785541Y816995D03*
X794241D03*
X785541Y810302D03*
X794241D03*
X785541Y833727D03*
X794241D03*
X785541Y827034D03*
X794241D03*
X785541Y840420D03*
X794241D03*
X785541Y847113D03*
X794241D03*
X785541Y853806D03*
X794241D03*
X785541Y863845D03*
X794241D03*
X785541Y883924D03*
X794241D03*
X785541Y870538D03*
X794241D03*
X785541Y877231D03*
X794241D03*
X785541Y900656D03*
X794241D03*
X785541Y890617D03*
X794241D03*
X785541Y907349D03*
X794241D03*
X785541Y914042D03*
X794241D03*
X785541Y920735D03*
X794241D03*
X785541Y927428D03*
X794241D03*
X785541Y937467D03*
X794241D03*
X785541Y944160D03*
X794241D03*
X785541Y960892D03*
X794241D03*
X785541Y950853D03*
X794241D03*
X785541Y964239D03*
Y957546D03*
Y954200D03*
Y980971D03*
X794241D03*
X785541Y974278D03*
X794241D03*
X785541Y967585D03*
X794241D03*
X785541Y987664D03*
X794241D03*
X785541Y994357D03*
Y1027822D03*
X794241D03*
X785541Y1017782D03*
X794241D03*
X785541Y1021129D03*
Y1024475D03*
Y1047900D03*
X794241D03*
X785541Y1041207D03*
X794241D03*
X785541Y1034515D03*
X794241D03*
X785541Y1054593D03*
X794241D03*
X785541Y1061286D03*
X794241D03*
X785541Y1051247D03*
Y1074672D03*
X794241D03*
X785541Y1067979D03*
X794241D03*
X785541Y1091404D03*
X794241D03*
X785541Y1084711D03*
X794241D03*
X785541Y1111483D03*
X794241D03*
X785541Y1104790D03*
X794241D03*
X785541Y1098097D03*
X794241D03*
X785541Y1128215D03*
X794241D03*
X785541Y1121522D03*
X794241D03*
X785541Y1141601D03*
X794241D03*
X785541Y1134908D03*
X794241D03*
X785541Y1158333D03*
X794241D03*
X785541Y1148294D03*
X794241D03*
X785541Y1171719D03*
X794241D03*
X785541Y1165026D03*
X794241D03*
X785541Y1178412D03*
X794241D03*
X785541Y1185105D03*
X794241D03*
X785541Y1208530D03*
X794241D03*
X785541Y1195144D03*
X794241D03*
X785541Y1201837D03*
X794241D03*
X785541Y1221916D03*
X794241D03*
X785541Y1215223D03*
X794241D03*
X785541Y1238648D03*
X794241D03*
X785541Y1231955D03*
X794241D03*
X785541Y1245341D03*
X794241D03*
X785541Y1255381D03*
X783130Y1259372D03*
X794157Y1252034D03*
X785541Y1248688D03*
X796880Y1262074D03*
X796280Y1254402D03*
X788446Y1273364D03*
X791246D03*
X785541Y1265420D03*
Y1262074D03*
X799099Y770144D03*
X807799D03*
X797417Y767345D03*
X799099Y783530D03*
X807799D03*
X799099Y776837D03*
X807799D03*
X799099Y780184D03*
Y773491D03*
Y786877D03*
Y800263D03*
X807799D03*
X799099Y793570D03*
X807799D03*
X799099Y803609D03*
Y796916D03*
Y790223D03*
Y820341D03*
X807799D03*
X799099Y806955D03*
X807799D03*
X799099Y813648D03*
X807799D03*
X799099Y816995D03*
Y810302D03*
Y830381D03*
X807799D03*
X799099Y833727D03*
Y823688D03*
Y827034D03*
Y850459D03*
X807799D03*
X799099Y837074D03*
X807799D03*
X799099Y843766D03*
X807799D03*
X799099Y847113D03*
Y840420D03*
Y867192D03*
X807799D03*
X799099Y857152D03*
X807799D03*
X799099Y853806D03*
Y860499D03*
Y863845D03*
Y873885D03*
X807799D03*
X799099Y880577D03*
X807799D03*
X799099Y883924D03*
Y877231D03*
Y870538D03*
Y887270D03*
X807799D03*
X799099Y893963D03*
X807799D03*
X799099Y890617D03*
Y897310D03*
Y900656D03*
Y917389D03*
X807799D03*
X799099Y904003D03*
X807799D03*
X799099Y910696D03*
X807799D03*
X799099Y914042D03*
Y907349D03*
Y930774D03*
X807799D03*
X799099Y924081D03*
X807799D03*
X799099Y927428D03*
Y920735D03*
Y934121D03*
Y947507D03*
X807799D03*
X799099Y940814D03*
X807799D03*
X799099Y944160D03*
Y937467D03*
Y964239D03*
X807799D03*
X799099Y954200D03*
X807799D03*
X799099Y960892D03*
Y950853D03*
Y957546D03*
Y970932D03*
X807799D03*
X799099Y977625D03*
X807799D03*
X799099Y980971D03*
Y974278D03*
Y967585D03*
Y991011D03*
X807799D03*
X799099Y984318D03*
X807799D03*
X799099Y994357D03*
Y987664D03*
Y1031168D03*
X807799D03*
X799099Y1024475D03*
X807799D03*
X799099Y1017782D03*
X807799D03*
X799099Y1027822D03*
Y1021129D03*
Y1037861D03*
X807799D03*
X799099Y1044554D03*
X807799D03*
X799099Y1047900D03*
Y1041207D03*
Y1034515D03*
Y1057940D03*
X807799D03*
X799099Y1051247D03*
X807799D03*
X799099Y1061286D03*
Y1054593D03*
Y1078018D03*
X807799D03*
X799099Y1071326D03*
X807799D03*
X799099Y1064633D03*
X807799D03*
X799099Y1074672D03*
Y1067979D03*
Y1094751D03*
X807799D03*
X799099Y1088058D03*
X807799D03*
X799099Y1091404D03*
Y1081365D03*
Y1084711D03*
Y1108137D03*
X807799D03*
X799099Y1101444D03*
X807799D03*
X799099Y1098097D03*
Y1111483D03*
Y1104790D03*
Y1124869D03*
X807799D03*
X799099Y1114829D03*
X807799D03*
X799099Y1128215D03*
Y1118176D03*
Y1121522D03*
Y1144948D03*
X807799D03*
X799099Y1138255D03*
X807799D03*
X799099Y1131562D03*
X807799D03*
X799099Y1141601D03*
Y1134908D03*
Y1161680D03*
X807799D03*
X799099Y1151641D03*
X807799D03*
X799099Y1148294D03*
Y1154987D03*
Y1158333D03*
Y1175066D03*
X807799D03*
X799099Y1168373D03*
X807799D03*
X799099Y1171719D03*
Y1165026D03*
Y1188452D03*
X807799D03*
X799099Y1181759D03*
X807799D03*
X799099Y1185105D03*
Y1178412D03*
Y1191798D03*
Y1205184D03*
X807799D03*
X799099Y1198491D03*
X807799D03*
X799099Y1208530D03*
Y1201837D03*
Y1195144D03*
Y1225263D03*
X807799D03*
X799099Y1211877D03*
X807799D03*
X799099Y1218570D03*
X807799D03*
X799099Y1221916D03*
Y1215223D03*
Y1241995D03*
X807799D03*
X799099Y1235302D03*
X807799D03*
X799099Y1238648D03*
Y1228609D03*
Y1231955D03*
Y1248688D03*
X807799D03*
X808046Y1257664D03*
X799099Y1245341D03*
Y1258727D03*
X812440D03*
X804946Y1273364D03*
X802146D03*
X799099Y1265420D03*
X815241Y766798D03*
X823941D03*
X815241Y770144D03*
Y773491D03*
X823941D03*
X815241Y780184D03*
X823941D03*
X815241Y776837D03*
Y786877D03*
Y783530D03*
Y803609D03*
X823941D03*
X815241Y790223D03*
X823941D03*
X815241Y796916D03*
X823941D03*
X815241Y800263D03*
Y793570D03*
Y816995D03*
X823941D03*
X815241Y810302D03*
X823941D03*
X815241Y813648D03*
Y806955D03*
Y820341D03*
Y833727D03*
X823941D03*
X815241Y827034D03*
X823941D03*
X815241Y830381D03*
Y823688D03*
Y840420D03*
X823941D03*
X815241Y847113D03*
X823941D03*
X815241Y850459D03*
Y843766D03*
Y837074D03*
Y853806D03*
X823941D03*
X815241Y863845D03*
X823941D03*
X815241Y867192D03*
Y860499D03*
Y857152D03*
Y883924D03*
X823941D03*
X815241Y870538D03*
X823941D03*
X815241Y877231D03*
X823941D03*
X815241Y873885D03*
Y880577D03*
Y900656D03*
X823941D03*
X815241Y890617D03*
X823941D03*
X815241Y887270D03*
Y897310D03*
Y893963D03*
Y907349D03*
X823941D03*
X815241Y914042D03*
X823941D03*
X815241Y917389D03*
Y910696D03*
Y904003D03*
Y920735D03*
X823941D03*
X815241Y927428D03*
X823941D03*
X815241Y924081D03*
Y934121D03*
Y930774D03*
Y937467D03*
X823941D03*
X815241Y944160D03*
X823941D03*
X815241Y947507D03*
Y940814D03*
Y960892D03*
X823941D03*
X815241Y950853D03*
X823941D03*
X815241Y964239D03*
Y957546D03*
Y954200D03*
Y980971D03*
X823941D03*
X815241Y974278D03*
X823941D03*
X815241Y967585D03*
X823941D03*
X815241Y977625D03*
Y970932D03*
Y987664D03*
X823941D03*
X815241Y991011D03*
Y984318D03*
Y994357D03*
Y1027822D03*
X823941D03*
X815241Y1017782D03*
X823941D03*
X815241Y1021129D03*
Y1024475D03*
Y1031168D03*
Y1047900D03*
X823941D03*
X815241Y1041207D03*
X823941D03*
X815241Y1034515D03*
X823941D03*
X815241Y1044554D03*
Y1037861D03*
Y1054593D03*
X823941D03*
X815241Y1061286D03*
X823941D03*
X814941Y1051247D03*
X815241Y1074672D03*
X823941D03*
X815241Y1067979D03*
X823941D03*
X815241Y1071325D03*
Y1064633D03*
Y1078018D03*
Y1091404D03*
X823941D03*
X815241Y1084711D03*
X823941D03*
X815241Y1094751D03*
Y1088058D03*
Y1081365D03*
Y1111483D03*
X823941D03*
X815241Y1104790D03*
X823941D03*
X815241Y1098097D03*
X823941D03*
X815241Y1108136D03*
Y1101444D03*
Y1128215D03*
X823941D03*
X815241Y1121522D03*
X823941D03*
X815241Y1124869D03*
Y1118176D03*
Y1114829D03*
Y1141601D03*
X823941D03*
X815241Y1134908D03*
X823941D03*
X815241Y1144947D03*
Y1138255D03*
Y1131562D03*
Y1158333D03*
X823941D03*
X815241Y1148294D03*
X823941D03*
X815241Y1161680D03*
Y1154987D03*
Y1151640D03*
Y1171719D03*
X823941D03*
X815241Y1165026D03*
X823941D03*
X815241Y1175066D03*
Y1168373D03*
Y1178412D03*
X823941D03*
X815241Y1185105D03*
X823941D03*
X815241Y1181758D03*
Y1191798D03*
Y1188451D03*
Y1208530D03*
X823941D03*
X815241Y1195144D03*
X823941D03*
X815241Y1201837D03*
X823941D03*
X815241Y1205184D03*
Y1198491D03*
Y1221916D03*
X823941D03*
X815241Y1215223D03*
X823941D03*
X815241Y1218570D03*
Y1211877D03*
Y1225263D03*
Y1238648D03*
X823941D03*
X815241Y1231955D03*
X823941D03*
X815241Y1241995D03*
Y1235302D03*
Y1228609D03*
Y1245341D03*
X823941D03*
X815241Y1255381D03*
X826750Y1262074D03*
X823877Y1252034D03*
X815241Y1248688D03*
X826501Y1254553D03*
X820946Y1273364D03*
X818146D03*
X815241Y1265420D03*
Y1262074D03*
X828799Y770144D03*
X837499D03*
X828699Y766798D03*
X828799Y783530D03*
X837499D03*
X828799Y776837D03*
X837499D03*
Y800263D03*
X828799D03*
X837499Y793570D03*
X828799D03*
Y820341D03*
X837499D03*
X828799Y813648D03*
X837499D03*
X828799Y806955D03*
X837499D03*
X828799Y830381D03*
X837499D03*
X828799Y850459D03*
X837499D03*
X828799Y843766D03*
X837499D03*
X828799Y837074D03*
X837499D03*
X828799Y867192D03*
X837499D03*
X828799Y857152D03*
X837499D03*
X828799Y880577D03*
X837499D03*
X828799Y873885D03*
X837499D03*
X828799Y893963D03*
X837499D03*
X828799Y887270D03*
X837499D03*
X828799Y917389D03*
X837499D03*
Y904003D03*
X828799D03*
X837499Y910696D03*
X828799D03*
Y930774D03*
X837499D03*
X828799Y924081D03*
X837499D03*
X828799Y947507D03*
X837499D03*
X828799Y940814D03*
X837499D03*
X828799Y964239D03*
X837499D03*
X828799Y954200D03*
X837499D03*
X828799Y960892D03*
Y957546D03*
Y977625D03*
X837499D03*
X828799Y970932D03*
X837499D03*
X828799Y967585D03*
Y991011D03*
X837499D03*
X828799Y984318D03*
X837499D03*
X828799Y1031168D03*
X837499D03*
X828799Y1024475D03*
X837499D03*
X828799Y1017782D03*
X837499D03*
X828799Y1044554D03*
X837499D03*
X828799Y1037861D03*
X837499D03*
X828799Y1057940D03*
X837499D03*
X828799Y1051247D03*
X837499D03*
X828799Y1054593D03*
Y1078018D03*
X837499D03*
X828799Y1071326D03*
X837499D03*
X828799Y1064633D03*
X837499D03*
X828799Y1094751D03*
X837499D03*
Y1088058D03*
X828799D03*
X837499Y1108137D03*
X828799D03*
Y1101444D03*
X837499D03*
Y1124869D03*
X828799D03*
X837499Y1114829D03*
X828799D03*
X837499Y1144948D03*
X828799D03*
X837499Y1138255D03*
X828799D03*
X837499Y1131562D03*
X828799D03*
X837499Y1161680D03*
X828799D03*
X837499Y1151641D03*
X828799D03*
X837499Y1175066D03*
X828799D03*
X837499Y1168373D03*
X828799D03*
Y1188452D03*
X837499D03*
Y1181759D03*
X828799D03*
X837499Y1205184D03*
X828799D03*
X837499Y1198491D03*
X828799D03*
X837499Y1225263D03*
X828799D03*
X837499Y1218570D03*
X828799D03*
X837499Y1211877D03*
X828799D03*
X837499Y1241995D03*
X828799D03*
X837499Y1235302D03*
X828799D03*
X837499Y1248688D03*
X828799D03*
X837846Y1256964D03*
X828799Y1258727D03*
X842630Y1256912D03*
X839246Y1273064D03*
X842046D03*
X831846Y1273364D03*
X834646D03*
X828799Y1265420D03*
X844941Y766798D03*
X853641D03*
X844941Y780184D03*
X853641D03*
X844941Y773491D03*
X853641D03*
X844941Y803609D03*
X853641D03*
X844941Y796916D03*
X853641D03*
X844941Y790223D03*
X853641D03*
X844941Y816995D03*
X853641D03*
X844941Y810302D03*
X853641D03*
X844941Y833727D03*
X853641D03*
X844941Y827034D03*
X853641D03*
X844941Y847113D03*
X853641D03*
X844941Y840420D03*
X853641D03*
X844941Y863845D03*
X853641D03*
X844941Y853806D03*
X853641D03*
X844941Y883924D03*
X853641D03*
X844941Y877231D03*
X853641D03*
X844941Y870538D03*
X853641D03*
X844941Y900656D03*
X853641D03*
X844941Y890617D03*
X853641D03*
X844941Y914042D03*
X853641D03*
X844941Y907349D03*
X853641D03*
X844941Y927428D03*
X853641D03*
X844941Y920735D03*
X853641D03*
X844941Y944160D03*
X853641D03*
X844941Y937467D03*
X853641D03*
X844941Y960892D03*
X853641D03*
X844941Y950853D03*
X853641D03*
X844941Y964239D03*
X844841Y957546D03*
Y954200D03*
X844941Y980971D03*
X853641D03*
X844941Y974278D03*
X853641D03*
X844941Y967585D03*
X853641D03*
X844941Y987664D03*
X853641D03*
X844841Y994357D03*
X844941Y1027822D03*
X853641D03*
X844941Y1017782D03*
X853641D03*
X844941Y1021129D03*
Y1024475D03*
Y1047900D03*
X853641D03*
X844941Y1041207D03*
X853641D03*
X844941Y1034515D03*
X853641D03*
X844941Y1061286D03*
X853641D03*
X844941Y1054593D03*
X853641D03*
X844941Y1051247D03*
Y1074672D03*
X853641D03*
X844941Y1067979D03*
X853641D03*
X844941Y1091404D03*
X853641D03*
X844941Y1084711D03*
X853641D03*
X844941Y1111483D03*
X853641D03*
X844941Y1104790D03*
X853641D03*
X844941Y1098097D03*
X853641D03*
X844941Y1128215D03*
X853641D03*
X844941Y1121522D03*
X853641D03*
X844941Y1141601D03*
X853641D03*
X844941Y1134908D03*
X853641D03*
X844941Y1158333D03*
X853641D03*
X844941Y1148294D03*
X853641D03*
X844941Y1171719D03*
X853641D03*
X844941Y1165026D03*
X853641D03*
X844941Y1185105D03*
X853641D03*
X844941Y1178412D03*
X853641D03*
X844941Y1208530D03*
X853641D03*
X844941Y1201837D03*
X853641D03*
X844941Y1195144D03*
X853641D03*
X844941Y1221916D03*
X853641D03*
X844941Y1215223D03*
X853641D03*
X844941Y1238648D03*
X853641D03*
X844941Y1231955D03*
X853641D03*
X844941Y1245341D03*
X853641D03*
X844941Y1258727D03*
Y1252034D03*
X844997Y1248155D03*
X844941Y1265420D03*
Y1262074D03*
X918264Y506011D03*
X998205Y195735D03*
Y192191D03*
X1000705Y195735D03*
Y192191D03*
X998205Y199278D03*
X1000705D03*
X998205Y202821D03*
X1000705D03*
X1003841Y770144D03*
Y783530D03*
Y776837D03*
Y800263D03*
Y793570D03*
Y820341D03*
Y813648D03*
Y806955D03*
Y830381D03*
Y850459D03*
Y843766D03*
Y837074D03*
Y867192D03*
Y857152D03*
Y880577D03*
Y873885D03*
Y893963D03*
Y887270D03*
Y917389D03*
Y910696D03*
Y904003D03*
Y930774D03*
Y924081D03*
Y947507D03*
Y940814D03*
Y964239D03*
Y954200D03*
Y977625D03*
Y970932D03*
Y991011D03*
Y984318D03*
Y1031168D03*
Y1024475D03*
Y1017782D03*
Y1044554D03*
Y1037861D03*
Y1057940D03*
Y1051247D03*
Y1078018D03*
Y1071326D03*
Y1064633D03*
Y1094751D03*
Y1088058D03*
Y1108137D03*
Y1101444D03*
Y1124869D03*
Y1114829D03*
Y1144948D03*
Y1138255D03*
Y1131562D03*
Y1161680D03*
Y1151641D03*
Y1175066D03*
Y1168373D03*
Y1188452D03*
Y1181759D03*
Y1205184D03*
Y1198491D03*
Y1225263D03*
Y1218570D03*
Y1211877D03*
Y1241995D03*
Y1235302D03*
Y1248688D03*
X1001970Y1251522D03*
X1003831Y1259077D03*
X1002070Y1256942D03*
X1003841Y1265420D03*
Y1262074D03*
X1019983Y766798D03*
X1012541Y770144D03*
X1012769Y766798D03*
X1019983Y780184D03*
Y773491D03*
X1012541Y783530D03*
Y776837D03*
X1019983Y803609D03*
Y796916D03*
Y790223D03*
X1012541Y800263D03*
Y793570D03*
X1019983Y816995D03*
Y810302D03*
X1012541Y820341D03*
Y813648D03*
Y806955D03*
X1019983Y833727D03*
Y827034D03*
X1012541Y830381D03*
X1019983Y847113D03*
Y840420D03*
X1012541Y850459D03*
Y843766D03*
Y837074D03*
X1019983Y863845D03*
Y853806D03*
X1012541Y867192D03*
Y857152D03*
X1019983Y883924D03*
Y877231D03*
Y870538D03*
X1012541Y880577D03*
Y873885D03*
X1019983Y900656D03*
Y890617D03*
X1012541Y893963D03*
Y887270D03*
X1019983Y914042D03*
Y907349D03*
X1012541Y917389D03*
Y910696D03*
Y904003D03*
X1019983Y927428D03*
Y920735D03*
X1012541Y930774D03*
Y924081D03*
X1019983Y944160D03*
Y937467D03*
X1012541Y947507D03*
Y940814D03*
X1019983Y960892D03*
Y950853D03*
X1012541Y964239D03*
Y954200D03*
Y960892D03*
Y957546D03*
X1019983Y980971D03*
Y974278D03*
Y967585D03*
X1012541Y977625D03*
Y970932D03*
Y967585D03*
X1019983Y987664D03*
X1012541Y991011D03*
Y984318D03*
X1019983Y994357D03*
Y1027822D03*
Y1017782D03*
X1012541Y1031168D03*
Y1024475D03*
Y1017782D03*
X1019983Y1047900D03*
Y1041207D03*
Y1034515D03*
X1012541Y1044554D03*
Y1037861D03*
X1019983Y1061286D03*
Y1054593D03*
X1012541Y1057940D03*
Y1051247D03*
Y1054593D03*
X1019983Y1067979D03*
Y1074672D03*
X1012541Y1078018D03*
Y1071326D03*
Y1064633D03*
X1019983Y1091404D03*
Y1084711D03*
X1012541Y1094751D03*
Y1088058D03*
X1019983Y1111483D03*
Y1104790D03*
Y1098097D03*
X1012541Y1108137D03*
Y1101444D03*
X1019983Y1128215D03*
Y1121522D03*
X1012541Y1124869D03*
Y1114829D03*
X1019983Y1141601D03*
Y1134908D03*
X1012541Y1144948D03*
Y1138255D03*
Y1131562D03*
X1019983Y1158333D03*
Y1148294D03*
X1012541Y1161680D03*
Y1151641D03*
X1019983Y1171719D03*
Y1165026D03*
X1012541Y1175066D03*
Y1168373D03*
X1019983Y1185105D03*
Y1178412D03*
X1012541Y1188452D03*
Y1181759D03*
X1019983Y1208530D03*
Y1201837D03*
Y1195144D03*
X1012541Y1205184D03*
Y1198491D03*
X1019983Y1221916D03*
Y1215223D03*
X1012541Y1225263D03*
Y1218570D03*
Y1211877D03*
X1019983Y1238648D03*
Y1231955D03*
X1012541Y1241995D03*
Y1235302D03*
X1012543Y1257198D03*
X1019983Y1245341D03*
X1012541Y1248688D03*
X1017900Y1247632D03*
X1019983Y1255381D03*
Y1252034D03*
Y1248688D03*
X1017111Y1273299D03*
X1014111D03*
X1019983Y1262074D03*
Y1265420D03*
X1033541Y770144D03*
X1028683Y766798D03*
X1033441D03*
X1033541Y783530D03*
Y776837D03*
X1028683Y780184D03*
Y773491D03*
X1033541Y800263D03*
Y793570D03*
X1028683Y803609D03*
Y796916D03*
Y790223D03*
X1033541Y820341D03*
Y813648D03*
Y806955D03*
X1028683Y816995D03*
Y810302D03*
X1033541Y830381D03*
X1028683Y833727D03*
Y827034D03*
X1033541Y850459D03*
Y843766D03*
Y837074D03*
X1028683Y847113D03*
Y840420D03*
X1033541Y867192D03*
Y857152D03*
X1028683Y863845D03*
Y853806D03*
X1033541Y880577D03*
Y873885D03*
X1028683Y883924D03*
Y877231D03*
Y870538D03*
X1033541Y893963D03*
Y887270D03*
X1028683Y900656D03*
Y890617D03*
X1033541Y917389D03*
Y910696D03*
Y904003D03*
X1028683Y914042D03*
Y907349D03*
X1033541Y930774D03*
Y924081D03*
X1028683Y927428D03*
Y920735D03*
X1033541Y947507D03*
Y940814D03*
X1028683Y944160D03*
Y937467D03*
X1033541Y964239D03*
Y954200D03*
X1028683Y960892D03*
Y950853D03*
Y964239D03*
Y957546D03*
Y954200D03*
X1033541Y977625D03*
Y970932D03*
X1028683Y980971D03*
Y974278D03*
Y967585D03*
X1033541Y991011D03*
Y984318D03*
X1028683Y987664D03*
X1033541Y1031168D03*
Y1017782D03*
Y1024475D03*
X1028683Y1027822D03*
Y1017782D03*
Y1021129D03*
Y1024475D03*
X1033541Y1044554D03*
Y1037861D03*
X1028683Y1047900D03*
Y1041207D03*
Y1034515D03*
X1033541Y1057940D03*
Y1051247D03*
X1028683Y1061286D03*
Y1054593D03*
Y1051247D03*
X1033541Y1078018D03*
Y1071326D03*
Y1064633D03*
X1028683Y1067979D03*
Y1074672D03*
X1033541Y1094751D03*
Y1088058D03*
X1028683Y1091404D03*
Y1084711D03*
X1033541Y1108137D03*
Y1101444D03*
X1028683Y1111483D03*
Y1104790D03*
Y1098097D03*
X1033541Y1114829D03*
Y1124869D03*
X1028683Y1128215D03*
Y1121522D03*
X1033541Y1144948D03*
Y1138255D03*
Y1131562D03*
X1028683Y1141601D03*
Y1134908D03*
X1033541Y1161680D03*
Y1151641D03*
X1028683Y1158333D03*
Y1148294D03*
X1033541Y1175066D03*
Y1168373D03*
X1028683Y1171719D03*
Y1165026D03*
X1033541Y1188452D03*
Y1181759D03*
X1028683Y1185105D03*
Y1178412D03*
X1033541Y1205184D03*
Y1198491D03*
X1028683Y1208530D03*
Y1201837D03*
Y1195144D03*
X1033541Y1225263D03*
Y1218570D03*
Y1211877D03*
X1028683Y1221916D03*
Y1215223D03*
X1033541Y1241995D03*
Y1235302D03*
X1028683Y1238648D03*
Y1231955D03*
X1033541Y1248688D03*
X1028683Y1245341D03*
X1033541Y1258727D03*
X1030830Y1261302D03*
X1030270Y1256042D03*
X1036588Y1273344D03*
X1022888D03*
X1025688D03*
X1033541Y1265420D03*
X1030780Y1266532D03*
X1049683Y766798D03*
X1042241Y770144D03*
X1049683Y780184D03*
Y773491D03*
X1042241Y783530D03*
Y776837D03*
Y780184D03*
Y773491D03*
Y786877D03*
X1049683Y803609D03*
Y796916D03*
Y790223D03*
X1042241Y800263D03*
Y793570D03*
Y803609D03*
Y796916D03*
Y790223D03*
X1049683Y816995D03*
Y810302D03*
X1042241Y820341D03*
Y813648D03*
Y806955D03*
Y816995D03*
Y810302D03*
X1049683Y833727D03*
Y827034D03*
X1042241Y830381D03*
Y833727D03*
Y823688D03*
Y827034D03*
X1049683Y847113D03*
Y840420D03*
X1042241Y850459D03*
Y843766D03*
Y837074D03*
Y847113D03*
Y840420D03*
X1049683Y863845D03*
Y853806D03*
X1042241Y867192D03*
Y857152D03*
Y853806D03*
Y860499D03*
Y863845D03*
X1049683Y883924D03*
Y877231D03*
Y870538D03*
X1042241Y880577D03*
Y873885D03*
Y883924D03*
Y877231D03*
Y870538D03*
X1049683Y900656D03*
Y890617D03*
X1042241Y893963D03*
Y887270D03*
Y890617D03*
Y897310D03*
Y900656D03*
X1049683Y914042D03*
Y907349D03*
X1042241Y917389D03*
Y910696D03*
Y904003D03*
Y914042D03*
Y907349D03*
X1049683Y927428D03*
Y920735D03*
X1042241Y930774D03*
Y924081D03*
Y927428D03*
Y920735D03*
Y934121D03*
X1049683Y944160D03*
Y937467D03*
X1042241Y947507D03*
Y940814D03*
Y944160D03*
Y937467D03*
X1049683Y960892D03*
Y950853D03*
X1042241Y964239D03*
Y954200D03*
Y960892D03*
Y950853D03*
Y957546D03*
X1049683Y980971D03*
Y974278D03*
Y967585D03*
X1042241Y977625D03*
Y970932D03*
Y980971D03*
Y974278D03*
Y967585D03*
X1049683Y987664D03*
X1042241Y991011D03*
Y984318D03*
Y994357D03*
Y987664D03*
X1049683Y1027822D03*
Y1017782D03*
X1042241Y1031168D03*
Y1017782D03*
Y1024475D03*
Y1027822D03*
Y1021129D03*
X1049683Y1047900D03*
Y1041207D03*
Y1034515D03*
X1042241Y1044554D03*
Y1037861D03*
Y1047900D03*
Y1041207D03*
Y1034515D03*
X1049683Y1061286D03*
Y1054593D03*
X1042241Y1057940D03*
Y1051247D03*
Y1061286D03*
Y1054593D03*
X1049683Y1074672D03*
Y1067979D03*
X1042241Y1078018D03*
Y1071326D03*
Y1064633D03*
Y1074672D03*
Y1067979D03*
X1049683Y1091404D03*
Y1084711D03*
X1042241Y1094751D03*
Y1088058D03*
Y1091404D03*
Y1081365D03*
Y1084711D03*
X1049683Y1111483D03*
Y1104790D03*
Y1098097D03*
X1042241Y1108137D03*
Y1101444D03*
Y1098097D03*
Y1111483D03*
Y1104790D03*
Y1114829D03*
X1049683Y1128215D03*
Y1121522D03*
X1042241Y1124869D03*
Y1128215D03*
Y1118176D03*
Y1121522D03*
X1049683Y1141601D03*
Y1134908D03*
X1042241Y1144948D03*
Y1138255D03*
Y1131562D03*
Y1141601D03*
Y1134908D03*
Y1161680D03*
X1049683Y1158333D03*
Y1148294D03*
X1042241Y1151641D03*
Y1148294D03*
Y1154987D03*
Y1158333D03*
X1049683Y1171719D03*
Y1165026D03*
X1042241Y1175066D03*
Y1168373D03*
Y1171719D03*
Y1165026D03*
X1049683Y1185105D03*
Y1178412D03*
X1042241Y1188452D03*
Y1181759D03*
Y1185105D03*
Y1178412D03*
Y1191798D03*
X1049683Y1208530D03*
Y1201837D03*
Y1195144D03*
X1042241Y1205184D03*
Y1198491D03*
Y1208530D03*
Y1201837D03*
Y1195144D03*
X1049683Y1215223D03*
Y1221916D03*
X1042241Y1225263D03*
Y1218570D03*
Y1211877D03*
Y1221916D03*
Y1215223D03*
X1049683Y1238648D03*
Y1231955D03*
X1042241Y1241995D03*
Y1235302D03*
Y1238648D03*
Y1228609D03*
Y1231955D03*
X1042331Y1257488D03*
X1049683Y1245341D03*
X1042241Y1248688D03*
Y1245341D03*
X1047010Y1259222D03*
X1049683Y1258727D03*
X1052588Y1273344D03*
X1039388D03*
X1049683Y1265420D03*
Y1262074D03*
X1044930Y1263492D03*
X1063241Y770144D03*
X1058383Y766798D03*
Y770144D03*
X1063141Y766798D03*
X1063241Y783530D03*
Y776837D03*
X1058383Y780184D03*
Y773491D03*
Y776837D03*
Y786877D03*
Y783530D03*
X1063241Y800263D03*
Y793570D03*
X1058383Y803609D03*
Y796916D03*
Y790223D03*
Y800263D03*
Y793570D03*
X1063241Y820341D03*
Y813648D03*
Y806955D03*
X1058383Y816995D03*
Y810302D03*
Y813648D03*
Y806955D03*
Y820341D03*
X1063241Y830381D03*
X1058383Y833727D03*
Y827034D03*
Y830381D03*
Y823688D03*
X1063241Y850459D03*
Y843766D03*
Y837074D03*
X1058383Y847113D03*
Y840420D03*
Y850459D03*
Y843766D03*
Y837074D03*
X1063241Y867192D03*
Y857152D03*
X1058383Y863845D03*
Y853806D03*
Y867192D03*
Y860499D03*
Y857152D03*
X1063241Y880577D03*
Y873885D03*
X1058383Y883924D03*
Y877231D03*
Y870538D03*
Y873885D03*
Y880577D03*
X1063241Y893963D03*
Y887270D03*
X1058383Y900656D03*
Y890617D03*
Y887270D03*
Y897310D03*
Y893963D03*
X1063241Y917389D03*
Y910696D03*
Y904003D03*
X1058383Y914042D03*
Y907349D03*
Y917389D03*
Y910696D03*
Y904003D03*
X1063241Y930774D03*
Y924081D03*
X1058383Y927428D03*
Y920735D03*
Y924081D03*
Y934121D03*
Y930774D03*
X1063241Y947507D03*
Y940814D03*
X1058383Y944160D03*
Y937467D03*
Y947507D03*
Y940814D03*
X1063241Y964239D03*
Y954200D03*
X1058383Y960892D03*
Y950853D03*
Y964239D03*
Y957546D03*
Y954200D03*
X1063241Y977625D03*
Y970932D03*
X1058383Y980971D03*
Y974278D03*
Y967585D03*
Y977625D03*
Y970932D03*
X1063241Y991011D03*
Y984318D03*
X1058383Y987664D03*
Y991011D03*
Y984318D03*
Y994357D03*
X1063241Y1031168D03*
Y1024475D03*
Y1017782D03*
X1058383Y1027822D03*
Y1017782D03*
Y1021129D03*
Y1024475D03*
Y1031168D03*
X1063241Y1044554D03*
Y1037861D03*
X1058383Y1047900D03*
Y1041207D03*
Y1034515D03*
Y1044554D03*
Y1037861D03*
X1063241Y1057940D03*
Y1051247D03*
X1058383Y1061286D03*
Y1054593D03*
Y1051247D03*
X1063241Y1078018D03*
Y1071326D03*
Y1064633D03*
X1058383Y1074672D03*
Y1067979D03*
Y1071326D03*
Y1064633D03*
Y1078018D03*
X1063241Y1094751D03*
Y1088058D03*
X1058383Y1091404D03*
Y1084711D03*
Y1094751D03*
Y1088058D03*
Y1081365D03*
X1063241Y1108137D03*
Y1101444D03*
X1058383Y1111483D03*
Y1104790D03*
Y1098097D03*
Y1108137D03*
Y1101444D03*
X1063241Y1124869D03*
Y1114829D03*
X1058383Y1128215D03*
Y1121522D03*
Y1124869D03*
Y1118176D03*
Y1114829D03*
X1063241Y1144948D03*
Y1138255D03*
Y1131562D03*
X1058383Y1141601D03*
Y1134908D03*
Y1144948D03*
Y1138255D03*
Y1131562D03*
X1063241Y1161680D03*
Y1151641D03*
X1058383Y1158333D03*
Y1148294D03*
Y1161680D03*
Y1154987D03*
Y1151641D03*
X1063241Y1175066D03*
Y1168373D03*
X1058383Y1171719D03*
Y1165026D03*
Y1175066D03*
Y1168373D03*
X1063241Y1188452D03*
Y1181759D03*
X1058383Y1185105D03*
Y1178412D03*
Y1181759D03*
Y1191798D03*
Y1188452D03*
X1063241Y1205184D03*
Y1198491D03*
X1058383Y1208530D03*
Y1201837D03*
Y1195144D03*
Y1205184D03*
Y1198491D03*
X1063241Y1225263D03*
Y1218570D03*
Y1211877D03*
X1058383Y1215223D03*
Y1221916D03*
Y1218570D03*
Y1211877D03*
Y1225263D03*
X1063241Y1241995D03*
Y1235302D03*
X1058383Y1238648D03*
Y1231955D03*
Y1241995D03*
Y1235302D03*
Y1228609D03*
X1063241Y1248688D03*
X1058383Y1245341D03*
X1063241Y1258727D03*
X1061330Y1262074D03*
X1058383Y1248688D03*
X1059410Y1252272D03*
X1069088Y1273344D03*
X1066288D03*
X1055388D03*
X1063241Y1265420D03*
X1079383Y766798D03*
X1071941Y770144D03*
X1079383Y780184D03*
Y773491D03*
X1071941Y783530D03*
Y776837D03*
X1079383Y803609D03*
Y796916D03*
Y790223D03*
X1071941Y800263D03*
Y793570D03*
X1079383Y816995D03*
Y810302D03*
X1071941Y820341D03*
Y813648D03*
Y806955D03*
X1079383Y833727D03*
Y827034D03*
X1071941Y830381D03*
X1079383Y847113D03*
Y840420D03*
X1071941Y850459D03*
Y843766D03*
Y837074D03*
X1079383Y863845D03*
Y853806D03*
X1071941Y867192D03*
Y857152D03*
X1079383Y883924D03*
Y877231D03*
Y870538D03*
X1071941Y880577D03*
Y873885D03*
X1079383Y900656D03*
Y890617D03*
X1071941Y893963D03*
Y887270D03*
X1079383Y914042D03*
Y907349D03*
X1071941Y917389D03*
Y910696D03*
Y904003D03*
X1079383Y927428D03*
Y920735D03*
X1071941Y930774D03*
Y924081D03*
X1079383Y944160D03*
Y937467D03*
X1071941Y947507D03*
Y940814D03*
X1079383Y960892D03*
Y950853D03*
X1071941Y964239D03*
Y954200D03*
Y960892D03*
Y957546D03*
X1079383Y980971D03*
Y974278D03*
Y967585D03*
X1071941Y977625D03*
Y970932D03*
Y967585D03*
X1079383Y987664D03*
X1071941Y991011D03*
Y984318D03*
X1079383Y994357D03*
Y1027822D03*
Y1017782D03*
X1071941Y1031168D03*
Y1024475D03*
Y1017782D03*
X1079383Y1047900D03*
Y1041207D03*
Y1034515D03*
X1071941Y1044554D03*
Y1037861D03*
X1079383Y1061286D03*
Y1054593D03*
X1071941Y1057940D03*
Y1051247D03*
Y1054593D03*
X1079383Y1074672D03*
Y1067979D03*
X1071941Y1078018D03*
Y1071326D03*
Y1064633D03*
X1079383Y1091404D03*
Y1084711D03*
X1071941Y1094751D03*
Y1088058D03*
X1079383Y1111483D03*
Y1104790D03*
Y1098097D03*
X1071941Y1108137D03*
Y1101444D03*
X1079383Y1128215D03*
Y1121522D03*
X1071941Y1124869D03*
Y1114829D03*
X1079383Y1141601D03*
Y1134908D03*
X1071941Y1144948D03*
Y1138255D03*
Y1131562D03*
X1079383Y1158333D03*
Y1148294D03*
X1071941Y1161680D03*
Y1151641D03*
X1079383Y1171719D03*
Y1165026D03*
X1071941Y1175066D03*
Y1168373D03*
X1079383Y1185105D03*
Y1178412D03*
X1071941Y1188452D03*
Y1181759D03*
X1079383Y1208530D03*
Y1201837D03*
Y1195144D03*
X1071941Y1205184D03*
Y1198491D03*
X1079383Y1221916D03*
Y1215223D03*
X1071941Y1225263D03*
Y1218570D03*
Y1211877D03*
X1079383Y1238648D03*
Y1231955D03*
X1071941Y1241995D03*
Y1235302D03*
X1071991Y1257262D03*
X1079383Y1245341D03*
X1071941Y1248688D03*
X1076520Y1259072D03*
X1079383Y1258727D03*
X1088262Y1252293D03*
X1085088Y1273344D03*
X1082288D03*
X1079383Y1265420D03*
Y1262074D03*
X1074480Y1263742D03*
X1092941Y770144D03*
X1101641D03*
X1088083Y766798D03*
X1092709Y766775D03*
X1092941Y783530D03*
X1101641D03*
X1092941Y776837D03*
X1101641D03*
X1088083Y780184D03*
Y773491D03*
X1101641Y780184D03*
Y773491D03*
Y786877D03*
Y800263D03*
X1092941D03*
X1101641Y793570D03*
X1092941D03*
X1088083Y803609D03*
Y796916D03*
Y790223D03*
X1101641Y803609D03*
Y796916D03*
Y790223D03*
Y820341D03*
X1092941D03*
X1101641Y813648D03*
X1092941D03*
X1101641Y806955D03*
X1092941D03*
X1088083Y816995D03*
Y810302D03*
X1101641Y816995D03*
Y810302D03*
Y830381D03*
X1092941D03*
X1088083Y833727D03*
Y827034D03*
X1101641Y833727D03*
Y823688D03*
Y827034D03*
Y850459D03*
X1092941D03*
X1101641Y843766D03*
X1092941D03*
X1101641Y837074D03*
X1092941D03*
X1088083Y847113D03*
Y840420D03*
X1101641Y847113D03*
Y840420D03*
Y867192D03*
X1092941D03*
X1101641Y857152D03*
X1092941D03*
X1088083Y863845D03*
Y853806D03*
X1101641D03*
Y860499D03*
Y863845D03*
Y880577D03*
X1092941D03*
X1101641Y873885D03*
X1092941D03*
X1088083Y883924D03*
Y877231D03*
Y870538D03*
X1101641Y883924D03*
Y877231D03*
Y870538D03*
Y893963D03*
X1092941D03*
X1101641Y887270D03*
X1092941D03*
X1088083Y900656D03*
Y890617D03*
X1101641D03*
Y897310D03*
Y900656D03*
Y917389D03*
X1092941D03*
X1101641Y910696D03*
X1092941D03*
X1101641Y904003D03*
X1092941D03*
X1088083Y914042D03*
Y907349D03*
X1101641Y914042D03*
Y907349D03*
Y930774D03*
X1092941D03*
X1101641Y924081D03*
X1092941D03*
X1088083Y927428D03*
Y920735D03*
X1101641Y927428D03*
Y920735D03*
Y934121D03*
Y947507D03*
X1092941D03*
X1101641Y940814D03*
X1092941D03*
X1088083Y944160D03*
Y937467D03*
X1101641Y944160D03*
Y937467D03*
Y964239D03*
X1092941D03*
X1101641Y954200D03*
X1092941D03*
X1088083Y960892D03*
Y950853D03*
X1101641Y960892D03*
Y950853D03*
X1088083Y964239D03*
X1101641Y957546D03*
X1088083D03*
Y954200D03*
X1101641Y977625D03*
X1092941D03*
X1101641Y970932D03*
X1092941D03*
X1088083Y980971D03*
Y974278D03*
Y967585D03*
X1101641Y980971D03*
Y974278D03*
Y967585D03*
Y991011D03*
X1092941D03*
X1101641Y984318D03*
X1092941D03*
X1088083Y987664D03*
X1101641Y994357D03*
Y987664D03*
Y1031168D03*
X1092941D03*
X1101641Y1024475D03*
X1092941D03*
X1101641Y1017782D03*
X1092941D03*
X1088083Y1027822D03*
Y1017782D03*
Y1021129D03*
Y1024475D03*
X1101641Y1027822D03*
Y1021129D03*
Y1044554D03*
X1092941D03*
X1101641Y1037861D03*
X1092941D03*
X1088083Y1047900D03*
Y1041207D03*
Y1034515D03*
X1101641Y1047900D03*
Y1041207D03*
Y1034515D03*
Y1057940D03*
X1092941D03*
X1101641Y1051247D03*
X1092941D03*
X1088083Y1061286D03*
Y1054593D03*
X1101641Y1061286D03*
X1088083Y1051247D03*
X1101641Y1054593D03*
Y1078018D03*
X1092941D03*
X1101641Y1071326D03*
X1092941D03*
X1101641Y1064633D03*
X1092941D03*
X1088083Y1074672D03*
Y1067979D03*
X1101641Y1074672D03*
Y1067979D03*
Y1094751D03*
X1092941D03*
X1101641Y1088058D03*
X1092941D03*
X1088083Y1091404D03*
Y1084711D03*
X1101641Y1091404D03*
Y1081365D03*
Y1084711D03*
Y1108137D03*
X1092941D03*
X1101641Y1101444D03*
X1092941D03*
X1088083Y1111483D03*
Y1104790D03*
Y1098097D03*
X1101641D03*
Y1111483D03*
Y1104790D03*
Y1124869D03*
X1092941D03*
X1101641Y1114829D03*
X1092941D03*
X1088083Y1128215D03*
Y1121522D03*
X1101641Y1128215D03*
Y1118176D03*
Y1121522D03*
Y1144948D03*
X1092941D03*
X1101641Y1138255D03*
X1092941D03*
X1101641Y1131562D03*
X1092941D03*
X1088083Y1141601D03*
Y1134908D03*
X1101641Y1141601D03*
Y1134908D03*
X1092941Y1161680D03*
X1101641D03*
Y1151641D03*
X1092941D03*
X1088083Y1158333D03*
Y1148294D03*
X1101641D03*
Y1154987D03*
Y1158333D03*
Y1175066D03*
X1092941D03*
X1101641Y1168373D03*
X1092941D03*
X1088083Y1171719D03*
Y1165026D03*
X1101641Y1171719D03*
Y1165026D03*
Y1181759D03*
X1092941D03*
Y1188452D03*
X1101641D03*
X1088083Y1185105D03*
Y1178412D03*
X1101641Y1185105D03*
Y1178412D03*
Y1191798D03*
X1092941Y1205184D03*
X1101641D03*
X1092941Y1198491D03*
X1101641D03*
X1088083Y1208530D03*
Y1201837D03*
Y1195144D03*
X1101641Y1208530D03*
Y1201837D03*
Y1195144D03*
Y1225263D03*
X1092941D03*
X1101641Y1218570D03*
X1092941D03*
Y1211877D03*
X1101641D03*
X1088083Y1221916D03*
Y1215223D03*
X1101641Y1221916D03*
Y1215223D03*
Y1241995D03*
X1092941D03*
X1101641Y1235302D03*
X1092941D03*
X1088083Y1238648D03*
Y1231955D03*
X1101641Y1238648D03*
Y1228609D03*
Y1231955D03*
X1101554Y1257102D03*
X1101641Y1248688D03*
X1092941D03*
X1088083Y1245341D03*
X1090273Y1246800D03*
X1101641Y1245341D03*
X1092941Y1258727D03*
X1088083Y1248688D03*
X1091000Y1262074D03*
X1106200Y1250162D03*
X1098788Y1273344D03*
X1095988D03*
X1092941Y1265420D03*
X1103530Y1263602D03*
X1109083Y766798D03*
X1117783D03*
Y770144D03*
Y780184D03*
X1109083D03*
X1117783Y773491D03*
X1109083D03*
X1117783Y776837D03*
Y786877D03*
Y783530D03*
Y803609D03*
X1109083D03*
X1117783Y796916D03*
X1109083D03*
Y790223D03*
X1117783D03*
Y800263D03*
Y793570D03*
Y816995D03*
X1109083D03*
X1117783Y810302D03*
X1109083D03*
X1117783Y813648D03*
Y806955D03*
Y820341D03*
Y833727D03*
X1109083D03*
X1117783Y827034D03*
X1109083D03*
X1117783Y830381D03*
Y823688D03*
Y847113D03*
X1109083D03*
X1117783Y840420D03*
X1109083D03*
X1117783Y850459D03*
Y843766D03*
Y837074D03*
Y863845D03*
X1109083D03*
X1117783Y853806D03*
X1109083D03*
X1117783Y867192D03*
Y860499D03*
Y857152D03*
Y883924D03*
X1109083D03*
X1117783Y877231D03*
X1109083D03*
X1117783Y870538D03*
X1109083D03*
X1117783Y873885D03*
Y880577D03*
Y900656D03*
X1109083D03*
X1117783Y890617D03*
X1109083D03*
X1117783Y887270D03*
Y897310D03*
Y893963D03*
Y914042D03*
X1109083D03*
X1117783Y907349D03*
X1109083D03*
X1117783Y917389D03*
Y910696D03*
Y904003D03*
Y927428D03*
X1109083D03*
X1117783Y920735D03*
X1109083D03*
X1117783Y924081D03*
Y934121D03*
Y930774D03*
Y944160D03*
X1109083D03*
X1117783Y937467D03*
X1109083D03*
X1117783Y947507D03*
Y940814D03*
Y960892D03*
X1109083D03*
X1117783Y950853D03*
X1109083D03*
X1117783Y964239D03*
Y957546D03*
Y954200D03*
Y980971D03*
X1109083D03*
X1117783Y974278D03*
X1109083D03*
X1117783Y967585D03*
X1109083D03*
X1117783Y977625D03*
Y970932D03*
Y987664D03*
X1109083D03*
X1117783Y991011D03*
Y984318D03*
Y994357D03*
Y1027822D03*
X1109083D03*
X1117783Y1017782D03*
X1109083D03*
X1117783Y1021129D03*
Y1024475D03*
Y1031168D03*
Y1047900D03*
X1109083D03*
X1117783Y1041207D03*
X1109083D03*
X1117783Y1034515D03*
X1109083D03*
X1117783Y1044554D03*
Y1037861D03*
Y1061286D03*
X1109083D03*
X1117783Y1054593D03*
X1109083D03*
X1117783Y1051247D03*
Y1057940D03*
Y1074672D03*
X1109083D03*
X1117783Y1067979D03*
X1109083D03*
X1117783Y1071326D03*
Y1064633D03*
Y1078018D03*
Y1091404D03*
X1109083D03*
X1117783Y1084711D03*
X1109083D03*
X1117783Y1094751D03*
Y1088058D03*
Y1081365D03*
Y1111483D03*
X1109083D03*
X1117783Y1104790D03*
X1109083D03*
X1117783Y1098097D03*
X1109083D03*
X1117783Y1108137D03*
Y1101444D03*
Y1128215D03*
X1109083D03*
X1117783Y1121522D03*
X1109083D03*
X1117783Y1124869D03*
Y1118176D03*
Y1114829D03*
Y1141601D03*
X1109083D03*
X1117783Y1134908D03*
X1109083D03*
X1117783Y1144948D03*
Y1138255D03*
Y1131562D03*
Y1158333D03*
X1109083D03*
X1117783Y1148294D03*
X1109083D03*
X1117783Y1161680D03*
Y1154987D03*
Y1151641D03*
Y1171719D03*
X1109083D03*
X1117783Y1165026D03*
X1109083D03*
X1117783Y1175066D03*
Y1168373D03*
Y1185105D03*
X1109083D03*
X1117783Y1178412D03*
X1109083D03*
X1117783Y1181759D03*
Y1191798D03*
Y1188452D03*
Y1208530D03*
X1109083D03*
X1117783Y1201837D03*
X1109083D03*
X1117783Y1195144D03*
X1109083D03*
X1117783Y1205184D03*
Y1198491D03*
Y1221916D03*
X1109083D03*
X1117783Y1215223D03*
X1109083D03*
X1117783Y1218570D03*
Y1211877D03*
Y1225263D03*
Y1238648D03*
X1109083D03*
X1117783Y1231955D03*
X1109083D03*
X1117783Y1241995D03*
Y1235302D03*
Y1228609D03*
Y1245341D03*
X1109083D03*
X1120800Y1262074D03*
X1117783Y1248688D03*
X1111988Y1273344D03*
X1114788D03*
X1109083Y1265420D03*
X1109050Y1262972D03*
X1106740Y1267902D03*
X1131341Y770144D03*
X1122641D03*
X1122541Y766798D03*
X1131341Y783530D03*
X1122641D03*
X1131341Y776837D03*
X1122641D03*
X1131341Y800263D03*
X1122641D03*
X1131341Y793570D03*
X1122641D03*
X1131341Y820341D03*
X1122641D03*
X1131341Y813648D03*
X1122641D03*
X1131341Y806955D03*
X1122641D03*
X1131341Y830381D03*
X1122641D03*
X1131341Y850459D03*
X1122641D03*
X1131341Y843766D03*
X1122641D03*
X1131341Y837074D03*
X1122641D03*
X1131341Y867192D03*
X1122641D03*
X1131341Y857152D03*
X1122641D03*
X1131341Y880577D03*
X1122641D03*
X1131341Y873885D03*
X1122641D03*
X1131341Y893963D03*
X1122641D03*
X1131341Y887270D03*
X1122641D03*
X1131341Y917389D03*
X1122641D03*
X1131341Y910696D03*
X1122641D03*
X1131341Y904003D03*
X1122641D03*
X1131341Y930774D03*
X1122641D03*
X1131341Y924081D03*
X1122641D03*
Y947507D03*
X1131341D03*
Y940814D03*
X1122641D03*
X1131341Y964239D03*
X1122641D03*
X1131341Y954200D03*
X1122641D03*
X1131341Y960892D03*
Y957546D03*
Y977625D03*
X1122641D03*
X1131341Y970932D03*
X1122641D03*
X1131341Y967585D03*
Y991011D03*
X1122641D03*
X1131341Y984318D03*
X1122641D03*
X1131341Y1031168D03*
X1122641D03*
X1131341Y1024475D03*
X1122641D03*
X1131341Y1017782D03*
X1122641D03*
X1131341Y1044554D03*
X1122641D03*
X1131341Y1037861D03*
X1122641D03*
X1131341Y1057940D03*
X1122641D03*
X1131341Y1051247D03*
X1122641D03*
X1131341Y1054593D03*
Y1078018D03*
X1122641D03*
X1131341Y1071326D03*
X1122641D03*
X1131341Y1064633D03*
X1122641D03*
X1131341Y1094751D03*
X1122641D03*
X1131341Y1088058D03*
X1122641D03*
X1131341Y1108137D03*
X1122641D03*
X1131341Y1101444D03*
X1122641D03*
X1131341Y1124869D03*
X1122641D03*
X1131341Y1114829D03*
X1122641D03*
X1131341Y1144948D03*
X1122641D03*
X1131341Y1138255D03*
X1122641D03*
X1131341Y1131562D03*
X1122641D03*
X1131341Y1161680D03*
X1122641D03*
X1131341Y1151641D03*
X1122641D03*
X1131341Y1175066D03*
X1122641D03*
X1131341Y1168373D03*
X1122641D03*
X1131341Y1188452D03*
X1122641D03*
X1131341Y1181759D03*
X1122641D03*
X1131341Y1205184D03*
X1122641D03*
X1131341Y1198491D03*
X1122641D03*
X1131341Y1225263D03*
X1122641D03*
X1131341Y1218570D03*
X1122641D03*
X1131341Y1211877D03*
X1122641D03*
X1131341Y1241995D03*
X1122641D03*
X1131341Y1235302D03*
X1122641D03*
X1131434Y1257291D03*
X1122641Y1248688D03*
X1131341D03*
X1122641Y1258727D03*
X1133200Y1255702D03*
X1126188Y1273344D03*
X1128988D03*
X1122620Y1264622D03*
X1152341Y770144D03*
X1147483Y766798D03*
X1138783D03*
X1152241D03*
X1152341Y783530D03*
Y776837D03*
X1147483Y780184D03*
X1138783D03*
Y773491D03*
X1147483D03*
X1152341Y800263D03*
X1147483Y803609D03*
X1138783D03*
X1152341Y793570D03*
X1147483Y796916D03*
X1138783D03*
X1147483Y790223D03*
X1138783D03*
X1152341Y820341D03*
X1147483Y816995D03*
X1138783D03*
X1152341Y813648D03*
Y806955D03*
X1147483Y810302D03*
X1138783D03*
X1147483Y833727D03*
X1138783D03*
X1152341Y830381D03*
X1147483Y827034D03*
X1138783D03*
X1152341Y850459D03*
Y843766D03*
Y837074D03*
X1147483Y847113D03*
X1138783D03*
X1147483Y840420D03*
X1138783D03*
X1152341Y867192D03*
Y857152D03*
X1147483Y863845D03*
X1138783D03*
X1147483Y853806D03*
X1138783D03*
X1152341Y880577D03*
Y873885D03*
X1147483Y883924D03*
X1138783D03*
X1147483Y877231D03*
X1138783D03*
X1147483Y870538D03*
X1138783D03*
X1152341Y893963D03*
Y887270D03*
X1138783Y900656D03*
X1147483D03*
X1138783Y890617D03*
X1147483D03*
X1152341Y917389D03*
Y910696D03*
Y904003D03*
X1147483Y914042D03*
X1138783D03*
X1147483Y907349D03*
X1138783D03*
X1152341Y930774D03*
Y924081D03*
X1147483Y927428D03*
X1138783D03*
X1147483Y920735D03*
X1138783D03*
X1152341Y947507D03*
Y940814D03*
X1147483Y944160D03*
X1138783D03*
X1147483Y937467D03*
X1138783D03*
X1152341Y964239D03*
Y954200D03*
X1147483Y960892D03*
X1138783D03*
X1147483Y950853D03*
X1138783D03*
X1147483Y964239D03*
Y957546D03*
Y954200D03*
X1152341Y977625D03*
Y970932D03*
X1147483Y980971D03*
X1138783D03*
X1147483Y974278D03*
X1138783D03*
X1147483Y967585D03*
X1138783D03*
X1152341Y991011D03*
Y984318D03*
X1147483Y987664D03*
X1138783D03*
Y994357D03*
X1152341Y1031168D03*
Y1024475D03*
Y1017782D03*
X1147483Y1027822D03*
X1138783D03*
X1147483Y1017782D03*
X1138783D03*
X1147483Y1021129D03*
Y1024475D03*
X1152341Y1044554D03*
Y1037861D03*
X1138783Y1047900D03*
X1147483D03*
Y1041207D03*
X1138783D03*
X1147483Y1034515D03*
X1138783D03*
X1152341Y1057940D03*
Y1051247D03*
X1147483Y1061286D03*
X1138783D03*
X1147483Y1054593D03*
X1138783D03*
X1147483Y1051247D03*
X1152341Y1078018D03*
Y1071326D03*
Y1064633D03*
X1147483Y1074672D03*
X1138783D03*
X1147483Y1067979D03*
X1138783D03*
X1152341Y1094751D03*
Y1088058D03*
X1147483Y1091404D03*
X1138783D03*
X1147483Y1084711D03*
X1138783D03*
X1152341Y1108137D03*
Y1101444D03*
X1147483Y1111483D03*
X1138783D03*
X1147483Y1104790D03*
X1138783D03*
X1147483Y1098097D03*
X1138783D03*
X1152341Y1124869D03*
Y1114829D03*
X1147483Y1128215D03*
X1138783D03*
X1147483Y1121522D03*
X1138783D03*
X1152341Y1144948D03*
Y1138255D03*
Y1131562D03*
X1147483Y1141601D03*
X1138783D03*
X1147483Y1134908D03*
X1138783D03*
X1152341Y1161680D03*
Y1151641D03*
X1147483Y1158333D03*
X1138783D03*
Y1148294D03*
X1147483D03*
X1152341Y1175066D03*
Y1168373D03*
X1147483Y1171719D03*
X1138783D03*
X1147483Y1165026D03*
X1138783D03*
X1152341Y1188452D03*
Y1181759D03*
X1147483Y1185105D03*
X1138783D03*
X1147483Y1178412D03*
X1138783D03*
X1152341Y1205184D03*
Y1198491D03*
X1147483Y1208530D03*
X1138783D03*
X1147483Y1201837D03*
X1138783D03*
X1147483Y1195144D03*
X1138783D03*
X1152341Y1225263D03*
Y1218570D03*
Y1211877D03*
X1147483Y1221916D03*
X1138783D03*
X1147483Y1215223D03*
X1138783D03*
X1152341Y1241995D03*
Y1235302D03*
X1147483Y1238648D03*
X1138783D03*
X1147483Y1231955D03*
X1138783D03*
X1152341Y1248688D03*
X1147483Y1245341D03*
X1138783D03*
X1152341Y1258727D03*
X1138783Y1255381D03*
Y1258727D03*
Y1252034D03*
X1147483Y1248688D03*
X1150400Y1262074D03*
X1148563Y1257097D03*
X1152381Y1269684D03*
X1147681D03*
X1138201Y1270277D03*
X1152341Y1265420D03*
X1138783Y1262027D03*
X1137980Y1264212D03*
X1168483Y766798D03*
X1161041Y770144D03*
X1168483Y780184D03*
Y773491D03*
X1161041Y783530D03*
Y776837D03*
Y780184D03*
Y773491D03*
Y786877D03*
X1168483Y803609D03*
Y796916D03*
Y790223D03*
X1161041Y800263D03*
Y793570D03*
Y803609D03*
Y796916D03*
Y790223D03*
X1168483Y816995D03*
Y810302D03*
X1161041Y820341D03*
Y813648D03*
Y806955D03*
Y816995D03*
Y810302D03*
X1168483Y833727D03*
X1167633Y827034D03*
X1161041Y830381D03*
Y833727D03*
Y823688D03*
Y827034D03*
X1168483Y847113D03*
Y840420D03*
X1161041Y850459D03*
Y843766D03*
Y837074D03*
Y847113D03*
Y840420D03*
X1167633Y863845D03*
X1161041Y867192D03*
X1168483Y853806D03*
X1161041Y857152D03*
Y853806D03*
Y860499D03*
Y863845D03*
X1168483Y883924D03*
Y877231D03*
Y870538D03*
X1161041Y880577D03*
Y873885D03*
Y883924D03*
Y877231D03*
Y870538D03*
X1168483Y900656D03*
Y890617D03*
X1161041Y893963D03*
Y887270D03*
Y890617D03*
Y897310D03*
Y900656D03*
X1168483Y914042D03*
Y907349D03*
X1161041Y917389D03*
Y910696D03*
Y904003D03*
Y914042D03*
Y907349D03*
X1167633Y927428D03*
X1168483Y920735D03*
X1161041Y930774D03*
Y924081D03*
Y927428D03*
Y920735D03*
Y934121D03*
X1168483Y937467D03*
Y944160D03*
X1161041Y947507D03*
Y940814D03*
Y944160D03*
Y937467D03*
X1168483Y960892D03*
Y950853D03*
X1161041Y964239D03*
Y954200D03*
Y960892D03*
Y950853D03*
Y957546D03*
X1168483Y974278D03*
Y980971D03*
Y967585D03*
X1161041Y977625D03*
Y970932D03*
Y980971D03*
Y974278D03*
Y967585D03*
X1168483Y987664D03*
X1161041Y991011D03*
Y984318D03*
Y994357D03*
Y987664D03*
X1168483Y1027822D03*
Y1017782D03*
X1161041Y1031168D03*
Y1024475D03*
Y1017782D03*
Y1027822D03*
Y1021129D03*
X1168483Y1047900D03*
Y1041207D03*
Y1034515D03*
X1161041Y1044554D03*
Y1037861D03*
Y1047900D03*
Y1041207D03*
Y1034515D03*
X1168483Y1054593D03*
Y1061286D03*
X1161041Y1057940D03*
Y1051247D03*
Y1061286D03*
Y1054593D03*
X1168483Y1074672D03*
Y1067979D03*
X1161041Y1078018D03*
Y1071326D03*
Y1064633D03*
Y1074672D03*
Y1067979D03*
X1168483Y1091404D03*
X1167633Y1084711D03*
X1161041Y1094751D03*
Y1088058D03*
Y1091404D03*
Y1081365D03*
Y1084711D03*
X1168483Y1111483D03*
Y1104790D03*
Y1098097D03*
X1161041Y1108137D03*
Y1101444D03*
Y1098097D03*
Y1111483D03*
Y1104790D03*
X1168483Y1128215D03*
Y1121522D03*
X1161041Y1124869D03*
Y1114829D03*
Y1128215D03*
Y1118176D03*
Y1121522D03*
X1168483Y1141601D03*
Y1134908D03*
X1161041Y1144948D03*
Y1138255D03*
Y1131562D03*
Y1141601D03*
Y1134908D03*
X1167633Y1158333D03*
X1168483Y1148294D03*
X1161041Y1161680D03*
Y1151641D03*
Y1148294D03*
Y1154987D03*
Y1158333D03*
X1168483Y1171719D03*
Y1165026D03*
X1161041Y1175066D03*
Y1168373D03*
Y1171719D03*
Y1165026D03*
X1168483Y1185105D03*
Y1178412D03*
X1161041Y1188452D03*
Y1181759D03*
Y1185105D03*
Y1178412D03*
Y1191798D03*
X1168483Y1208530D03*
Y1201837D03*
Y1195144D03*
X1161041Y1205184D03*
Y1198491D03*
Y1208530D03*
Y1201837D03*
Y1195144D03*
X1168483Y1221916D03*
Y1215223D03*
X1161041Y1225263D03*
Y1218570D03*
Y1211877D03*
Y1221916D03*
Y1215223D03*
X1168483Y1238648D03*
X1167633Y1231955D03*
X1161041Y1241995D03*
Y1235302D03*
Y1238648D03*
Y1228609D03*
Y1231955D03*
X1161065Y1258871D03*
X1168483Y1245341D03*
X1161041Y1248688D03*
Y1245341D03*
X1168483Y1255381D03*
Y1258727D03*
Y1252034D03*
X1161781Y1269684D03*
X1168483Y1265420D03*
Y1262074D03*
X1182041Y770144D03*
X1177183Y766798D03*
Y770144D03*
X1181941Y766798D03*
X1182041Y783530D03*
Y776837D03*
X1177183Y780184D03*
Y773491D03*
Y776837D03*
Y786877D03*
Y783530D03*
X1182041Y800263D03*
Y793570D03*
X1177183Y803609D03*
Y796916D03*
Y790223D03*
Y800263D03*
Y793570D03*
X1182041Y813648D03*
Y806955D03*
X1181191Y820341D03*
X1177183Y816995D03*
Y810302D03*
Y813648D03*
Y806955D03*
Y820341D03*
X1181191Y830381D03*
X1177183Y833727D03*
Y827034D03*
Y830381D03*
Y823688D03*
X1182041Y850459D03*
Y837074D03*
Y843766D03*
X1177183Y847113D03*
Y840420D03*
Y850459D03*
Y843766D03*
Y837074D03*
X1181191Y867192D03*
X1177183Y863845D03*
X1181191Y857152D03*
X1177183Y853806D03*
Y867192D03*
Y860499D03*
Y857152D03*
X1182041Y873885D03*
Y880577D03*
X1177183Y883924D03*
Y877231D03*
Y870538D03*
Y873885D03*
Y880577D03*
X1182041Y893963D03*
Y887270D03*
X1177183Y900656D03*
Y890617D03*
Y887270D03*
Y897310D03*
Y893963D03*
X1182041Y917389D03*
Y910696D03*
Y904003D03*
X1177183Y914042D03*
Y907349D03*
Y917389D03*
Y910696D03*
Y904003D03*
X1181191Y930774D03*
Y924081D03*
X1177183Y927428D03*
Y920735D03*
Y924081D03*
Y934121D03*
Y930774D03*
X1182041Y940814D03*
Y947507D03*
X1177183Y937467D03*
Y944160D03*
Y947507D03*
Y940814D03*
X1182041Y964239D03*
Y954200D03*
X1177183Y960892D03*
Y950853D03*
Y964239D03*
Y957546D03*
Y954200D03*
X1182041Y970932D03*
Y977625D03*
X1177183Y974278D03*
Y980971D03*
Y967585D03*
Y977625D03*
Y970932D03*
X1182041Y991011D03*
Y984318D03*
X1177183Y987664D03*
Y991011D03*
Y984318D03*
Y994357D03*
X1182041Y1031168D03*
Y1017782D03*
Y1024475D03*
X1177183Y1027822D03*
Y1017782D03*
X1177283Y1021129D03*
Y1024475D03*
Y1031168D03*
X1182041Y1044554D03*
Y1037861D03*
X1177183Y1047900D03*
Y1041207D03*
Y1034515D03*
X1177283Y1044554D03*
Y1037861D03*
X1182041Y1057940D03*
Y1051247D03*
X1177183Y1054593D03*
Y1061286D03*
X1177283Y1051247D03*
X1181191Y1078018D03*
X1182041Y1071326D03*
Y1064633D03*
X1177183Y1074672D03*
Y1067979D03*
X1177283Y1071326D03*
Y1064633D03*
Y1078018D03*
X1182041Y1094751D03*
X1181191Y1088058D03*
X1177183Y1091404D03*
Y1084711D03*
X1177283Y1094752D03*
Y1088059D03*
Y1081366D03*
X1182041Y1101444D03*
Y1108137D03*
X1177183Y1111483D03*
Y1104790D03*
Y1098097D03*
X1177283Y1108137D03*
Y1101444D03*
X1182041Y1114829D03*
Y1124869D03*
X1177183Y1128215D03*
Y1121522D03*
Y1124869D03*
X1177283Y1118177D03*
Y1114830D03*
X1182041Y1144948D03*
Y1138255D03*
Y1131562D03*
X1177183Y1141601D03*
Y1134908D03*
X1177283Y1144948D03*
Y1138255D03*
X1177183Y1131562D03*
X1181191Y1161680D03*
Y1151641D03*
X1177183Y1158333D03*
Y1148294D03*
X1177283Y1161680D03*
Y1154988D03*
Y1151641D03*
X1182041Y1168373D03*
Y1175066D03*
X1177183Y1171719D03*
Y1165026D03*
X1177283Y1175066D03*
Y1168373D03*
X1182041Y1188452D03*
Y1181759D03*
X1177183Y1185105D03*
Y1178412D03*
X1177283Y1181759D03*
Y1191799D03*
Y1188452D03*
X1182041Y1205184D03*
Y1198491D03*
X1177183Y1208530D03*
Y1201837D03*
Y1195144D03*
X1177283Y1205184D03*
Y1198491D03*
X1181191Y1225263D03*
X1182041Y1211877D03*
Y1218570D03*
X1177183Y1221916D03*
Y1215223D03*
X1177283Y1218570D03*
Y1211877D03*
Y1225263D03*
X1182041Y1241995D03*
X1181191Y1235302D03*
X1177183Y1238648D03*
Y1231955D03*
X1177250Y1241995D03*
X1177283Y1235302D03*
Y1228609D03*
X1182041Y1248688D03*
X1177183Y1245341D03*
X1177120Y1248688D03*
X1177222Y1255567D03*
X1176867Y1270029D03*
X1182041Y1265420D03*
X1181850Y1260192D03*
X1179180Y1265872D03*
X1198183Y766798D03*
X1190741Y770144D03*
X1198183Y780184D03*
Y773491D03*
X1190741Y783530D03*
Y776837D03*
X1198183Y803609D03*
Y796916D03*
Y790223D03*
X1190741Y800263D03*
Y793570D03*
X1197333Y816995D03*
X1198183Y810302D03*
X1190741Y813648D03*
Y806955D03*
X1191591Y820341D03*
X1198183Y833727D03*
X1197333Y827034D03*
X1191591Y830381D03*
X1198183Y847113D03*
Y840420D03*
X1190741Y850459D03*
Y837074D03*
Y843766D03*
X1197333Y863845D03*
X1191591Y867192D03*
X1198183Y853806D03*
X1191591Y857152D03*
X1198183Y877231D03*
X1197333Y870538D03*
X1198183Y883924D03*
X1190741Y873885D03*
Y880577D03*
X1198183Y900656D03*
Y890617D03*
X1190741Y893963D03*
Y887270D03*
X1198183Y914042D03*
Y907349D03*
X1190741Y917389D03*
Y910696D03*
Y904003D03*
X1197383Y927428D03*
X1198183Y920735D03*
X1191591Y930774D03*
Y924081D03*
X1198183Y944160D03*
X1197333Y937467D03*
X1190741Y940814D03*
Y947507D03*
X1198183Y960892D03*
Y950853D03*
X1190741Y964239D03*
Y954200D03*
Y960892D03*
Y957546D03*
X1198183D03*
Y954200D03*
Y980971D03*
Y974278D03*
Y967585D03*
X1190741Y970932D03*
Y977625D03*
X1198183Y987664D03*
X1190741Y991011D03*
Y984318D03*
X1198183Y994357D03*
Y1027822D03*
Y1017782D03*
X1190741Y1031168D03*
Y1017782D03*
Y1024475D03*
X1198183Y1047900D03*
Y1041207D03*
Y1034515D03*
X1190741Y1044554D03*
Y1037861D03*
X1198183Y1054593D03*
Y1061286D03*
X1190741Y1057940D03*
Y1051247D03*
X1197333Y1074672D03*
X1198183Y1067979D03*
X1191591Y1078018D03*
X1190741Y1071326D03*
Y1064633D03*
X1198183Y1091404D03*
X1197333Y1084711D03*
X1190741Y1094751D03*
X1191591Y1088058D03*
X1198183Y1111483D03*
Y1098097D03*
Y1104790D03*
X1190741Y1101444D03*
Y1108137D03*
X1198183Y1128215D03*
Y1121522D03*
X1190741Y1114829D03*
Y1124869D03*
X1198183Y1141601D03*
X1197333Y1134908D03*
X1190741Y1144948D03*
Y1138255D03*
Y1131562D03*
X1198183Y1158333D03*
X1197333Y1148294D03*
X1191591Y1161680D03*
Y1151641D03*
X1198183Y1165026D03*
Y1171719D03*
X1190741Y1168373D03*
Y1175066D03*
X1198183Y1185105D03*
Y1178412D03*
X1190741Y1188452D03*
Y1181759D03*
X1198183Y1208530D03*
Y1201837D03*
Y1195144D03*
X1190741Y1205184D03*
Y1198491D03*
X1198183Y1221916D03*
Y1215223D03*
X1191591Y1225263D03*
X1190741Y1211877D03*
Y1218570D03*
X1197333Y1238648D03*
Y1231955D03*
X1190741Y1241995D03*
X1191591Y1235302D03*
X1198183Y1245341D03*
X1190966Y1258711D03*
X1190741Y1248688D03*
X1198183Y1252034D03*
X1191538Y1270004D03*
X1198180Y1262112D03*
X1196470Y1265382D03*
X1193590Y1267912D03*
X1195470Y1262802D03*
X1195994Y1580678D03*
Y1575686D03*
X1200950Y1580678D03*
Y1575686D03*
X1196772Y1578182D03*
X1200172D03*
X1201294Y1599884D03*
X1195994Y1592590D03*
Y1587598D03*
X1200950Y1592590D03*
Y1587598D03*
X1196772Y1590094D03*
X1200172D03*
X1201294Y1604876D03*
Y1611796D03*
Y1616788D03*
X1211741Y770144D03*
X1206883Y766798D03*
X1211641D03*
X1211741Y783530D03*
Y776837D03*
X1206883Y780184D03*
Y773491D03*
X1211741Y800263D03*
Y793570D03*
X1206883Y803609D03*
Y796916D03*
Y790223D03*
X1210891Y820341D03*
Y813648D03*
X1211741Y806955D03*
X1207148Y817554D03*
X1206883Y810302D03*
X1211741Y830381D03*
X1206883Y833727D03*
X1207733Y827034D03*
X1211741Y850459D03*
Y837074D03*
Y843766D03*
X1206883Y847113D03*
Y840420D03*
X1210891Y867492D03*
X1207733Y863845D03*
X1210891Y857152D03*
X1206883Y853806D03*
X1211741Y874185D03*
Y880577D03*
X1206883Y877231D03*
X1207201Y871084D03*
X1206883Y883924D03*
X1211741Y893963D03*
Y887270D03*
X1206883Y900656D03*
Y890617D03*
X1211741Y917389D03*
Y910696D03*
Y904003D03*
X1206883Y914042D03*
Y907349D03*
X1211741Y930774D03*
Y924081D03*
X1207683Y927428D03*
X1206883Y920735D03*
X1211741Y947507D03*
X1211001Y940814D03*
X1206883Y944660D03*
X1207733Y937467D03*
X1211741Y964239D03*
Y954200D03*
X1206883Y960892D03*
Y950853D03*
X1211741Y977625D03*
Y970932D03*
X1206883Y980971D03*
Y974278D03*
Y967585D03*
X1211741Y991011D03*
X1206883Y987664D03*
X1211741Y984318D03*
X1213983Y1000437D03*
X1216663Y1000395D03*
X1212533Y1002557D03*
X1205033D03*
X1207533D03*
X1210033D03*
X1211741Y1031168D03*
X1206883Y1027822D03*
Y1017782D03*
X1211741D03*
Y1024475D03*
Y1044554D03*
Y1037861D03*
X1206883Y1047900D03*
Y1041207D03*
Y1034515D03*
X1211741Y1051247D03*
Y1057940D03*
X1206883Y1054593D03*
Y1061286D03*
X1210891Y1078018D03*
X1211741Y1064633D03*
Y1071326D03*
X1207733Y1074672D03*
X1206883Y1067979D03*
X1211741Y1094751D03*
X1210891Y1088058D03*
X1206883Y1091404D03*
Y1084711D03*
X1211741Y1108137D03*
Y1101444D03*
X1206883Y1111483D03*
Y1098097D03*
Y1104790D03*
X1210891Y1124869D03*
X1211741Y1114829D03*
X1206883Y1128215D03*
Y1121522D03*
X1211741Y1144948D03*
Y1138255D03*
X1210891Y1131562D03*
X1206883Y1141601D03*
X1207733Y1134908D03*
X1211741Y1151641D03*
Y1161680D03*
X1206883Y1158333D03*
X1207733Y1148294D03*
X1211741Y1175066D03*
Y1168373D03*
X1206883Y1165026D03*
Y1171719D03*
X1211741Y1188452D03*
Y1181759D03*
X1206883Y1185105D03*
Y1178412D03*
X1211741Y1205184D03*
Y1198491D03*
X1206883Y1208530D03*
Y1201837D03*
Y1195144D03*
X1210891Y1225263D03*
X1211741Y1218570D03*
Y1211877D03*
X1206883Y1221916D03*
Y1215223D03*
X1211741Y1241995D03*
X1211328Y1234977D03*
X1207733Y1238648D03*
Y1231955D03*
X1206883Y1245341D03*
X1211741Y1248688D03*
X1208830Y1256692D03*
X1206883Y1248688D03*
X1207048Y1255174D03*
X1204608Y1273119D03*
X1202043Y1273123D03*
X1211240Y1265502D03*
X1208750Y1266546D03*
X1213010Y1575686D03*
X1208054D03*
X1213010Y1580678D03*
X1208054D03*
X1212232Y1578182D03*
X1208832D03*
X1206250Y1599884D03*
X1213354D03*
X1213010Y1587598D03*
X1208054D03*
X1213010Y1592590D03*
X1208054D03*
X1212232Y1590094D03*
X1208832D03*
X1206250Y1604876D03*
Y1611796D03*
Y1616788D03*
X1213354D03*
Y1604876D03*
Y1611796D03*
X1214132Y1614292D03*
X1202072D03*
X1217532D03*
X1205472D03*
X1214132Y1602380D03*
X1202072D03*
X1217532D03*
X1205472D03*
X1227883Y766798D03*
X1220441Y770144D03*
X1227883Y780184D03*
Y773491D03*
X1220441Y783530D03*
Y776837D03*
X1227883Y803609D03*
Y796916D03*
Y790223D03*
X1220441Y800263D03*
Y793570D03*
X1227033Y816995D03*
X1227883Y810302D03*
X1221291Y820341D03*
Y813648D03*
X1220441Y806955D03*
X1227883Y833727D03*
X1227033Y827034D03*
X1220441Y830381D03*
X1227883Y847113D03*
Y840420D03*
X1220441Y850459D03*
Y837074D03*
Y843766D03*
X1227033Y863845D03*
X1221291Y867192D03*
X1227033Y853806D03*
X1221291Y857152D03*
X1227883Y870538D03*
Y883924D03*
Y877231D03*
X1220441Y873885D03*
Y880577D03*
Y883924D03*
X1227033Y900656D03*
X1227883Y890617D03*
X1220441Y893963D03*
Y887270D03*
Y890617D03*
Y897310D03*
Y900656D03*
X1227883Y914042D03*
Y907349D03*
X1220441Y917389D03*
Y910696D03*
Y904003D03*
Y914042D03*
Y907349D03*
X1227033Y927428D03*
X1227883Y920735D03*
X1221291Y930774D03*
X1220441Y924081D03*
X1227883Y944160D03*
X1227033Y937467D03*
X1220441Y947507D03*
X1221291Y940814D03*
X1227883Y960892D03*
Y950853D03*
X1220441Y964239D03*
Y954200D03*
Y960892D03*
Y957546D03*
X1227883D03*
Y954200D03*
Y974278D03*
Y967585D03*
X1220441Y977625D03*
Y970932D03*
X1227883Y980971D03*
Y987664D03*
X1220441Y991011D03*
Y984318D03*
X1227883Y994357D03*
X1233703Y999608D03*
X1231023Y999650D03*
X1227883Y1027822D03*
X1220441Y1031168D03*
X1227883Y1017782D03*
X1220441D03*
Y1024475D03*
X1227883Y1047900D03*
Y1041207D03*
Y1034515D03*
X1220441Y1044554D03*
Y1037861D03*
X1227883Y1061286D03*
Y1054593D03*
X1220441Y1051247D03*
Y1057940D03*
Y1061286D03*
X1227033Y1074672D03*
Y1067979D03*
X1221291Y1078018D03*
X1220441Y1064633D03*
Y1071326D03*
X1227883Y1091404D03*
Y1084711D03*
X1220441Y1094751D03*
X1221291Y1088058D03*
X1227883Y1104790D03*
X1227033Y1111483D03*
X1227883Y1098097D03*
X1220441Y1108137D03*
Y1101444D03*
X1227883Y1128215D03*
X1227033Y1121522D03*
X1221291Y1124869D03*
X1220441Y1114829D03*
X1227883Y1134908D03*
Y1141601D03*
X1220441Y1144948D03*
Y1138255D03*
X1221291Y1131562D03*
X1227883Y1158333D03*
Y1148294D03*
X1220441Y1151641D03*
Y1161680D03*
X1227883Y1171719D03*
Y1165026D03*
X1220441Y1175066D03*
Y1168373D03*
X1227883Y1185105D03*
Y1178412D03*
X1220441Y1188452D03*
Y1181759D03*
Y1185105D03*
Y1178412D03*
Y1191798D03*
X1227883Y1208530D03*
Y1201837D03*
X1227033Y1195144D03*
X1220441Y1205184D03*
Y1198491D03*
Y1208530D03*
Y1201837D03*
Y1195144D03*
X1227033Y1221916D03*
X1227883Y1215223D03*
X1221291Y1225263D03*
X1220441Y1218570D03*
Y1211877D03*
X1227883Y1238648D03*
X1227033Y1231955D03*
X1220441Y1241995D03*
X1221291Y1235302D03*
X1220441Y1248688D03*
X1227883Y1245341D03*
X1224189Y1259155D03*
X1226899Y1257968D03*
X1227847Y1251715D03*
X1220601Y1269684D03*
X1220931Y1260093D03*
X1233327Y1274515D03*
X1231377Y1275855D03*
X1227670Y1265162D03*
X1225540Y1266402D03*
X1225070Y1580678D03*
Y1575686D03*
X1220114D03*
Y1580678D03*
X1232174D03*
Y1575686D03*
X1220892Y1578182D03*
X1232952D03*
X1224292D03*
X1218310Y1599884D03*
X1225414D03*
X1230370D03*
X1225070Y1592590D03*
X1220114D03*
X1225070Y1587598D03*
X1220114D03*
X1232174D03*
Y1592590D03*
X1220892Y1590094D03*
X1232952D03*
X1224292D03*
X1218310Y1616788D03*
Y1604876D03*
Y1611796D03*
X1225414D03*
Y1604876D03*
X1230370Y1611796D03*
Y1604876D03*
X1225414Y1616788D03*
X1230370D03*
X1226192Y1614292D03*
X1229592D03*
X1226192Y1602380D03*
X1229592D03*
X1236583Y766798D03*
Y780184D03*
Y773491D03*
Y803609D03*
Y796916D03*
Y790223D03*
X1237433Y816995D03*
X1236583Y810302D03*
Y833727D03*
X1237433Y827034D03*
X1236583Y847113D03*
Y840420D03*
X1237433Y863845D03*
Y853806D03*
X1236583Y870538D03*
Y883924D03*
Y877231D03*
Y880577D03*
Y900656D03*
Y890617D03*
Y887270D03*
Y897310D03*
Y893963D03*
Y914042D03*
Y907349D03*
Y910696D03*
Y904003D03*
X1237433Y927428D03*
X1236583Y920735D03*
Y944160D03*
X1237433Y937467D03*
X1236583Y960892D03*
Y950853D03*
Y974278D03*
Y967585D03*
Y980971D03*
Y987664D03*
Y1027822D03*
Y1017782D03*
Y1047900D03*
Y1041207D03*
Y1034515D03*
Y1061286D03*
Y1054593D03*
Y1057940D03*
X1237433Y1074672D03*
Y1067979D03*
X1236583Y1091404D03*
Y1084711D03*
Y1104790D03*
X1237433Y1111483D03*
X1236583Y1098097D03*
Y1128215D03*
X1237433Y1121522D03*
X1236583Y1134908D03*
Y1141601D03*
Y1158333D03*
Y1148294D03*
Y1171719D03*
Y1165026D03*
Y1175066D03*
Y1185105D03*
Y1178412D03*
Y1181759D03*
Y1191798D03*
Y1188452D03*
Y1208530D03*
Y1201837D03*
Y1195144D03*
Y1205184D03*
Y1198491D03*
X1237433Y1221916D03*
X1236583Y1215223D03*
Y1238648D03*
X1237433Y1231955D03*
X1236583Y1245341D03*
Y1248688D03*
X1237130Y1575686D03*
Y1580678D03*
X1244234D03*
X1249190D03*
X1244234Y1575686D03*
X1249190D03*
X1245012Y1578182D03*
X1236352D03*
X1248412D03*
X1242430Y1599884D03*
X1237474D03*
X1249534D03*
X1237130Y1587598D03*
Y1592590D03*
X1249190D03*
X1244234D03*
Y1587598D03*
X1249190D03*
X1245012Y1590094D03*
X1236352D03*
X1248412D03*
X1242430Y1616788D03*
X1237474D03*
X1242430Y1611796D03*
Y1604876D03*
X1237474Y1611796D03*
Y1604876D03*
X1249534Y1611796D03*
Y1604876D03*
Y1616788D03*
X1238252Y1614292D03*
X1241652D03*
X1238252Y1602380D03*
X1241652D03*
X1241142Y1675383D03*
Y1679920D03*
X1249016Y1679320D03*
X1241142Y1684454D03*
Y1689556D03*
Y1694093D03*
Y1698627D03*
X1249016Y1688391D03*
Y1693493D03*
Y1698030D03*
Y1683857D03*
X1241142Y1703729D03*
Y1708266D03*
Y1712800D03*
X1249016Y1707666D03*
Y1712203D03*
Y1702564D03*
X1241142Y1726974D03*
Y1722440D03*
Y1717903D03*
X1249016Y1730911D03*
Y1726377D03*
Y1721840D03*
Y1716737D03*
X1261250Y1575686D03*
X1256294D03*
X1261250Y1580678D03*
X1256294D03*
X1257072Y1578182D03*
X1260472D03*
X1254490Y1599884D03*
X1261594D03*
X1261250Y1587598D03*
X1256294D03*
X1261250Y1592590D03*
X1256294D03*
X1257072Y1590094D03*
X1260472D03*
X1254490Y1611796D03*
Y1604876D03*
Y1616788D03*
X1261594D03*
Y1611796D03*
Y1604876D03*
X1262372Y1614292D03*
X1250312D03*
X1265772D03*
X1253712D03*
X1262372Y1602380D03*
X1250312D03*
X1265772D03*
X1253712D03*
X1256890Y1675383D03*
Y1679920D03*
X1264764Y1679320D03*
X1256890Y1684454D03*
Y1689556D03*
Y1694093D03*
Y1698627D03*
X1264764Y1688391D03*
Y1693493D03*
Y1698030D03*
Y1683857D03*
X1256890Y1703729D03*
Y1708266D03*
Y1712800D03*
X1264764Y1707666D03*
Y1712203D03*
Y1702564D03*
X1256890Y1726974D03*
Y1722440D03*
Y1717903D03*
X1264764Y1730911D03*
Y1726377D03*
Y1721840D03*
Y1716737D03*
X1273310Y1580678D03*
Y1575592D03*
X1268354D03*
Y1580678D03*
X1280414Y1575686D03*
Y1580678D03*
X1269132Y1578182D03*
X1281192D03*
X1272532D03*
X1266550Y1599884D03*
X1273654Y1599790D03*
X1278610D03*
X1273310Y1592590D03*
X1268354D03*
X1273310Y1587598D03*
X1268354D03*
X1280414D03*
Y1592590D03*
X1269132Y1590094D03*
X1281192D03*
X1272532D03*
X1266550Y1616788D03*
Y1611796D03*
Y1604876D03*
X1273654Y1611796D03*
Y1604876D03*
X1278610Y1611796D03*
Y1604876D03*
X1273654Y1616788D03*
X1278610D03*
X1274432Y1614292D03*
X1277832D03*
X1274432Y1602380D03*
X1277832D03*
X1272638Y1675383D03*
Y1679920D03*
X1280512Y1679320D03*
X1272638Y1684454D03*
Y1689556D03*
Y1694093D03*
Y1698627D03*
X1280512Y1688391D03*
Y1693493D03*
Y1698030D03*
Y1683857D03*
X1272638Y1703729D03*
Y1708266D03*
Y1712800D03*
X1280512Y1707666D03*
Y1712203D03*
Y1702564D03*
X1272638Y1726974D03*
Y1722440D03*
Y1717903D03*
X1280512Y1730911D03*
Y1726377D03*
Y1721840D03*
Y1716737D03*
X1297012Y157449D03*
X1293802Y159299D03*
Y162999D03*
X1297007Y161149D03*
X1297012Y168549D03*
X1297007Y164849D03*
X1293802Y166699D03*
X1293511Y179048D03*
X1296999Y183349D03*
X1297007Y172249D03*
X1296999Y175949D03*
X1293802Y183349D03*
Y170399D03*
X1294163Y175865D03*
X1296999Y179649D03*
Y194449D03*
Y198149D03*
Y190749D03*
X1293802Y187049D03*
Y190749D03*
Y198149D03*
Y194449D03*
Y201849D03*
X1296999Y187049D03*
Y201849D03*
X1293805Y211099D03*
X1293798Y205833D03*
X1296999Y216649D03*
Y209249D03*
X1293807Y218499D03*
Y214799D03*
X1296999Y212949D03*
Y205549D03*
X1294357Y224688D03*
X1296999Y224049D03*
X1293807Y222199D03*
X1300393Y235762D03*
X1285370Y1575686D03*
Y1580678D03*
X1297430D03*
X1292474D03*
Y1575686D03*
X1297430D03*
X1293252Y1578182D03*
X1284592D03*
X1296652D03*
X1285714Y1599884D03*
X1290670D03*
X1297774D03*
X1285370Y1587598D03*
Y1592590D03*
X1297430D03*
X1292474D03*
X1297430Y1587598D03*
X1292474D03*
X1293252Y1590094D03*
X1284592D03*
X1296652D03*
X1290670Y1616788D03*
X1285714D03*
Y1611796D03*
X1290670D03*
X1285714Y1604876D03*
X1290670D03*
X1297774Y1611796D03*
Y1604876D03*
Y1616788D03*
X1298552Y1614292D03*
X1286492D03*
X1289892D03*
X1298552Y1602380D03*
X1286492D03*
X1289892D03*
X1296260Y1679320D03*
X1288386Y1675383D03*
Y1679920D03*
X1296260Y1688391D03*
Y1693493D03*
Y1698030D03*
Y1683857D03*
X1288386Y1684454D03*
Y1689556D03*
Y1694093D03*
Y1698627D03*
X1296260Y1707666D03*
Y1712203D03*
Y1702564D03*
X1288386Y1703729D03*
Y1708266D03*
Y1712800D03*
X1296260Y1730911D03*
Y1726377D03*
Y1721840D03*
Y1716737D03*
X1288386Y1726974D03*
Y1722440D03*
Y1717903D03*
X1303417Y164849D03*
X1300213Y162999D03*
X1300212Y166699D03*
X1306622D03*
X1300774Y155288D03*
X1309832Y161149D03*
X1303417D03*
X1309832Y168549D03*
X1303417D03*
X1309832Y157449D03*
X1306626Y162999D03*
Y159299D03*
X1313037Y162999D03*
X1309832Y164849D03*
X1313037Y159299D03*
X1303417Y157449D03*
X1300217Y159299D03*
X1313033Y166699D03*
X1300212Y170399D03*
X1306626D03*
X1303407Y183349D03*
X1309817Y175949D03*
X1300212Y174099D03*
X1313037Y170399D03*
X1300207Y177799D03*
X1303422Y172249D03*
X1313033Y174099D03*
X1306622D03*
X1300207Y185199D03*
X1306617Y181499D03*
Y185199D03*
X1309832Y172249D03*
X1313027Y181499D03*
Y185199D03*
X1303407Y175949D03*
Y179649D03*
X1306617Y177799D03*
X1309817Y179649D03*
X1300204Y181499D03*
X1309817Y194449D03*
X1306617Y188899D03*
X1303407Y194449D03*
X1306617Y196299D03*
X1300207D03*
X1303407Y190749D03*
Y187049D03*
X1300207Y192599D03*
X1309817Y187049D03*
X1306617Y192599D03*
X1313023Y199999D03*
X1306617D03*
X1300207D03*
X1303407Y201849D03*
X1300204Y188899D03*
X1313027Y192599D03*
X1309817Y190749D03*
X1313025Y188899D03*
X1309817Y198149D03*
X1303407D03*
X1300207Y203699D03*
Y207399D03*
X1303422Y209249D03*
X1313032Y214799D03*
X1306622Y218499D03*
X1303417Y212949D03*
Y216649D03*
X1300207Y214799D03*
X1309832Y209249D03*
X1313027Y203699D03*
X1300220Y218499D03*
X1309833Y220349D03*
X1303416Y205549D03*
X1306614Y203699D03*
X1306627Y214799D03*
X1316242Y209249D03*
X1300207Y211099D03*
X1303422Y220349D03*
X1301151Y225450D03*
X1309828Y224049D03*
X1306622Y222199D03*
X1300220D03*
X1313033D03*
X1303425Y224049D03*
X1309100Y236477D03*
X1300493Y238062D03*
X1314184Y849978D03*
X1313920Y854584D03*
X1312266Y857972D03*
X1312070Y877014D03*
X1310221Y880219D03*
X1308370Y877014D03*
X1313921Y880219D03*
X1312070Y883423D03*
Y896240D03*
X1310220Y893036D03*
X1313921D03*
X1312070Y889832D03*
X1310221Y886627D03*
X1313921D03*
X1308371Y902649D03*
X1312070Y915466D03*
X1308370D03*
X1308371Y921875D03*
X1312070Y934692D03*
X1308371Y941100D03*
X1308370Y934692D03*
X1312070Y953917D03*
X1308370D03*
X1310221Y957122D03*
X1308371Y973143D03*
X1310221Y976347D03*
X1307426Y978814D03*
X1311491Y985939D03*
X1314352Y996480D03*
X1314353Y1002888D03*
X1308803Y1006093D03*
X1314353Y1015705D03*
X1308803Y1025318D03*
Y1018910D03*
Y1044544D03*
X1310653Y1041340D03*
X1309976Y1062790D03*
X1305774Y1092168D03*
X1312502Y1082995D03*
X1314353Y1111834D03*
X1311486Y1097289D03*
X1314353Y1124651D03*
X1312503Y1115039D03*
Y1127856D03*
X1314353Y1118243D03*
X1312503Y1121447D03*
X1314353Y1131060D03*
X1309490Y1575686D03*
X1304534D03*
X1309490Y1580678D03*
X1304534D03*
X1305312Y1578182D03*
X1308712D03*
X1302730Y1599884D03*
X1309834D03*
X1314790D03*
X1309490Y1587598D03*
X1304534D03*
X1309490Y1592590D03*
X1304534D03*
X1305312Y1590094D03*
X1308712D03*
X1302730Y1611796D03*
Y1604876D03*
Y1616788D03*
X1309834D03*
Y1611796D03*
Y1604876D03*
X1314790Y1616788D03*
Y1611796D03*
Y1604876D03*
X1310612Y1614292D03*
X1314012D03*
X1301952D03*
X1310612Y1602380D03*
X1314012D03*
X1301952D03*
X1308071Y1675383D03*
Y1679920D03*
Y1684454D03*
Y1689556D03*
Y1694093D03*
Y1698627D03*
Y1703729D03*
Y1708266D03*
Y1712800D03*
Y1726974D03*
Y1722440D03*
Y1717903D03*
X1319452Y162999D03*
X1316242Y168549D03*
X1319442Y159299D03*
X1316241Y157449D03*
X1320469Y155288D03*
X1322652Y161149D03*
X1316242D03*
X1319452Y166699D03*
X1329062Y168549D03*
X1316242Y164849D03*
X1322652D03*
X1329062D03*
X1326918Y161161D03*
X1329062Y157449D03*
X1322652D03*
X1319442Y170399D03*
X1318502Y176574D03*
Y186024D03*
Y182874D03*
X1329062Y172249D03*
X1316237D03*
X1331102Y176574D03*
X1327952Y186024D03*
Y182874D03*
X1325853Y174099D03*
X1331102Y179724D03*
Y182874D03*
Y186024D03*
X1325085Y176402D03*
X1324802Y179724D03*
Y186024D03*
Y182874D03*
X1315352Y186024D03*
Y179724D03*
X1319442Y174099D03*
X1332268D03*
X1318502Y189174D03*
X1315352Y195474D03*
X1327952Y189174D03*
X1331102Y195474D03*
X1327952Y198624D03*
X1321652D03*
X1324802Y195474D03*
X1327952D03*
X1318502D03*
X1321652D03*
X1327952Y201774D03*
X1321652D03*
X1331102Y189174D03*
X1315405Y189227D03*
X1325852Y214799D03*
X1319442Y218499D03*
X1329062Y209249D03*
X1319442Y207399D03*
X1329062Y216649D03*
Y212949D03*
X1325852Y211099D03*
X1319442D03*
X1324802Y204924D03*
X1327952D03*
X1318502D03*
X1315352D03*
X1322652Y209249D03*
X1325857Y218499D03*
X1322652Y216649D03*
X1319442Y222199D03*
X1329061Y224049D03*
X1329062Y220349D03*
X1325856Y222199D03*
X1322652Y224049D03*
Y220349D03*
X1326377Y235784D03*
X1321986Y236726D03*
X1326869Y844971D03*
X1323170D03*
X1321320Y848176D03*
X1330571Y851380D03*
X1323170D03*
X1319469D03*
X1321320Y854584D03*
X1326869Y851380D03*
X1330569Y844971D03*
X1325020Y848176D03*
X1328720D03*
X1317620Y854584D03*
X1315770Y857789D03*
X1328721Y854584D03*
X1330571Y864197D03*
X1326871D03*
X1323171D03*
Y857789D03*
X1325020Y854584D03*
X1321321Y860993D03*
X1319469Y857789D03*
X1328721Y867401D03*
X1325021D03*
Y860993D03*
X1326871Y857789D03*
X1328720Y860993D03*
X1330571Y857789D03*
Y877014D03*
X1328722Y880219D03*
X1323171Y870606D03*
X1326871Y877014D03*
X1321321Y873810D03*
X1315771Y877014D03*
X1321321Y880219D03*
X1319471Y877014D03*
X1315771Y883423D03*
X1326871D03*
X1323171D03*
X1317621Y880219D03*
X1319471Y883423D03*
X1326871Y870606D03*
X1330571D03*
X1328720Y873810D03*
X1330571Y883423D03*
X1325020Y873810D03*
X1323171Y877014D03*
X1325020Y880219D03*
X1328720Y899445D03*
X1315771Y896240D03*
Y889832D03*
X1328720Y893036D03*
Y886627D03*
X1325021D03*
X1323171Y889832D03*
X1321321Y893036D03*
X1319470Y896240D03*
X1321321Y899445D03*
X1325020D03*
Y893036D03*
X1326871Y889832D03*
X1330571D03*
X1317620Y893036D03*
X1319470Y889832D03*
X1323171Y896240D03*
X1330571D03*
X1317621Y886627D03*
X1326871Y896240D03*
X1321321Y886627D03*
X1328720Y905853D03*
X1325020D03*
X1328720Y912262D03*
X1323171Y909057D03*
Y902649D03*
X1321321Y912262D03*
X1315771Y915466D03*
X1319471D03*
X1325020Y912262D03*
X1326871Y909057D03*
X1330571D03*
X1326871Y902649D03*
X1330571D03*
X1323171Y915466D03*
X1330571D03*
X1326871D03*
X1328720Y925079D03*
Y918670D03*
X1325020Y925079D03*
X1323171Y928283D03*
Y921875D03*
X1321321Y918670D03*
X1328720Y931488D03*
X1321321D03*
X1325021D03*
X1326871Y928283D03*
X1330571D03*
Y921875D03*
X1326871D03*
X1325020Y918670D03*
X1323171Y941100D03*
X1325020Y944304D03*
X1323171Y947509D03*
X1328720Y944304D03*
Y937896D03*
X1315771Y934692D03*
X1321321Y937896D03*
X1319470Y934692D03*
X1326871Y941100D03*
X1325020Y937896D03*
X1330571Y941100D03*
X1323171Y934691D03*
X1330571D03*
X1326871D03*
Y947509D03*
X1330571D03*
X1321321Y957122D03*
X1323171Y966735D03*
X1325020Y963530D03*
X1323171Y960326D03*
X1321321Y950713D03*
X1315771Y953917D03*
Y966735D03*
X1319470Y953917D03*
X1328720Y957122D03*
Y963530D03*
Y950713D03*
X1325020D03*
X1326871Y960326D03*
X1325020Y957122D03*
X1330571Y960326D03*
X1326871Y966735D03*
X1330571D03*
X1326871Y953917D03*
X1330571D03*
X1323172D03*
X1321321Y969939D03*
X1325020Y982756D03*
X1323171Y979552D03*
X1321321Y976347D03*
X1315771Y973143D03*
X1319471D03*
X1328720Y969939D03*
X1330570Y973143D03*
X1326871D03*
X1328720Y982756D03*
X1328721Y976347D03*
X1315771Y979552D03*
X1326871D03*
X1330571D03*
X1325020Y976347D03*
X1323171Y973143D03*
X1325020Y969939D03*
X1327304Y1006093D03*
X1331003D03*
X1329153Y1009297D03*
Y1002888D03*
X1323603Y999684D03*
X1321753Y1009297D03*
X1319903Y1006093D03*
X1321753Y1002888D03*
X1323603Y1012501D03*
Y1006093D03*
X1325453Y1002888D03*
X1327303Y999684D03*
X1331003D03*
X1327303Y1012501D03*
X1325453Y1009297D03*
X1331003Y1012501D03*
X1319903Y999684D03*
X1329153Y1028523D03*
Y1015705D03*
X1318053D03*
X1329153Y1022114D03*
X1325453Y1015705D03*
X1323603Y1018910D03*
X1321753Y1028523D03*
Y1022114D03*
X1323603Y1031727D03*
X1327304D03*
X1325453Y1028523D03*
X1331003Y1031727D03*
X1325453Y1022114D03*
X1327303Y1018910D03*
X1331003D03*
X1323603Y1025318D03*
X1331004D03*
X1327304D03*
X1329153Y1034931D03*
Y1047749D03*
Y1041340D03*
X1325453Y1034931D03*
X1323603Y1038136D03*
X1321753Y1041340D03*
X1319903Y1044544D03*
X1321753Y1047749D03*
X1325453D03*
Y1041340D03*
X1327303Y1038136D03*
X1331003D03*
X1323603Y1044544D03*
X1331003D03*
X1327303D03*
X1329153Y1060565D03*
Y1054157D03*
X1325453D03*
X1323603Y1050952D03*
Y1057361D03*
X1321753Y1060565D03*
X1319903Y1063770D03*
X1325453Y1060565D03*
X1327303Y1057361D03*
X1331003D03*
X1323603Y1063770D03*
X1327303D03*
X1331003D03*
X1327303Y1050952D03*
X1331003D03*
X1329153Y1073383D03*
X1316204Y1076587D03*
X1329153Y1066974D03*
X1323603Y1076587D03*
Y1070178D03*
X1325454Y1073383D03*
X1321753Y1066974D03*
X1329153Y1079791D03*
X1321753D03*
X1331003Y1070178D03*
X1327304D03*
X1325453Y1066974D03*
Y1079791D03*
X1327303Y1076587D03*
X1331003D03*
X1329153Y1086200D03*
Y1092608D03*
X1325452Y1092609D03*
X1323603Y1089404D03*
X1321752Y1086200D03*
X1319902Y1082995D03*
X1319849Y1091513D03*
X1327303Y1089404D03*
X1325453Y1086200D03*
X1331003Y1089404D03*
X1323603Y1082995D03*
X1331003D03*
X1327303D03*
X1331003Y1108630D03*
X1329153Y1099017D03*
X1323603Y1108630D03*
X1316203D03*
Y1102221D03*
X1325453Y1099017D03*
X1323603Y1102221D03*
X1319903D03*
X1325453Y1105426D03*
X1329153D03*
X1325454Y1111834D03*
X1327303Y1102221D03*
X1321753Y1111834D03*
X1318054D03*
X1318053Y1105426D03*
X1327304Y1108630D03*
X1329154Y1111834D03*
X1331003Y1102221D03*
X1319904Y1108630D03*
X1321753Y1105426D03*
X1316203Y1115039D03*
X1331003D03*
X1327303Y1121447D03*
Y1115039D03*
X1325453Y1124651D03*
X1325454Y1118243D03*
X1321753D03*
X1319903Y1115039D03*
X1318053Y1124651D03*
X1329153D03*
X1331003Y1127856D03*
X1327304D03*
X1329153Y1118243D03*
X1331003Y1121447D03*
X1323603D03*
X1319903Y1127856D03*
X1316203D03*
X1318054Y1118243D03*
X1321753Y1124651D03*
X1323603Y1127856D03*
X1319903Y1121447D03*
X1316203D03*
X1323603Y1115039D03*
X1329152Y1137469D03*
X1329153Y1131060D03*
X1321752Y1137469D03*
X1321753Y1131060D03*
X1325453D03*
X1319903Y1134264D03*
X1325452Y1137469D03*
X1327303Y1134264D03*
X1331003D03*
X1323603D03*
X1318053Y1131060D03*
X1321550Y1580678D03*
X1316594D03*
X1321550Y1575686D03*
X1316594D03*
X1328654D03*
Y1580678D03*
X1317372Y1578182D03*
X1320772D03*
X1329432D03*
X1321894Y1599884D03*
X1326850D03*
X1321550Y1592590D03*
X1316594D03*
X1321550Y1587598D03*
X1316594D03*
X1328654D03*
Y1592590D03*
X1317372Y1590094D03*
X1320772D03*
X1329432D03*
X1321894Y1611796D03*
Y1604876D03*
X1326850Y1611796D03*
Y1604876D03*
X1321894Y1616788D03*
X1326850D03*
X1322672Y1614292D03*
X1326072D03*
X1322672Y1602380D03*
X1326072D03*
X1323819Y1675383D03*
Y1679920D03*
X1315945Y1679320D03*
X1323819Y1684454D03*
Y1689556D03*
Y1694093D03*
Y1698627D03*
X1315945Y1688391D03*
Y1693493D03*
Y1698030D03*
Y1683857D03*
X1323819Y1703729D03*
Y1708266D03*
Y1712800D03*
X1315945Y1707666D03*
Y1712203D03*
Y1702564D03*
X1323819Y1726974D03*
Y1722440D03*
Y1717903D03*
X1315945Y1730911D03*
Y1726377D03*
Y1721840D03*
Y1716737D03*
X1339727Y161149D03*
X1341992Y156897D03*
X1344103Y155288D03*
X1342936Y159301D03*
X1335472Y161149D03*
X1346137Y168549D03*
X1342907Y166699D03*
X1332268D03*
X1346137Y164849D03*
X1339727D03*
X1335472Y168549D03*
X1332268Y162999D03*
X1342903Y170399D03*
X1339727Y168549D03*
X1335472Y164849D03*
X1346140Y161149D03*
X1342937Y162999D03*
X1335472Y157449D03*
X1346140D03*
X1339727D03*
X1339568Y176028D03*
X1339727Y179649D03*
X1342937Y181499D03*
Y185199D03*
X1346137Y172249D03*
X1335472D03*
X1332268Y170399D03*
X1334252Y176574D03*
X1339727Y183349D03*
X1346137Y175949D03*
X1342937Y177799D03*
X1346137Y183349D03*
Y179649D03*
X1339727Y190749D03*
X1342937Y188899D03*
X1334252Y195474D03*
X1346137Y194449D03*
Y190749D03*
X1337901Y196035D03*
X1339727Y187049D03*
X1337345Y201831D03*
X1339727Y201849D03*
X1337402Y198624D03*
X1342937Y192599D03*
X1346137Y187049D03*
X1346147Y201849D03*
Y198149D03*
X1336527Y214799D03*
X1339727Y216649D03*
X1346147Y212949D03*
Y216649D03*
X1336527Y218499D03*
X1342937D03*
Y214799D03*
X1346147Y209248D03*
X1337102Y206675D03*
X1332262Y218499D03*
Y214799D03*
Y211099D03*
X1339686Y205478D03*
X1332262Y207399D03*
X1339727Y209249D03*
Y220349D03*
X1336527Y222199D03*
X1346147Y220349D03*
X1332285Y226210D03*
X1342937Y222199D03*
X1332267D03*
X1343521Y841467D03*
X1336121D03*
X1345371Y851380D03*
X1341671D03*
X1337971D03*
X1334271D03*
X1347220Y848176D03*
X1339820D03*
X1332420D03*
X1332421Y841467D03*
X1337969Y844971D03*
X1339821Y841467D03*
X1345369Y844971D03*
X1347221Y841467D03*
X1334269Y844971D03*
X1336120Y848176D03*
X1341669Y844971D03*
X1343520Y848176D03*
X1345371Y864197D03*
X1343521Y854584D03*
X1341671Y864197D03*
X1337971D03*
X1336121Y854584D03*
X1334271Y864197D03*
X1343521Y867401D03*
X1336121D03*
X1347220D03*
X1332420D03*
X1339820D03*
Y860993D03*
X1347220D03*
X1332420D03*
Y854584D03*
X1334271Y857789D03*
X1337971D03*
X1341671D03*
X1345371D03*
X1336120Y860993D03*
X1339820Y854584D03*
X1343520Y860993D03*
X1347220Y854584D03*
X1345371Y877014D03*
X1343521Y880219D03*
X1341671Y877014D03*
X1337971D03*
X1336121Y880219D03*
X1334271Y877014D03*
Y870606D03*
X1337971D03*
X1341671D03*
X1336120Y873810D03*
X1343520D03*
X1345371Y870606D03*
X1332420Y880219D03*
X1334271Y883423D03*
X1339820Y880219D03*
X1341671Y883423D03*
X1347220Y880219D03*
X1337971Y883423D03*
X1345371D03*
X1339820Y873810D03*
X1332420D03*
X1347220D03*
X1332420Y886627D03*
X1345371Y896240D03*
Y889832D03*
X1341671Y896240D03*
Y889832D03*
X1337970Y896240D03*
X1337971Y889832D03*
X1336121Y893036D03*
X1334270Y889832D03*
X1336121Y899445D03*
X1347220D03*
X1332420D03*
Y893036D03*
X1334271Y896240D03*
X1339820Y899445D03*
X1343520D03*
X1347220Y893036D03*
X1339821D03*
X1343521D03*
X1336120Y886627D03*
X1343520D03*
X1347220D03*
X1339820D03*
X1332420Y905853D03*
X1341671Y909057D03*
Y902649D03*
X1336120Y912262D03*
X1334270Y909057D03*
X1334271Y902649D03*
X1347221Y912262D03*
X1345371Y915466D03*
X1341671D03*
X1337970D03*
X1332420Y912262D03*
X1334271Y915466D03*
X1339820Y912262D03*
X1337971Y909057D03*
X1343520Y912262D03*
X1345371Y909057D03*
X1337971Y902649D03*
X1345371D03*
X1336120Y905853D03*
X1343520D03*
X1339820D03*
X1347220D03*
X1332421Y925079D03*
X1341671Y928283D03*
Y921875D03*
X1336121Y918670D03*
X1334270Y928283D03*
X1334271Y921875D03*
X1347220Y918670D03*
X1336120Y931488D03*
X1347221D03*
X1332420D03*
X1339820D03*
X1332420Y918670D03*
X1337971Y928283D03*
X1343520Y931488D03*
X1345371Y928283D03*
X1337971Y921875D03*
X1339820Y918670D03*
X1345371Y921875D03*
X1343520Y918670D03*
X1336120Y925079D03*
X1343520D03*
X1339820D03*
X1347220D03*
X1341671Y947509D03*
Y941100D03*
X1334270Y947509D03*
X1334271Y941100D03*
X1332421Y944304D03*
X1345371Y934691D03*
X1341671D03*
X1337970D03*
X1336121Y937896D03*
X1347220D03*
X1332420D03*
X1334271Y934691D03*
X1337971Y941100D03*
X1339820Y937896D03*
X1345371Y941100D03*
X1343520Y937896D03*
X1337971Y947509D03*
X1345371D03*
X1343520Y944304D03*
X1336120D03*
X1347220D03*
X1339820D03*
X1337971Y953917D03*
X1345371D03*
X1341671D03*
Y960326D03*
X1347220Y957122D03*
X1343520Y963530D03*
X1339821D03*
X1341670Y966735D03*
X1347221Y950713D03*
X1334271Y960326D03*
X1336121Y957122D03*
X1332421Y963530D03*
X1334270Y966735D03*
X1336120Y950713D03*
X1332420D03*
Y957122D03*
X1334271Y953917D03*
X1337971Y966735D03*
X1345371D03*
X1336120Y963530D03*
X1339820Y950713D03*
X1343520D03*
X1337971Y960326D03*
X1339820Y957122D03*
X1345371Y960326D03*
X1343520Y957122D03*
X1347220Y963530D03*
X1347221Y969939D03*
X1337970Y973143D03*
X1347220Y976347D03*
X1345371Y973143D03*
X1341671Y979552D03*
Y973143D03*
X1336120Y969939D03*
X1336121Y976347D03*
X1334271Y979552D03*
X1332421Y982756D03*
X1336120D03*
X1343520D03*
X1339820D03*
X1347220D03*
X1345371Y979552D03*
X1343520Y976347D03*
X1337971Y979552D03*
X1339820Y976347D03*
X1332420D03*
Y969939D03*
X1334271Y973143D03*
X1339820Y969939D03*
X1343520D03*
X1345804Y1006093D03*
X1342104Y999684D03*
Y1006093D03*
X1338403D03*
X1336553Y1009297D03*
X1336554Y1002888D03*
X1334704Y999684D03*
X1347654Y1009297D03*
X1342103Y1012501D03*
X1334703D03*
X1334704Y1006093D03*
X1332853Y1002888D03*
Y1009297D03*
X1338404Y1012501D03*
X1345804D03*
X1340253Y1009297D03*
X1343953D03*
X1340253Y1002888D03*
X1338404Y999684D03*
X1345804D03*
X1332854Y1015705D03*
X1345804Y1025318D03*
X1343953Y1015705D03*
X1342104Y1025318D03*
Y1018910D03*
X1340254Y1015705D03*
X1336553Y1028523D03*
X1338403Y1025318D03*
X1336554Y1022114D03*
X1334704Y1018910D03*
X1347653Y1028523D03*
Y1022114D03*
X1342104Y1031727D03*
X1334703D03*
X1332853Y1028523D03*
Y1022114D03*
X1338404Y1031727D03*
X1340253Y1028523D03*
X1345804Y1031727D03*
X1343953Y1028523D03*
X1334704Y1025318D03*
X1336553Y1015705D03*
X1347653D03*
X1340253Y1022114D03*
X1338404Y1018910D03*
X1343953Y1022114D03*
X1345804Y1018910D03*
X1332854Y1034931D03*
X1345804Y1044544D03*
X1342104D03*
Y1038136D03*
X1338403Y1044544D03*
X1336554Y1041340D03*
X1334704Y1038136D03*
X1347653Y1041340D03*
X1336553Y1047749D03*
X1347653D03*
X1332853D03*
Y1041340D03*
X1340253D03*
X1338404Y1038136D03*
X1343953Y1041340D03*
X1345804Y1038136D03*
X1336553Y1034931D03*
X1347653D03*
X1340253D03*
X1334704Y1044544D03*
X1343953Y1034931D03*
X1340253Y1047749D03*
X1343953D03*
X1332854Y1054157D03*
X1342104Y1057361D03*
Y1050952D03*
X1336554Y1060565D03*
X1334704Y1057361D03*
X1334703Y1050952D03*
X1347653Y1060565D03*
X1345804Y1063770D03*
X1342104D03*
X1338403D03*
X1332853Y1060565D03*
X1334704Y1063770D03*
X1340253Y1060565D03*
X1338404Y1057361D03*
X1343953Y1060565D03*
X1345804Y1057361D03*
X1338404Y1050952D03*
X1345804D03*
X1336553Y1054157D03*
X1347653D03*
X1340253D03*
X1343953D03*
X1332854Y1073383D03*
X1342104Y1070178D03*
Y1076587D03*
X1336553Y1066974D03*
X1334703Y1070178D03*
X1334704Y1076587D03*
X1347654Y1066974D03*
X1336554Y1079791D03*
X1347653D03*
X1332853Y1066974D03*
X1343953Y1079791D03*
X1345804Y1076587D03*
X1338404Y1070178D03*
X1340253Y1066974D03*
X1345804Y1070178D03*
X1343953Y1066974D03*
X1332853Y1079791D03*
X1340253D03*
X1338404Y1076587D03*
X1336553Y1073383D03*
X1347653D03*
X1340253D03*
X1343953D03*
X1345804Y1082995D03*
X1342104Y1089404D03*
Y1082995D03*
X1338403D03*
X1336553Y1086200D03*
X1334703Y1089404D03*
X1332854Y1092608D03*
X1347654Y1086200D03*
X1342104Y1095813D03*
X1334703D03*
X1332853Y1086200D03*
X1334704Y1082995D03*
X1338404Y1095813D03*
X1345804D03*
X1338404Y1089404D03*
X1340253Y1086200D03*
X1345804Y1089404D03*
X1343953Y1086200D03*
X1336553Y1092608D03*
X1343953D03*
X1340253D03*
X1347653D03*
X1342104Y1102221D03*
X1338404D03*
X1336553Y1099017D03*
X1332853Y1105426D03*
Y1099017D03*
X1347654Y1105426D03*
Y1099017D03*
X1340254Y1111834D03*
X1332854D03*
X1347654D03*
X1340253Y1099017D03*
X1343953D03*
X1334704Y1102221D03*
X1345803D03*
X1343953Y1105426D03*
X1336554D03*
X1345803Y1108630D03*
X1340254Y1105426D03*
X1336554Y1111834D03*
X1334703Y1108630D03*
X1343954Y1111834D03*
X1342103Y1108630D03*
X1338403D03*
X1343953Y1118243D03*
X1340253D03*
X1338403Y1115039D03*
X1336553Y1118243D03*
X1332853D03*
X1347653D03*
X1342104Y1127856D03*
X1334703D03*
Y1121447D03*
X1336554Y1124651D03*
X1340253D03*
X1343953D03*
X1347653D03*
X1332854D03*
X1338404Y1127856D03*
X1342104Y1121447D03*
X1345804Y1127856D03*
Y1121447D03*
X1338403D03*
X1342103Y1115039D03*
X1345803D03*
X1334703D03*
X1343953Y1131060D03*
X1342103Y1140973D03*
X1340254Y1131060D03*
X1336554D03*
X1334703Y1140973D03*
X1332854Y1131060D03*
X1347653D03*
X1334703Y1134264D03*
X1338403Y1140973D03*
X1342104Y1134264D03*
X1345803Y1140973D03*
X1332854Y1137469D03*
X1336554D03*
X1340254D03*
X1343954D03*
X1347654D03*
X1338404Y1134264D03*
X1345804D03*
X1333610Y1575686D03*
Y1580678D03*
X1345670D03*
X1340714D03*
X1345670Y1575686D03*
X1340714D03*
X1332832Y1578182D03*
X1341492D03*
X1344892D03*
X1338910Y1599884D03*
X1333954D03*
X1346014D03*
X1333610Y1587598D03*
Y1592590D03*
X1345670D03*
X1340714D03*
X1345670Y1587598D03*
X1340714D03*
X1332832Y1590094D03*
X1341492D03*
X1344892D03*
X1338910Y1616788D03*
Y1611796D03*
Y1604876D03*
X1333954Y1616788D03*
Y1611796D03*
Y1604876D03*
X1346014Y1611796D03*
Y1604876D03*
Y1616788D03*
X1346792Y1614292D03*
X1334732D03*
X1338132D03*
X1346792Y1602380D03*
X1334732D03*
X1338132D03*
X1339567Y1675383D03*
Y1679920D03*
X1331693Y1679320D03*
X1347441D03*
X1339567Y1684454D03*
Y1689556D03*
Y1694093D03*
Y1698627D03*
X1331693Y1688391D03*
Y1693493D03*
Y1698030D03*
Y1683857D03*
X1347441Y1688391D03*
Y1693493D03*
Y1698030D03*
Y1683857D03*
X1339567Y1703729D03*
Y1708266D03*
Y1712800D03*
X1331693Y1707666D03*
Y1712203D03*
Y1702564D03*
X1347441Y1707666D03*
Y1712203D03*
Y1702564D03*
X1339567Y1726974D03*
Y1722440D03*
Y1717903D03*
X1331693Y1730911D03*
Y1726377D03*
Y1721840D03*
Y1716737D03*
X1347441Y1730911D03*
Y1726377D03*
Y1721840D03*
Y1716737D03*
X1352550Y157449D03*
X1349351Y159298D03*
X1355758D03*
X1355761Y162998D03*
X1358865Y166732D03*
Y158854D03*
Y162793D03*
X1349351Y166698D03*
X1352557Y164848D03*
X1355961Y155458D03*
X1352557Y168548D03*
X1355762Y166698D03*
X1349344Y162999D03*
X1348386Y156646D03*
X1352551Y161148D03*
X1358865Y170671D03*
Y174603D03*
Y182484D03*
Y178544D03*
X1355761Y170398D03*
Y177798D03*
X1352557Y179648D03*
Y172248D03*
X1349351Y177798D03*
Y170398D03*
Y174098D03*
X1352557Y175948D03*
X1349351Y181498D03*
X1355761Y185198D03*
X1349351D03*
X1355761Y174098D03*
Y181498D03*
X1352557Y183348D03*
X1358371Y188778D03*
X1358865Y195240D03*
Y199180D03*
X1349351Y196298D03*
X1352561Y194448D03*
X1352551Y190748D03*
X1349345Y188898D03*
X1355761Y192598D03*
X1349351D03*
X1352551Y187048D03*
X1355761Y188898D03*
X1352561Y198148D03*
X1355771Y196298D03*
X1355765Y199999D03*
X1349361Y199998D03*
X1352561Y201848D03*
X1355766Y214798D03*
X1349351Y218498D03*
X1352561Y216648D03*
X1355766Y218498D03*
X1358865Y207060D03*
Y203120D03*
Y213994D03*
Y217934D03*
X1352560Y205549D03*
X1355765Y207399D03*
X1349351Y214798D03*
X1352561Y212948D03*
X1349351Y211098D03*
X1355765Y203699D03*
X1352561Y220348D03*
X1355766Y222198D03*
X1349351D03*
X1360186Y226264D03*
X1358321Y841467D03*
X1350921D03*
X1360171Y851380D03*
X1356471D03*
X1352771D03*
X1349071D03*
X1363871D03*
X1362020Y848176D03*
X1354620D03*
X1363869Y844971D03*
X1352769D03*
X1356469D03*
X1360169D03*
X1362021Y841467D03*
X1349069Y844971D03*
X1350920Y848176D03*
X1354621Y841467D03*
X1358320Y848176D03*
X1360171Y864197D03*
X1358321Y854584D03*
X1356471Y864197D03*
X1352771D03*
X1350921Y854584D03*
X1349071Y864197D03*
X1363871D03*
X1358321Y867401D03*
X1350921D03*
X1354620D03*
X1362020D03*
Y860993D03*
X1354620D03*
X1349071Y857789D03*
X1354620Y854584D03*
X1356471Y857789D03*
X1360171D03*
X1363871D03*
X1350920Y860993D03*
X1352771Y857789D03*
X1358320Y860993D03*
X1362020Y854584D03*
X1360171Y877014D03*
X1358321Y880219D03*
X1356471Y877014D03*
X1352771D03*
X1350921Y880219D03*
X1349071Y877014D03*
X1363871D03*
Y870606D03*
X1349071D03*
X1356471D03*
X1350920Y873810D03*
X1352771Y870606D03*
X1358320Y873810D03*
X1360171Y870606D03*
X1349071Y883423D03*
X1354620Y880219D03*
X1356471Y883423D03*
X1362020Y880219D03*
X1363871Y883423D03*
X1352771D03*
X1360171D03*
X1354620Y873810D03*
X1362020D03*
X1360171Y889832D03*
X1356471D03*
X1354621Y893036D03*
X1352771Y889832D03*
X1349071D03*
X1363871Y896240D03*
Y889832D03*
X1362021Y899445D03*
X1354620D03*
X1350920D03*
X1358320D03*
Y893036D03*
X1350920D03*
X1362020D03*
X1349071Y896240D03*
X1356471D03*
X1352771D03*
X1360171D03*
X1350920Y886627D03*
X1358320D03*
X1354620D03*
X1362020D03*
Y912262D03*
X1360170Y909057D03*
X1360171Y902649D03*
X1358321Y905853D03*
X1354620Y912262D03*
Y905853D03*
X1350920D03*
X1349071Y909057D03*
X1349070Y902649D03*
X1363870Y915466D03*
X1352771Y902649D03*
X1356471D03*
X1350920Y912262D03*
X1352771Y909057D03*
X1358320Y912262D03*
X1356471Y909057D03*
X1363871D03*
Y902649D03*
X1349071Y915466D03*
X1362020Y905853D03*
X1356471Y915466D03*
X1352771D03*
X1360171D03*
X1362021Y918670D03*
X1360170Y928283D03*
X1360171Y921875D03*
X1358321Y925079D03*
X1354620D03*
Y918670D03*
X1350920Y925079D03*
X1349071Y928283D03*
X1349070Y921875D03*
X1362020Y931488D03*
X1354620D03*
X1350920D03*
X1352771Y928283D03*
X1358320Y931488D03*
X1356471Y928283D03*
X1363871Y921875D03*
X1352771D03*
X1350920Y918670D03*
X1356471Y921875D03*
X1358320Y918670D03*
X1363871Y928283D03*
X1362020Y925079D03*
X1360171Y941100D03*
X1358321Y944304D03*
X1354620D03*
X1360170Y947509D03*
X1350920Y944304D03*
X1349071Y947509D03*
X1349070Y941100D03*
X1362021Y937896D03*
X1354620D03*
X1363870Y934691D03*
X1356471Y941100D03*
X1358320Y937896D03*
X1352771Y947509D03*
X1356471D03*
X1352771Y941100D03*
X1350920Y937896D03*
X1349071Y934691D03*
X1356471D03*
X1352771D03*
X1360171D03*
X1363871Y947509D03*
Y941100D03*
X1362020Y944304D03*
X1363871Y953917D03*
X1360171Y960326D03*
X1362021Y957122D03*
X1354620D03*
X1358321Y963530D03*
X1354620D03*
X1360170Y966735D03*
X1354620Y950713D03*
X1362020D03*
X1349070Y960326D03*
X1350920Y963530D03*
X1349071Y966735D03*
X1352771Y960326D03*
X1350920Y957122D03*
X1356471Y960326D03*
X1358320Y957122D03*
X1350920Y950713D03*
X1358320D03*
X1349071Y953917D03*
X1356471D03*
X1352771D03*
X1360171D03*
X1363871Y960326D03*
Y966735D03*
X1356471D03*
X1352771D03*
X1362020Y963530D03*
Y969939D03*
X1354620D03*
X1363870Y973143D03*
X1362021Y976347D03*
X1360171Y979552D03*
X1358321Y982756D03*
X1356470Y973143D03*
X1354620Y982756D03*
X1354621Y976347D03*
X1350920Y982756D03*
X1349070Y979552D03*
X1352771Y973143D03*
X1362020Y982756D03*
X1363871Y979552D03*
X1352771D03*
X1356471D03*
X1350920Y976347D03*
X1358320D03*
X1349071Y973143D03*
X1350920Y969939D03*
X1358320D03*
X1360171Y973143D03*
X1351352Y996480D03*
X1349503Y999684D03*
X1362453Y1009297D03*
X1362454Y1002888D03*
X1360604Y999684D03*
X1355053Y1009297D03*
Y1002888D03*
X1360603Y1012501D03*
X1349504D03*
Y1006093D03*
X1356904D03*
X1353204D03*
X1360604D03*
X1351353Y1002888D03*
X1353204Y999684D03*
X1358753Y1002888D03*
X1356904Y999684D03*
X1353204Y1012501D03*
X1351353Y1009297D03*
X1356904Y1012501D03*
X1358753Y1009297D03*
X1362453Y1028523D03*
X1362454Y1022114D03*
X1360604Y1018910D03*
X1358754Y1015705D03*
X1355053Y1028523D03*
Y1022114D03*
Y1015705D03*
X1351353D03*
X1349503Y1018910D03*
X1360603Y1031727D03*
X1349504D03*
X1353204D03*
X1351353Y1028523D03*
X1356904Y1031727D03*
X1358753Y1028523D03*
X1351353Y1022114D03*
X1353204Y1018910D03*
X1358753Y1022114D03*
X1356904Y1018910D03*
X1353204Y1025318D03*
X1360604D03*
X1349502D03*
X1356902D03*
X1362453Y1015705D03*
X1362454Y1041340D03*
X1360604Y1038136D03*
X1358754Y1034931D03*
X1355053Y1041340D03*
Y1034931D03*
X1351353D03*
X1349503Y1038136D03*
X1362453Y1047749D03*
X1355053D03*
X1351353D03*
X1358753D03*
X1351353Y1041340D03*
X1353204Y1038136D03*
X1358753Y1041340D03*
X1356904Y1038136D03*
X1349504Y1044544D03*
X1356904D03*
X1353204D03*
X1360604D03*
X1362453Y1034931D03*
X1362454Y1060565D03*
X1360604Y1057361D03*
X1360603Y1050952D03*
X1358754Y1054157D03*
X1355053Y1060565D03*
Y1054157D03*
X1351353D03*
X1349503Y1057361D03*
X1349504Y1050952D03*
X1351353Y1060565D03*
X1353204Y1057361D03*
X1358753Y1060565D03*
X1356904Y1057361D03*
X1353204Y1050952D03*
X1356904D03*
X1349504Y1063770D03*
X1360604D03*
X1353204D03*
X1356904D03*
X1362453Y1054157D03*
Y1066974D03*
X1360604Y1076587D03*
X1360603Y1070178D03*
X1358754Y1073383D03*
X1355053D03*
Y1066974D03*
X1351353Y1073383D03*
X1349503Y1076587D03*
X1349504Y1070178D03*
X1362453Y1079791D03*
X1355053D03*
X1356904Y1070178D03*
X1358753Y1066974D03*
X1353204Y1070178D03*
X1351353Y1066974D03*
Y1079791D03*
X1353204Y1076587D03*
X1358753Y1079791D03*
X1356904Y1076587D03*
X1362453Y1073383D03*
Y1086200D03*
X1360603Y1089404D03*
X1358753Y1092608D03*
X1355053D03*
Y1086200D03*
X1351353Y1092608D03*
X1349504Y1089404D03*
X1360604Y1095813D03*
X1349504D03*
X1353204Y1089404D03*
X1351353Y1086200D03*
X1356904Y1089404D03*
X1358753Y1086200D03*
X1349504Y1082995D03*
X1362453Y1092608D03*
X1360604Y1082995D03*
X1353204D03*
X1356904D03*
X1351354Y1099017D03*
X1356904Y1095813D03*
X1362454Y1099017D03*
X1360604Y1102221D03*
X1356904Y1108630D03*
X1355053Y1099017D03*
X1353204Y1102221D03*
X1349503Y1108630D03*
Y1102221D03*
X1358753Y1099017D03*
X1362453Y1111834D03*
Y1105426D03*
X1358753D03*
X1351353Y1111834D03*
Y1105426D03*
X1358753Y1111834D03*
X1360604Y1108630D03*
X1355053Y1111834D03*
X1356904Y1102221D03*
X1353204Y1108630D03*
X1355054Y1105426D03*
X1362453Y1118243D03*
X1360603Y1115039D03*
X1358753Y1118243D03*
X1355053D03*
X1353203Y1115039D03*
X1351353Y1118243D03*
X1349503Y1115039D03*
X1356903Y1127856D03*
X1349503D03*
X1351353Y1124651D03*
X1355053D03*
X1358753D03*
X1362453D03*
X1349504Y1121447D03*
X1353204Y1127856D03*
X1356904Y1121447D03*
X1360604Y1127856D03*
Y1121447D03*
X1353204D03*
X1356904Y1115039D03*
X1362453Y1131060D03*
X1358753D03*
X1356903Y1140973D03*
X1355053Y1131060D03*
X1351353D03*
X1349503Y1140973D03*
X1349504Y1134264D03*
X1353203Y1140973D03*
X1356904Y1134264D03*
X1360603Y1140973D03*
X1351354Y1137469D03*
X1355054D03*
X1358754D03*
X1362454D03*
X1353204Y1134264D03*
X1360604D03*
X1357730Y1575686D03*
X1352774D03*
X1357730Y1580678D03*
X1352774D03*
X1353552Y1578182D03*
X1356952D03*
X1350970Y1599884D03*
X1363030D03*
X1358074D03*
X1357730Y1587598D03*
X1352774D03*
X1357730Y1592590D03*
X1352774D03*
X1353552Y1590094D03*
X1356952D03*
X1350970Y1611796D03*
Y1604876D03*
Y1616788D03*
X1363030D03*
Y1611796D03*
Y1604876D03*
X1358074Y1616788D03*
Y1611796D03*
Y1604876D03*
X1358852Y1614292D03*
X1362252D03*
X1350192D03*
X1358852Y1602380D03*
X1362252D03*
X1350192D03*
X1363189Y1679320D03*
X1355315Y1675383D03*
Y1679920D03*
X1363189Y1688391D03*
Y1693493D03*
Y1698030D03*
Y1683857D03*
X1355315Y1684454D03*
Y1689556D03*
Y1694093D03*
Y1698627D03*
X1363189Y1707666D03*
Y1712203D03*
Y1702564D03*
X1355315Y1703729D03*
Y1708266D03*
Y1712800D03*
X1363189Y1730911D03*
Y1726377D03*
Y1721840D03*
Y1716737D03*
X1355315Y1726974D03*
Y1722440D03*
Y1717903D03*
X1373121Y841467D03*
X1365721D03*
X1378671Y851380D03*
X1374971D03*
X1371271D03*
X1367571D03*
X1376820Y848176D03*
X1369420D03*
X1367569Y844971D03*
X1369421Y841467D03*
X1373120Y848176D03*
X1376821Y841467D03*
X1365720Y848176D03*
X1371269Y844971D03*
X1374969D03*
X1378669D03*
X1378671Y864197D03*
X1374971D03*
X1373121Y854584D03*
X1371271Y864197D03*
X1367571D03*
X1365721Y854584D03*
X1373121Y867401D03*
X1365721D03*
X1376820D03*
X1369420D03*
X1376820Y860993D03*
X1369420D03*
X1365720D03*
X1367571Y857789D03*
X1373120Y860993D03*
X1374971Y857789D03*
X1369420Y854584D03*
X1371271Y857789D03*
X1376820Y854584D03*
X1378671Y857789D03*
Y877014D03*
X1374971D03*
X1373121Y880219D03*
X1371271Y877014D03*
X1367571D03*
X1365721Y880219D03*
X1367571Y870606D03*
X1371271D03*
X1378671D03*
X1365720Y873810D03*
X1373120D03*
X1374971Y870606D03*
X1369420Y880219D03*
X1371271Y883423D03*
X1376820Y880219D03*
X1378671Y883423D03*
X1367571D03*
X1374971D03*
X1369420Y873810D03*
X1376820D03*
X1378671Y889832D03*
X1374971D03*
X1371271Y896240D03*
Y889832D03*
X1367570Y896240D03*
X1367571Y889832D03*
X1365721Y893036D03*
X1373120Y899445D03*
X1378671Y896240D03*
X1376820Y899445D03*
X1365720D03*
X1369420D03*
X1369421Y893036D03*
X1373121D03*
X1373120Y886627D03*
X1365720D03*
X1374971Y896240D03*
X1376820Y893036D03*
X1369420Y886627D03*
X1376820D03*
X1380520Y899445D03*
X1374971Y909057D03*
X1374970Y902649D03*
X1373121Y912262D03*
X1367571Y909057D03*
Y902649D03*
X1371271Y915466D03*
X1367571D03*
X1376820Y905853D03*
X1378671Y915466D03*
Y909057D03*
X1365720Y912262D03*
X1369420D03*
X1371271Y909057D03*
Y902649D03*
X1369420Y905853D03*
X1365720D03*
X1373120D03*
X1376820Y912262D03*
X1378671Y902649D03*
X1376820Y931488D03*
X1378671Y928283D03*
X1376820Y925079D03*
X1374971Y928283D03*
X1374970Y921875D03*
X1373120Y918670D03*
X1367571Y928283D03*
Y921875D03*
X1373120Y931488D03*
X1369420D03*
X1371271Y928283D03*
X1365720Y918670D03*
X1371271Y921875D03*
X1369420Y918670D03*
X1365720Y931488D03*
X1369420Y925079D03*
X1365720D03*
X1373120D03*
X1378671Y921875D03*
X1374971Y934691D03*
X1378671D03*
X1376820Y937896D03*
X1374970Y941100D03*
X1373120Y937896D03*
X1371271Y934691D03*
X1367571Y941100D03*
Y934691D03*
X1374971Y947509D03*
X1367571D03*
X1371271D03*
X1365720Y937896D03*
X1371271Y941100D03*
X1369420Y937896D03*
Y944304D03*
X1365720D03*
X1373120D03*
X1378671Y947509D03*
X1376820Y957122D03*
X1374970Y960326D03*
X1373120Y957122D03*
X1373121Y950713D03*
X1371271Y953917D03*
X1367571Y960326D03*
Y953917D03*
X1376820Y963530D03*
X1374971Y966735D03*
X1367571D03*
X1365720Y957122D03*
X1371271Y960326D03*
X1369420Y957122D03*
X1371271Y966735D03*
X1365720Y950713D03*
X1369420D03*
X1373120Y963530D03*
X1369420D03*
X1365720D03*
X1378671Y966735D03*
Y960326D03*
Y953917D03*
X1374971D03*
X1376822Y950713D03*
X1376820Y982756D03*
Y969939D03*
X1374970Y979552D03*
X1373120Y976347D03*
X1373121Y969939D03*
X1371271Y973143D03*
X1367571Y979552D03*
Y973143D03*
X1374971D03*
X1376820Y976347D03*
X1378671Y979552D03*
Y973143D03*
X1369420Y982756D03*
X1365720D03*
X1373120D03*
X1369420Y976347D03*
X1371271Y979552D03*
X1365721Y976347D03*
X1365720Y969939D03*
X1369420D03*
X1364303Y1006093D03*
X1377253Y1002888D03*
X1373554Y1009297D03*
X1373553Y1002888D03*
X1371704Y1006093D03*
X1368004D03*
Y999684D03*
X1375404Y1012501D03*
X1368003D03*
X1375404Y1006093D03*
X1379104D03*
X1366153Y1002888D03*
X1364304Y999684D03*
X1369853Y1002888D03*
X1371704Y999684D03*
X1375404D03*
X1379104D03*
X1364304Y1012501D03*
X1371704D03*
X1366153Y1009297D03*
X1369853D03*
X1377253D03*
X1379104Y1012501D03*
Y1031727D03*
X1364303Y1025318D03*
X1375403Y1018910D03*
X1373553Y1028523D03*
Y1022114D03*
X1371704Y1025318D03*
X1369853Y1015705D03*
X1368004Y1025318D03*
Y1018910D03*
X1366154Y1015705D03*
X1375404Y1031727D03*
X1368004D03*
X1373553Y1015705D03*
X1364304Y1031727D03*
X1366153Y1028523D03*
X1371704Y1031727D03*
X1369853Y1028523D03*
X1366153Y1022114D03*
X1364304Y1018910D03*
X1369853Y1022114D03*
X1371704Y1018910D03*
X1377253Y1028523D03*
X1375404Y1025318D03*
X1377253Y1022114D03*
X1379102Y1018910D03*
X1379104Y1025318D03*
X1377253Y1015705D03*
X1364303Y1044544D03*
X1375403Y1038136D03*
X1373553Y1041340D03*
X1371704Y1044544D03*
X1368004D03*
Y1038136D03*
X1373553Y1047749D03*
X1366153Y1041340D03*
X1364304Y1038136D03*
X1369853Y1041340D03*
X1371704Y1038136D03*
X1366153Y1047749D03*
X1369853D03*
Y1034931D03*
X1366153D03*
X1373553D03*
X1375404Y1044544D03*
X1377253Y1041340D03*
X1379104Y1044544D03*
Y1038136D03*
X1377253Y1047749D03*
X1375403Y1057361D03*
X1375404Y1050952D03*
X1373553Y1060565D03*
X1368004Y1057361D03*
Y1050952D03*
X1364303Y1063770D03*
X1371704D03*
X1368004D03*
X1366153Y1060565D03*
X1364304Y1057361D03*
X1369853Y1060565D03*
X1371704Y1057361D03*
X1364304Y1050952D03*
X1371704D03*
X1369853Y1054157D03*
X1366153D03*
X1373553D03*
X1379104Y1057361D03*
Y1063770D03*
X1377255Y1060565D03*
X1375404Y1063770D03*
X1377253Y1054157D03*
X1379104Y1050952D03*
X1380953Y1054157D03*
X1379104Y1076587D03*
Y1070178D03*
X1377253Y1073383D03*
X1375403Y1076587D03*
X1375404Y1070178D03*
X1373554Y1066974D03*
X1368004Y1076587D03*
Y1070178D03*
X1377253Y1079791D03*
X1373553D03*
X1366153D03*
X1364304Y1076587D03*
X1369853Y1079791D03*
X1371704Y1076587D03*
X1364304Y1070178D03*
X1366153Y1066974D03*
X1371704Y1070178D03*
X1369853Y1066974D03*
Y1073383D03*
X1366153D03*
X1373553D03*
X1377254Y1066974D03*
X1364303Y1082995D03*
X1377254Y1092608D03*
X1377253Y1086200D03*
X1375404Y1089404D03*
X1373554Y1086200D03*
X1371704Y1082995D03*
X1368004Y1089404D03*
Y1082995D03*
X1379104Y1095813D03*
X1375403D03*
X1368004D03*
X1371704D03*
X1364304Y1089404D03*
X1366153Y1086200D03*
X1371704Y1089404D03*
X1369853Y1086200D03*
X1364304Y1095813D03*
X1369853Y1092608D03*
X1366153D03*
X1373553D03*
X1375404Y1082995D03*
X1379104D03*
X1379103Y1089404D03*
X1364304Y1108630D03*
Y1102221D03*
X1377253Y1105426D03*
X1375404Y1102221D03*
X1373554Y1099017D03*
X1371704Y1102221D03*
X1366153Y1105426D03*
X1373553Y1111834D03*
X1366153D03*
X1369853Y1099017D03*
X1366153D03*
X1368004Y1102221D03*
X1369853Y1105426D03*
Y1111834D03*
X1368004Y1108630D03*
X1377253Y1099017D03*
X1379104Y1108630D03*
X1373553Y1105426D03*
X1371704Y1108630D03*
X1379104Y1102221D03*
X1377253Y1111834D03*
X1375404Y1108630D03*
X1364303Y1115039D03*
X1377253Y1118243D03*
X1373553D03*
X1371703Y1115039D03*
X1369853Y1118243D03*
X1366153D03*
X1364303Y1127856D03*
X1379103D03*
X1371703D03*
X1366153Y1124651D03*
X1371704Y1121447D03*
X1373553Y1124651D03*
X1377253D03*
X1368004Y1127856D03*
X1369853Y1124651D03*
X1375404Y1127856D03*
X1379104Y1121447D03*
X1364304D03*
X1368004D03*
X1375404Y1115039D03*
X1368004D03*
X1379104D03*
X1375404Y1121447D03*
X1364303Y1140973D03*
X1379103D03*
X1377253Y1131060D03*
X1373553D03*
X1371703Y1140973D03*
X1369853Y1131060D03*
X1366153D03*
X1368003Y1140973D03*
X1371704Y1134264D03*
X1375403Y1140973D03*
X1379104Y1134264D03*
X1364304D03*
X1366154Y1137469D03*
X1369854D03*
X1373554D03*
X1377254D03*
X1368004Y1134264D03*
X1375404D03*
X1374847Y1153069D03*
X1369790Y1580678D03*
X1364834D03*
X1369790Y1575592D03*
X1364834D03*
X1376894Y1575686D03*
Y1580678D03*
X1365612Y1578182D03*
X1377672D03*
X1369012D03*
X1375090Y1599790D03*
X1370134D03*
X1369790Y1592590D03*
X1364834D03*
X1369790Y1587598D03*
X1364834D03*
X1376894D03*
Y1592590D03*
X1365612Y1590094D03*
X1377672D03*
X1369012D03*
X1375090Y1611796D03*
Y1604876D03*
Y1616788D03*
X1370134Y1611796D03*
Y1604876D03*
Y1616788D03*
X1370912Y1614292D03*
X1374312D03*
X1370912Y1602380D03*
X1374312D03*
X1380521Y841467D03*
X1395321D03*
X1387921D03*
X1393471Y851380D03*
X1389771D03*
X1386071D03*
X1382371D03*
X1391620Y848176D03*
X1384220D03*
X1380520D03*
X1386069Y844971D03*
X1389769D03*
X1393469D03*
X1382369D03*
X1384221Y841467D03*
X1387920Y848176D03*
X1391621Y841467D03*
X1395320Y848176D03*
X1380521Y854584D03*
X1395321D03*
X1393471Y864197D03*
X1389771D03*
X1387921Y854584D03*
X1386071Y864197D03*
X1382371D03*
X1380521Y867401D03*
X1395321D03*
X1387921D03*
X1384220D03*
X1391620D03*
X1384220Y860993D03*
X1391620D03*
X1380520D03*
X1382371Y857789D03*
X1387920Y860993D03*
X1389771Y857789D03*
X1395320Y860993D03*
X1384220Y854584D03*
X1386071Y857789D03*
X1391620Y854584D03*
X1393471Y857789D03*
X1380521Y880219D03*
X1395321D03*
X1393471Y877014D03*
X1389771D03*
X1387921Y880219D03*
X1386071Y877014D03*
Y870606D03*
X1382371Y877014D03*
X1380520Y873810D03*
X1382371Y870606D03*
X1384220Y880219D03*
X1386071Y883423D03*
X1382371D03*
X1395320Y873810D03*
X1393471Y870606D03*
X1387920Y873810D03*
X1389771Y870606D03*
X1393471Y883423D03*
X1391620Y880219D03*
X1389771Y883423D03*
X1391620Y873810D03*
X1384220D03*
X1386071Y896240D03*
X1389771D03*
X1393471D03*
X1387920Y899445D03*
X1391620Y893036D03*
X1395320Y899445D03*
X1395321Y893036D03*
X1393471Y889832D03*
X1389771D03*
X1387921Y893036D03*
X1386071Y889832D03*
X1384221Y893036D03*
X1382371Y889832D03*
X1380520Y886627D03*
X1387920D03*
X1395320D03*
X1380520Y893036D03*
X1382371Y896240D03*
X1384220Y886627D03*
X1391620D03*
Y899445D03*
X1384221Y899446D03*
X1386071Y902649D03*
X1380520Y912262D03*
Y905853D03*
X1395320Y912262D03*
X1395321Y905853D03*
X1393471Y902649D03*
X1389771D03*
X1386071Y909057D03*
Y915466D03*
X1393471Y909057D03*
X1382371D03*
X1389771D03*
Y915466D03*
X1399020Y905853D03*
X1382371Y915466D03*
X1384220Y918670D03*
X1387920Y905853D03*
X1384220D03*
Y912262D03*
X1382371Y902649D03*
X1391620Y905853D03*
X1387920Y912262D03*
X1391620D03*
X1393471Y915466D03*
X1391621Y918670D03*
X1380520D03*
X1395187Y926265D03*
X1395320Y918670D03*
X1386071Y921875D03*
X1381189Y930811D03*
X1382371Y921875D03*
X1382809Y927986D03*
X1385070Y928468D03*
X1393471Y921875D03*
X1391550Y925219D03*
X1387921Y918670D03*
X1381189Y938045D03*
X1381287Y946239D03*
Y948539D03*
X1381189Y935745D03*
X1390234Y942097D03*
X1386030Y942163D03*
X1383730D03*
X1381430D03*
X1392534Y942097D03*
X1394834D03*
X1381264Y965896D03*
Y963596D03*
X1393826Y956619D03*
X1387826D03*
X1391326D03*
X1385526D03*
X1390506Y971139D03*
X1392896D03*
X1381003Y981269D03*
Y978969D03*
X1380926Y971099D03*
X1383226D03*
X1387826D03*
X1385526D03*
X1396346D03*
X1381003Y986421D03*
X1381243Y992971D03*
Y995271D03*
X1381003Y988721D03*
X1393716Y985579D03*
X1391326D03*
X1396286Y985549D03*
X1388506Y985609D03*
X1386206D03*
X1381369Y1007156D03*
X1381373Y1004848D03*
X1391326Y1014539D03*
X1393716D03*
Y1000059D03*
X1391326D03*
X1385526Y1014539D03*
X1387826D03*
X1383226D03*
X1386226Y1000079D03*
X1396356Y1000039D03*
X1388526Y1000079D03*
X1396546Y1014469D03*
X1381128Y1022427D03*
X1381140Y1026821D03*
X1388102Y1028854D03*
X1390602D03*
X1393102D03*
X1395602D03*
X1384466Y1034270D03*
Y1031970D03*
X1393904Y1044544D03*
X1384653Y1041340D03*
X1380953Y1047749D03*
X1388353D03*
X1380953Y1041340D03*
X1388353D03*
X1392053D03*
X1395753D03*
Y1047749D03*
X1392053D03*
X1382804Y1044544D03*
X1386504D03*
X1384653Y1047749D03*
X1390204Y1044544D03*
X1382804Y1050952D03*
X1380953Y1060565D03*
X1393904Y1050952D03*
X1392053Y1060565D03*
Y1054157D03*
X1388353Y1060565D03*
X1386504Y1050952D03*
X1384653Y1054157D03*
X1382804Y1057361D03*
X1386504D03*
X1390204Y1050952D03*
X1393904Y1057361D03*
X1395753Y1054157D03*
X1382804Y1063770D03*
X1384653Y1060565D03*
X1386504Y1063770D03*
X1388353Y1054157D03*
X1390204Y1057361D03*
X1393904Y1063770D03*
X1390204D03*
X1395753Y1060565D03*
Y1079791D03*
X1384653Y1073383D03*
X1382804Y1070178D03*
X1380953Y1073383D03*
Y1066974D03*
X1395753Y1073383D03*
X1392053Y1066974D03*
X1386504Y1076587D03*
Y1070178D03*
X1382803Y1076587D03*
X1380953Y1079791D03*
X1388353D03*
X1393904Y1076587D03*
X1392053Y1079791D03*
X1384653Y1066974D03*
X1388353Y1073383D03*
X1392053D03*
X1390204Y1070178D03*
X1393904D03*
X1388353Y1066974D03*
X1395753D03*
X1384653Y1079791D03*
X1393903Y1089404D03*
Y1082995D03*
X1392053Y1092608D03*
X1392054Y1086200D03*
X1388353Y1092608D03*
X1384653Y1086200D03*
X1386504Y1095813D03*
X1382804D03*
X1395754Y1099017D03*
X1380953Y1092608D03*
X1393904Y1095813D03*
X1390203D03*
X1388353Y1086200D03*
X1386504Y1082995D03*
X1390204Y1089404D03*
X1382804D03*
X1390204Y1082995D03*
X1382804D03*
X1395753Y1086200D03*
Y1092608D03*
X1380953Y1086200D03*
X1386504Y1089404D03*
X1384653Y1092608D03*
X1380954Y1105426D03*
X1393904Y1102221D03*
X1392054Y1099017D03*
X1390204Y1108630D03*
X1388353Y1099017D03*
X1386504Y1102221D03*
X1382803Y1108630D03*
Y1102221D03*
X1380954Y1111834D03*
X1380953Y1099017D03*
X1395753Y1105426D03*
X1393904Y1108630D03*
X1390204Y1102221D03*
X1392053Y1111834D03*
X1388353D03*
X1384653Y1105426D03*
Y1099017D03*
X1392053Y1105426D03*
X1395753Y1111834D03*
X1388353Y1105426D03*
X1384653Y1111834D03*
X1386504Y1108630D03*
X1380953Y1118243D03*
X1393903Y1115039D03*
X1392053Y1118243D03*
X1390203Y1121447D03*
X1388353Y1124651D03*
Y1118243D03*
X1386503Y1115039D03*
X1384653Y1118243D03*
X1382803Y1115039D03*
X1386503Y1127856D03*
X1380953Y1124651D03*
X1384653D03*
X1382804Y1127856D03*
X1386504Y1121447D03*
X1392054Y1124651D03*
X1393903Y1121447D03*
Y1127856D03*
X1395754Y1118243D03*
Y1124651D03*
X1390204Y1115039D03*
X1382803Y1121447D03*
X1390204Y1127856D03*
X1380953Y1131060D03*
X1390204Y1134264D03*
X1388354Y1131060D03*
X1386503Y1140973D03*
X1384653Y1131060D03*
X1382803Y1140973D03*
X1386504Y1134264D03*
X1380954Y1137469D03*
X1384654D03*
X1382804Y1134264D03*
X1390203Y1140973D03*
X1392054Y1131060D03*
Y1137469D03*
X1393903Y1134264D03*
Y1140973D03*
X1395754Y1131060D03*
Y1137469D03*
X1388354D03*
X1381850Y1575686D03*
Y1580678D03*
X1381072Y1578182D03*
X1387150Y1599884D03*
X1382194D03*
X1381850Y1587598D03*
Y1592590D03*
X1381072Y1590094D03*
X1387150Y1616788D03*
X1382194D03*
X1387150Y1611796D03*
Y1604876D03*
X1382194Y1611796D03*
Y1604876D03*
X1382972Y1614292D03*
X1386372D03*
X1382972Y1602380D03*
X1386372D03*
X1408269Y844971D03*
X1402721Y841467D03*
X1397171Y851380D03*
X1408271D03*
X1404571D03*
X1400871D03*
X1411971D03*
X1399020Y848176D03*
X1397169Y844971D03*
X1399021Y841467D03*
X1402720Y848176D03*
X1406420D03*
X1411969Y844971D03*
X1400869D03*
X1404569D03*
X1410120Y848176D03*
X1397171Y864197D03*
X1408271D03*
X1404571D03*
X1402721Y854584D03*
X1400871Y864197D03*
X1410121Y854584D03*
X1411971Y864197D03*
X1410121Y867401D03*
X1402721D03*
X1406420D03*
X1399020D03*
X1406420Y860993D03*
X1399020D03*
X1397171Y857789D03*
X1402720Y860993D03*
X1404571Y857789D03*
X1410121Y860993D03*
X1411971Y857789D03*
X1399020Y854584D03*
X1400871Y857789D03*
X1406420Y854584D03*
X1408271Y857789D03*
X1397171Y877014D03*
X1410121Y880219D03*
X1408271Y877014D03*
X1404571D03*
X1402721Y880219D03*
X1400871Y877014D03*
X1411971D03*
X1408271Y870606D03*
X1402720Y873810D03*
X1400871Y870606D03*
X1410121Y873810D03*
X1404571Y870606D03*
X1397171D03*
X1411971D03*
X1408271Y883423D03*
X1406420Y880219D03*
X1400871Y883423D03*
X1399020Y880219D03*
X1404571Y883423D03*
X1397171D03*
X1411971D03*
X1399020Y873810D03*
X1406420D03*
X1397171Y896240D03*
X1402720Y899445D03*
X1404571Y896240D03*
X1410120Y899445D03*
X1399020Y893036D03*
X1400871Y896240D03*
X1406420Y893036D03*
X1408271Y896240D03*
X1411971D03*
X1397171Y889832D03*
X1410121Y893036D03*
X1408271Y889832D03*
X1404571D03*
X1402721Y893036D03*
X1400871Y889832D03*
X1411971D03*
X1410120Y886627D03*
X1402720D03*
X1406420D03*
X1399020D03*
X1406420Y899445D03*
X1399020D03*
Y912262D03*
X1400871Y915466D03*
X1402720Y912262D03*
X1400871Y902649D03*
X1397171D03*
X1408271D03*
X1404571Y909057D03*
Y902649D03*
X1411971D03*
X1404571Y915466D03*
X1406420Y912262D03*
X1408271Y915466D03*
X1397171Y909057D03*
X1411971D03*
Y915466D03*
X1408270Y909057D03*
X1410120Y905853D03*
X1400870Y909057D03*
X1406420Y905853D03*
X1402720D03*
X1397171Y915466D03*
X1410121Y912262D03*
X1406420Y918670D03*
X1410121Y925079D03*
Y931488D03*
X1404571Y921875D03*
X1408271D03*
X1410121Y918670D03*
X1411971Y921875D03*
X1401528Y927155D03*
X1399028D03*
X1401817Y929464D03*
X1399317D03*
X1400871Y921875D03*
X1399020Y918670D03*
X1397171Y921875D03*
X1402720Y918670D03*
X1411971Y934691D03*
X1406420Y925079D03*
X1408271Y928283D03*
X1406420Y931488D03*
X1411971Y928283D03*
X1403016Y949498D03*
Y947198D03*
X1406420Y937896D03*
X1404016Y936469D03*
X1410120Y937896D03*
X1410121Y944304D03*
X1406421D03*
X1408271Y941100D03*
X1411971D03*
X1404016Y944229D03*
Y941929D03*
X1408270Y947509D03*
X1411971D03*
X1408271Y934691D03*
X1403046Y963634D03*
Y965934D03*
X1410121Y957122D03*
Y950713D03*
Y963530D03*
X1406421Y950713D03*
Y957122D03*
X1408270Y953917D03*
Y960326D03*
X1411971Y953917D03*
Y960326D03*
X1404016Y954072D03*
Y956372D03*
X1401326Y956619D03*
X1398826D03*
X1406421Y963530D03*
X1408270Y966735D03*
X1411971D03*
X1403046Y978035D03*
Y980335D03*
X1410121Y976347D03*
Y969939D03*
Y982756D03*
X1406421Y969939D03*
X1406409Y976347D03*
X1408270Y973143D03*
X1411971D03*
X1404016Y971266D03*
Y968966D03*
X1398826Y971099D03*
X1406421Y982756D03*
X1408270Y979552D03*
X1411971D03*
X1404016Y983110D03*
X1403046Y992421D03*
Y994721D03*
X1404016Y985410D03*
X1398826Y985579D03*
X1404016Y997520D03*
X1403046Y1009174D03*
Y1006874D03*
X1410553Y1009297D03*
Y1002888D03*
X1412404Y999684D03*
Y1006093D03*
Y1012501D03*
X1406853Y1002888D03*
Y1009297D03*
X1408703Y999684D03*
Y1006093D03*
Y1012501D03*
X1404016Y1012151D03*
Y999820D03*
X1398826Y1000059D03*
X1404016Y1014451D03*
X1399156Y1014469D03*
X1403046Y1021962D03*
Y1019662D03*
X1410553Y1028523D03*
Y1022114D03*
Y1015705D03*
X1398102Y1028854D03*
X1406853Y1028523D03*
X1412404Y1018910D03*
X1406853Y1015705D03*
Y1022114D03*
X1408703Y1018910D03*
X1412404Y1025318D03*
X1408703D03*
X1404016Y1026703D03*
X1412404Y1031727D03*
X1408703D03*
X1404016Y1029003D03*
Y1031303D03*
X1405004Y1044544D03*
X1410553Y1034931D03*
X1406854Y1047749D03*
X1399453D03*
X1403153D03*
X1403154Y1041340D03*
X1399454D03*
X1401304Y1044544D03*
X1412403Y1038136D03*
Y1044544D03*
X1406853Y1034931D03*
Y1041340D03*
X1408703Y1038136D03*
Y1044544D03*
X1410554Y1041340D03*
X1404016Y1033603D03*
X1399426Y1036883D03*
Y1034583D03*
Y1032283D03*
X1410554Y1047749D03*
X1397604Y1044544D03*
X1403153Y1054157D03*
X1406853D03*
X1408703Y1050952D03*
X1401304Y1057361D03*
X1410553Y1060565D03*
Y1054157D03*
X1397604Y1063770D03*
X1405003Y1057361D03*
X1408703D03*
Y1063770D03*
X1412404Y1050952D03*
Y1057361D03*
Y1063770D03*
X1397604Y1057361D03*
X1401304Y1050952D03*
X1399453Y1054157D03*
X1405004Y1050952D03*
X1397604D03*
X1401304Y1063770D03*
X1399453Y1060565D03*
X1403153D03*
X1405003Y1063770D03*
X1406853Y1060565D03*
X1397604Y1076587D03*
X1408703D03*
X1406853Y1073383D03*
X1403153D03*
Y1066974D03*
X1401304Y1076587D03*
X1399453Y1066974D03*
X1410553Y1073383D03*
Y1066974D03*
X1403154Y1079791D03*
X1410553D03*
X1408702Y1070178D03*
X1399453Y1073383D03*
Y1079791D03*
X1412404Y1070178D03*
Y1076587D03*
X1397604Y1070178D03*
X1401304D03*
X1405004D03*
X1406853Y1066974D03*
X1405003Y1076587D03*
X1406853Y1079791D03*
X1408703Y1089404D03*
Y1082995D03*
X1405003D03*
X1401304Y1089404D03*
X1397604Y1082995D03*
X1410553Y1092608D03*
Y1086200D03*
X1408703Y1095813D03*
X1405003D03*
X1397604D03*
X1412404Y1082995D03*
Y1089404D03*
X1412403Y1095813D03*
X1401304Y1082995D03*
X1405003Y1089404D03*
X1399453Y1086200D03*
X1406853Y1092608D03*
X1399453D03*
X1397604Y1089404D03*
X1403154Y1086200D03*
X1406852D03*
X1403153Y1092608D03*
X1401304Y1095813D03*
X1403153Y1099017D03*
X1401303Y1102221D03*
X1399453Y1105426D03*
X1397604Y1108630D03*
X1410553Y1105426D03*
X1399453Y1111834D03*
X1410553D03*
X1397604Y1102221D03*
X1399453Y1099017D03*
X1412404Y1102221D03*
Y1108630D03*
X1401304D03*
X1403154Y1105426D03*
Y1111834D03*
X1405003Y1102221D03*
Y1108630D03*
X1406853Y1099017D03*
Y1105426D03*
Y1111834D03*
X1408703Y1102221D03*
Y1108630D03*
X1410554Y1099017D03*
X1399453Y1124651D03*
Y1118243D03*
X1397604Y1115039D03*
X1410553Y1124651D03*
Y1118243D03*
X1412404Y1115039D03*
Y1121447D03*
Y1127856D03*
X1397603Y1121447D03*
Y1127856D03*
X1401304Y1115039D03*
Y1121447D03*
Y1127856D03*
X1403154Y1118243D03*
Y1124651D03*
X1405003Y1115039D03*
Y1121447D03*
Y1127856D03*
X1406853Y1118243D03*
Y1124651D03*
X1408703Y1115039D03*
Y1121447D03*
Y1127856D03*
X1399454Y1137469D03*
X1399453Y1131060D03*
X1410554Y1137769D03*
X1410553Y1131060D03*
X1412403Y1134264D03*
X1397603D03*
Y1140973D03*
X1401304Y1134264D03*
X1401303Y1140973D03*
X1403154Y1131060D03*
Y1137569D03*
X1405003Y1134264D03*
Y1140973D03*
X1406853Y1131060D03*
Y1137769D03*
X1408703Y1134264D03*
X1428620Y848176D03*
X1415669Y844971D03*
X1421220Y848176D03*
X1417520D03*
X1426771Y851380D03*
X1423070D03*
X1419370D03*
X1415671D03*
X1413820Y848176D03*
X1413822Y860993D03*
X1426771Y864197D03*
X1424921Y854584D03*
X1423071Y864197D03*
X1419371D03*
X1417521Y854584D03*
X1415671Y864197D03*
Y857789D03*
X1424921Y867401D03*
X1417521D03*
X1428620D03*
X1421220D03*
X1413820D03*
X1421220Y860993D03*
X1428621D03*
X1424921D03*
X1421220Y854584D03*
X1417520Y860993D03*
X1428620Y854584D03*
X1426771Y857789D03*
X1423071D03*
X1419371D03*
X1413821Y854584D03*
X1426771Y877014D03*
X1424921Y880219D03*
X1423071Y877014D03*
X1419371D03*
X1417521Y880219D03*
X1415671Y877014D03*
X1424921Y873810D03*
X1423071Y870606D03*
X1417520Y873810D03*
X1415671Y870606D03*
X1426771D03*
X1419371D03*
X1428621Y880219D03*
X1423071Y883423D03*
X1421220Y880219D03*
X1415671Y883423D03*
X1413820Y880219D03*
X1426771Y883423D03*
X1419371D03*
X1413821Y873810D03*
X1428621D03*
X1421220D03*
X1413820Y893036D03*
X1421220Y899445D03*
X1419371Y896240D03*
X1424920Y899445D03*
X1426772Y896240D03*
X1417520Y899445D03*
X1421220Y893036D03*
X1423071Y896240D03*
X1428621Y893036D03*
X1413820Y886627D03*
X1426771Y889832D03*
X1424921Y893036D03*
X1423071Y889832D03*
X1419371D03*
X1417521Y893036D03*
X1415671Y896240D03*
Y889832D03*
X1413821Y899445D03*
X1424920Y886627D03*
X1417520D03*
X1428620Y899445D03*
Y886627D03*
X1421220D03*
X1413820Y912262D03*
X1413821Y905853D03*
X1426771Y902649D03*
X1423071Y909057D03*
Y902649D03*
X1419371D03*
X1415670D03*
X1423071Y915466D03*
X1419371Y909057D03*
X1415671Y915466D03*
X1421221Y905853D03*
X1417521D03*
X1430471Y909057D03*
X1426772D03*
X1428621Y905853D03*
X1424921D03*
X1424922Y912262D03*
X1417522D03*
X1415671Y909057D03*
X1421222Y912262D03*
X1419371Y915466D03*
X1426771D03*
X1428620Y912262D03*
X1424921Y918670D03*
X1430471Y915466D03*
X1415671Y921875D03*
X1423071Y928283D03*
X1417520Y925079D03*
Y931488D03*
X1413820Y918670D03*
X1423071Y921875D03*
X1417520Y918670D03*
X1426771Y921875D03*
X1421220Y918670D03*
X1419371Y921875D03*
X1428620Y918670D03*
X1424921Y931488D03*
X1419371Y928283D03*
X1413820Y931488D03*
X1424921Y925079D03*
X1419371Y934691D03*
X1421220Y931488D03*
Y925079D03*
X1415671Y928283D03*
X1413820Y925079D03*
X1426771Y928283D03*
X1424920Y937896D03*
X1421220D03*
X1417520D03*
X1413820D03*
X1423070Y941100D03*
X1423071Y947509D03*
X1413821Y944304D03*
X1415671Y941100D03*
X1417521Y944304D03*
X1419371Y941100D03*
X1421220Y944304D03*
X1424921D03*
X1426771Y941100D03*
X1415670Y947509D03*
X1419370D03*
X1426771D03*
X1423071Y934691D03*
X1415671D03*
X1423071Y960326D03*
Y953917D03*
Y966735D03*
X1413821Y950713D03*
Y957122D03*
X1415670Y953917D03*
Y960326D03*
X1417521Y950713D03*
Y957122D03*
X1419370Y953917D03*
Y960326D03*
X1421220Y950713D03*
Y957122D03*
X1424921Y950713D03*
Y957122D03*
X1426771Y953917D03*
Y960326D03*
X1413821Y963530D03*
X1415670Y966735D03*
X1417521Y963530D03*
X1419370Y966735D03*
X1421220Y963530D03*
X1424921D03*
X1426771Y966735D03*
X1423071Y979552D03*
Y973143D03*
X1413821Y969939D03*
Y976347D03*
X1415670Y973143D03*
X1417521Y969939D03*
Y976347D03*
X1419370Y973143D03*
X1421220Y969939D03*
Y976347D03*
X1424921Y969939D03*
Y976347D03*
X1426771Y973143D03*
X1413821Y982756D03*
X1415670Y979552D03*
X1417521Y982756D03*
X1419370Y979552D03*
X1421220Y982756D03*
X1424921D03*
X1426771Y979552D03*
X1423503Y1006093D03*
Y999684D03*
Y1012501D03*
X1414254Y1002888D03*
Y1009297D03*
X1416103Y999684D03*
Y1006093D03*
Y1012501D03*
X1417954Y1002888D03*
Y1009297D03*
X1419803Y999684D03*
Y1006093D03*
Y1012501D03*
X1421653Y1002888D03*
Y1009297D03*
X1425354Y1002888D03*
Y1009297D03*
X1427203Y999684D03*
Y1006093D03*
Y1012501D03*
X1423503Y1025318D03*
Y1018910D03*
Y1031727D03*
X1421653Y1028523D03*
X1414254D03*
X1417954D03*
X1425354D03*
X1414254Y1015705D03*
Y1022114D03*
X1416103Y1018910D03*
X1417954Y1015705D03*
Y1022114D03*
X1419803Y1018910D03*
X1421653Y1015705D03*
Y1022114D03*
X1425354Y1015705D03*
Y1022114D03*
X1427203Y1018910D03*
X1416103Y1025318D03*
X1419803D03*
X1427203D03*
X1416103Y1031727D03*
X1419803D03*
X1427203D03*
X1429053Y1041340D03*
X1427203Y1044544D03*
X1423503Y1038136D03*
X1425353Y1047749D03*
X1429053D03*
X1414254Y1034931D03*
Y1041340D03*
X1416103Y1038136D03*
Y1044544D03*
X1417954Y1034931D03*
Y1041340D03*
X1419803Y1038136D03*
Y1044544D03*
X1421653Y1034931D03*
Y1041340D03*
X1423503Y1044544D03*
X1425354Y1034931D03*
X1425353Y1041340D03*
X1427203Y1038136D03*
X1421653Y1047749D03*
X1414254D03*
X1417954D03*
X1429053Y1060565D03*
X1423503Y1057361D03*
Y1050952D03*
Y1063770D03*
X1425353Y1054157D03*
X1425355Y1060565D03*
X1414254Y1054157D03*
X1416103Y1050952D03*
X1417954Y1054157D03*
X1419803Y1050952D03*
X1421653Y1054157D03*
X1414254Y1060565D03*
X1416103Y1057361D03*
X1417954Y1060565D03*
X1419803Y1057361D03*
X1421653Y1060565D03*
X1416103Y1063770D03*
X1419803D03*
X1427203D03*
X1429053Y1054157D03*
X1427203Y1050952D03*
X1430903D03*
X1430904Y1057361D03*
X1427204D03*
X1425353Y1073383D03*
X1423503Y1076587D03*
Y1070178D03*
X1429053Y1079791D03*
X1425353D03*
X1429053Y1073383D03*
X1427203Y1076587D03*
X1414254Y1066974D03*
Y1073383D03*
X1416103Y1070178D03*
Y1076587D03*
X1417954Y1066974D03*
Y1073383D03*
X1419803Y1070178D03*
Y1076587D03*
X1421653Y1066974D03*
Y1073383D03*
X1414254Y1079791D03*
X1417954D03*
X1421653D03*
X1429053Y1066974D03*
X1425353D03*
X1427204Y1070178D03*
X1429053Y1092608D03*
X1427204Y1089404D03*
X1425354Y1086200D03*
X1423503Y1082995D03*
X1427203Y1095812D03*
X1429053Y1086200D03*
X1416103Y1082995D03*
X1419803D03*
X1414254Y1086200D03*
Y1092608D03*
X1416103Y1089404D03*
Y1095813D03*
X1417954Y1086200D03*
Y1092608D03*
X1419803Y1089404D03*
Y1095813D03*
X1421653Y1086200D03*
Y1092608D03*
X1423503Y1089404D03*
Y1095813D03*
X1425353Y1092608D03*
X1427202Y1082995D03*
X1429053Y1099017D03*
X1423503Y1108630D03*
Y1102221D03*
X1414254Y1099017D03*
Y1105426D03*
Y1111834D03*
X1416103Y1102221D03*
Y1108630D03*
X1417954Y1099017D03*
Y1105426D03*
Y1111834D03*
X1419803Y1102221D03*
Y1108630D03*
X1421653Y1099017D03*
Y1105426D03*
Y1111834D03*
X1425354Y1099017D03*
Y1105426D03*
Y1111834D03*
X1427203Y1102221D03*
Y1108630D03*
X1429054Y1105426D03*
Y1111834D03*
X1423503Y1121447D03*
Y1115039D03*
Y1127856D03*
X1414254Y1118243D03*
Y1124651D03*
X1416103Y1115039D03*
Y1121447D03*
Y1127856D03*
X1417954Y1118243D03*
Y1124651D03*
X1419803Y1115039D03*
Y1121447D03*
Y1127856D03*
X1421653Y1118243D03*
Y1124651D03*
X1425354Y1118243D03*
Y1124651D03*
X1427203Y1115039D03*
Y1121447D03*
Y1127856D03*
X1429054Y1118243D03*
Y1124651D03*
X1423503Y1134264D03*
X1414254Y1131060D03*
Y1137769D03*
X1416103Y1134264D03*
X1417954Y1131060D03*
Y1137769D03*
X1419803Y1134264D03*
X1421653Y1131060D03*
Y1137769D03*
X1425354Y1131060D03*
Y1137769D03*
X1427203Y1134264D03*
X1429054Y1131060D03*
Y1137769D03*
X1437871Y851380D03*
X1434171D03*
X1430470D03*
X1432321Y841467D03*
X1439721D03*
X1445271Y851380D03*
X1441571D03*
X1443420Y848176D03*
X1436020D03*
X1439721Y854584D03*
X1432321D03*
X1437871Y864197D03*
X1434171D03*
X1430471D03*
X1445271D03*
X1441571D03*
X1432321Y867401D03*
X1439721D03*
X1443420D03*
X1436020D03*
X1443420Y860993D03*
X1436020D03*
X1445271Y857789D03*
X1439720Y860993D03*
X1437871Y857789D03*
X1432320Y860993D03*
X1430471Y857789D03*
X1443420Y854584D03*
X1441571Y857789D03*
X1436020Y854584D03*
X1434171Y857789D03*
X1437871Y877014D03*
X1434171D03*
X1432321Y880219D03*
X1430471Y877014D03*
X1445271D03*
X1441571D03*
X1439721Y880219D03*
X1445271Y870606D03*
X1439720Y873810D03*
X1437871Y870606D03*
X1432320Y873810D03*
X1430471Y870606D03*
X1441571D03*
X1434171D03*
X1445271Y883423D03*
X1443420Y880219D03*
X1437871Y883423D03*
X1436020Y880219D03*
X1430471Y883423D03*
X1441571D03*
X1434171D03*
X1436020Y873810D03*
X1443420D03*
X1430471Y896240D03*
X1436020Y893036D03*
X1437871Y896240D03*
X1441571D03*
X1432320Y899445D03*
X1434171Y896240D03*
X1439720Y899445D03*
X1443420Y893036D03*
X1437871Y889832D03*
X1434171D03*
X1432321Y893036D03*
X1430471Y889832D03*
X1445271Y896240D03*
X1439721Y893036D03*
X1445271Y889832D03*
X1441571D03*
X1439720Y886627D03*
X1432320D03*
X1436020Y899445D03*
X1443420D03*
X1436020Y886627D03*
X1443420D03*
X1447120Y899445D03*
X1437871Y902649D03*
X1434171D03*
X1432320Y912262D03*
Y905853D03*
X1430471Y902649D03*
X1441571D03*
Y909057D03*
Y915466D03*
X1445271Y902649D03*
X1434171Y909057D03*
X1437871Y915466D03*
X1443420Y912262D03*
X1445271Y915466D03*
X1437871Y909057D03*
X1434171Y915466D03*
X1436020Y918670D03*
X1439720Y912262D03*
X1436020D03*
Y905853D03*
X1439720D03*
X1443420D03*
X1445271Y909057D03*
X1430244Y931358D03*
Y933658D03*
X1437871Y921875D03*
X1432320Y918670D03*
X1430471Y921875D03*
X1443420Y918670D03*
X1439777Y928348D03*
X1437477D03*
X1435177D03*
X1444377D03*
X1442077D03*
X1445271Y921875D03*
X1439720Y918670D03*
X1441571Y921875D03*
X1434171D03*
X1438402Y942151D03*
X1440702D03*
X1443002D03*
X1430564Y949138D03*
X1445392Y942195D03*
X1429726Y944537D03*
Y939937D03*
Y942237D03*
X1440015Y956539D03*
X1430564Y951438D03*
X1442413Y956539D03*
X1430534Y963828D03*
Y966128D03*
X1429544Y959298D03*
Y956998D03*
X1437565Y956619D03*
X1434545D03*
X1445045D03*
X1440015Y971139D03*
X1442413Y971099D03*
X1430404Y981208D03*
Y978908D03*
X1429544Y970798D03*
Y973098D03*
X1437565Y971139D03*
X1434545Y971099D03*
X1440015Y985579D03*
X1430604Y995298D03*
Y992998D03*
X1442413Y985579D03*
X1429544Y986898D03*
Y984598D03*
X1437565Y985579D03*
X1434545D03*
X1445045D03*
X1429544Y998398D03*
X1440015Y1014539D03*
Y1000059D03*
X1430584Y1009408D03*
Y1007108D03*
X1442413Y1014539D03*
Y1000059D03*
X1429544Y1012198D03*
Y1000698D03*
X1437565Y1000079D03*
X1434545D03*
X1445045D03*
X1429544Y1014498D03*
X1437436Y1014509D03*
X1434545Y1014539D03*
X1445036Y1014549D03*
X1430575Y1022185D03*
Y1019885D03*
X1439321Y1028854D03*
X1436821D03*
X1434321D03*
X1441821D03*
X1434083Y1031908D03*
X1443541Y1036914D03*
X1436453Y1041340D03*
X1442003Y1044544D03*
X1432753Y1047749D03*
X1440153D03*
X1447553Y1041340D03*
X1443853D03*
X1436453Y1047750D03*
X1443853D03*
X1430904Y1044544D03*
Y1038136D03*
X1434083Y1034408D03*
X1434813Y1037069D03*
X1439413D03*
X1437113D03*
X1432753Y1041340D03*
X1440153D03*
X1438304Y1044544D03*
X1434604D03*
X1432753Y1060565D03*
X1438303Y1057361D03*
X1432753Y1054157D03*
X1442004Y1057361D03*
X1438304Y1050952D03*
X1434604Y1063770D03*
X1442004D03*
X1438303D03*
X1442002Y1050952D03*
X1440153Y1054157D03*
X1436454D03*
X1434604Y1057361D03*
X1443854Y1054157D03*
Y1060565D03*
X1430903Y1063770D03*
X1440154Y1060565D03*
X1434603Y1050952D03*
X1436453Y1060565D03*
X1432753Y1073383D03*
X1430903Y1076587D03*
X1430904Y1070178D03*
X1443853Y1073383D03*
Y1066974D03*
X1438304Y1070178D03*
X1432754Y1079791D03*
X1443853D03*
X1436453Y1073383D03*
X1434602Y1070178D03*
X1436453Y1066974D03*
X1440153D03*
X1442002Y1070178D03*
X1447553Y1066974D03*
X1440154Y1079791D03*
X1436454D03*
X1438304Y1076587D03*
X1432753Y1066974D03*
X1442004Y1076587D03*
X1440153Y1073383D03*
X1434604Y1076587D03*
X1434603Y1082995D03*
X1432753Y1086200D03*
X1436453Y1092608D03*
X1443854Y1086200D03*
X1440153D03*
X1443854Y1092608D03*
X1438304Y1082995D03*
X1442004D03*
X1438303Y1095812D03*
X1434603D03*
X1442003Y1089403D03*
X1432754Y1092607D03*
X1430903Y1089403D03*
X1436454Y1086199D03*
X1430902Y1082995D03*
X1442003Y1095812D03*
X1440154Y1092607D03*
X1430903Y1095812D03*
X1434603Y1089403D03*
X1438303D03*
X1436454Y1105426D03*
X1434604Y1102221D03*
X1432753Y1099017D03*
X1442003Y1108630D03*
Y1102221D03*
X1440154Y1105426D03*
Y1099017D03*
X1438304Y1108630D03*
X1440154Y1111834D03*
X1443853Y1105426D03*
Y1111834D03*
X1438304Y1102221D03*
X1443853Y1099017D03*
X1430903Y1102221D03*
Y1108630D03*
X1432754Y1105426D03*
X1432753Y1111834D03*
X1434603Y1108630D03*
X1436454Y1111834D03*
Y1099016D03*
X1434604Y1121447D03*
Y1115039D03*
X1443854Y1124651D03*
X1443853Y1118243D03*
X1442004Y1121447D03*
Y1115039D03*
X1434604Y1127856D03*
X1430903Y1115039D03*
Y1121447D03*
Y1127856D03*
X1432753Y1118243D03*
Y1124651D03*
X1436454Y1118243D03*
Y1124651D03*
X1438303Y1115039D03*
Y1121447D03*
Y1127856D03*
X1440153Y1118243D03*
X1440154Y1124651D03*
X1442003Y1127856D03*
X1434604Y1134264D03*
X1443854Y1131060D03*
Y1137469D03*
X1430903Y1134264D03*
Y1140973D03*
X1432753Y1131060D03*
X1432754Y1137469D03*
X1434603Y1140973D03*
X1436454Y1131060D03*
Y1137469D03*
X1438303Y1134264D03*
Y1140973D03*
X1440154Y1131060D03*
Y1137469D03*
X1442003Y1134264D03*
Y1140973D03*
X1454521Y841467D03*
X1447121D03*
X1460071Y851380D03*
X1452671D03*
X1456371D03*
X1448971D03*
X1450820Y848176D03*
X1458220D03*
X1460071Y864197D03*
X1456371D03*
X1454521Y854584D03*
X1452671Y864197D03*
X1447121Y854584D03*
X1448971Y864197D03*
X1454521Y867401D03*
X1447121D03*
X1450820D03*
X1458220D03*
X1450820Y860993D03*
X1458220D03*
X1460071Y857789D03*
X1454520Y860993D03*
X1452671Y857789D03*
X1447120Y860993D03*
X1458220Y854584D03*
X1456371Y857789D03*
X1450820Y854584D03*
X1448971Y857789D03*
X1460071Y877014D03*
X1456371D03*
X1454521Y880219D03*
X1452671Y877014D03*
X1448971D03*
X1448970Y870606D03*
X1447121Y880219D03*
Y873810D03*
X1456371Y870606D03*
X1452671D03*
X1454520Y873810D03*
X1460071Y870606D03*
X1450820Y880219D03*
X1452671Y883423D03*
X1458220Y880219D03*
X1460071Y883423D03*
X1448971D03*
X1456371D03*
X1458220Y873810D03*
X1450820D03*
X1456370Y896240D03*
X1456371Y889832D03*
X1454521Y893036D03*
X1447121D03*
X1460071Y889832D03*
X1452671D03*
X1448971D03*
X1458220Y899445D03*
X1450820D03*
Y893036D03*
X1448971Y896240D03*
X1458220Y893036D03*
X1460071Y896240D03*
X1447120Y886627D03*
X1454520D03*
Y899445D03*
X1458220Y886627D03*
X1450820D03*
X1452671Y896240D03*
X1456371Y902649D03*
X1460071Y909057D03*
X1458221Y912262D03*
X1450820D03*
Y905853D03*
X1460070Y902649D03*
X1460071Y915466D03*
X1456371D03*
X1447122Y912262D03*
X1454521Y918670D03*
X1452671Y915466D03*
X1454522Y912262D03*
X1448971Y902649D03*
X1456370Y909057D03*
X1458220Y905853D03*
X1452671Y902649D03*
X1448970Y915466D03*
X1447120Y905853D03*
X1454520D03*
X1448971Y909057D03*
X1452671D03*
X1456371Y928283D03*
X1454522Y931488D03*
X1454520Y925079D03*
X1458220D03*
X1452426Y930125D03*
X1460071Y928283D03*
X1458220Y918670D03*
X1456371Y921875D03*
X1460070D03*
X1452670D03*
X1450820Y918670D03*
X1458220Y931488D03*
X1448971Y921875D03*
X1447120Y918670D03*
X1446677Y928348D03*
X1454520Y937896D03*
X1456371Y941100D03*
X1452426Y934725D03*
X1454520Y944304D03*
X1452321Y945354D03*
Y947654D03*
X1460070Y941100D03*
X1458221Y944304D03*
X1458220Y937896D03*
X1456371Y934691D03*
X1460070Y947509D03*
X1460071Y934691D03*
X1456371Y947509D03*
X1449992Y942195D03*
X1447692D03*
X1452426Y962325D03*
Y960025D03*
Y964625D03*
X1460070Y960326D03*
X1458220Y957122D03*
X1458221Y950713D03*
X1460071Y966735D03*
X1454520Y963530D03*
X1456371Y966735D03*
X1458220Y963529D03*
X1460071Y953917D03*
X1456370Y960326D03*
X1456371Y953917D03*
X1454520Y957122D03*
Y950713D03*
X1447545Y956619D03*
X1452426Y966925D03*
X1452333Y977669D03*
X1452476Y980736D03*
X1458221Y969939D03*
X1460070Y979552D03*
X1458220Y976347D03*
X1460071Y973143D03*
X1458220Y982756D03*
X1454521Y969939D03*
X1450045Y971099D03*
X1445445D03*
X1447745D03*
X1452426Y973825D03*
Y971525D03*
X1456371Y979552D03*
X1454520Y982756D03*
X1456371Y973143D03*
X1454520Y976347D03*
X1452426Y996825D03*
Y994525D03*
Y989925D03*
Y987625D03*
X1447545Y985579D03*
X1452436Y1010499D03*
X1452426Y1006025D03*
Y1003725D03*
Y1012925D03*
X1460503Y999684D03*
X1458654Y1009297D03*
X1458653Y1002888D03*
X1460504Y1012501D03*
X1456804Y999684D03*
X1454953Y1002888D03*
Y1009297D03*
X1456804Y1012501D03*
X1460504Y1006093D03*
X1447545Y1000079D03*
X1447345Y1014539D03*
X1452416Y1022635D03*
X1452426Y1017525D03*
X1458653Y1028523D03*
Y1022114D03*
X1460503Y1018910D03*
Y1031727D03*
X1460504Y1025318D03*
X1456804Y1031727D03*
X1454953Y1028523D03*
Y1022114D03*
X1456803Y1018910D03*
X1454953Y1015705D03*
X1446934Y1028889D03*
X1452466Y1031794D03*
Y1029494D03*
Y1027194D03*
X1456804Y1025318D03*
X1458653Y1015705D03*
X1447424Y1036526D03*
X1449649Y1035928D03*
X1458653Y1041340D03*
X1458654Y1034931D03*
X1451253Y1041340D03*
X1460503Y1038136D03*
X1458653Y1047749D03*
X1447553D03*
X1460504Y1044544D03*
X1451253Y1047749D03*
X1445704Y1044544D03*
X1454953Y1034931D03*
X1456804Y1038136D03*
X1454953Y1041340D03*
X1456804Y1044544D03*
X1449404D03*
X1454953Y1047749D03*
X1453104Y1044544D03*
X1460503Y1057361D03*
X1458653Y1060565D03*
X1456804Y1050952D03*
X1451253Y1060565D03*
X1447553Y1054157D03*
X1460504Y1050952D03*
Y1063770D03*
X1456804D03*
X1458653Y1054157D03*
X1454954D03*
X1453104Y1057361D03*
Y1063770D03*
X1454954Y1060565D03*
X1456803Y1057361D03*
X1453103Y1050952D03*
X1445703Y1057361D03*
X1445704Y1063770D03*
X1447554Y1060565D03*
X1449403Y1057361D03*
X1449404Y1063770D03*
X1451254Y1054157D03*
X1445703Y1050952D03*
X1449404D03*
X1460503Y1076587D03*
X1451253Y1066974D03*
X1449404Y1070178D03*
X1460504D03*
X1458654Y1066974D03*
X1454953Y1073383D03*
X1458653Y1079791D03*
X1454954D03*
X1451253D03*
X1454953Y1066974D03*
X1445702Y1070178D03*
X1453104Y1076587D03*
X1456804D03*
Y1070178D03*
X1453104D03*
X1447553Y1073383D03*
X1449404Y1076587D03*
X1445704D03*
X1447553Y1079791D03*
X1451253Y1073383D03*
X1458653D03*
X1445703Y1089404D03*
X1458654Y1086200D03*
X1456804Y1082995D03*
X1453104Y1089404D03*
X1449404Y1082995D03*
X1460504Y1089404D03*
X1445704Y1095813D03*
X1460504D03*
X1456803D03*
X1460504Y1082995D03*
X1445704D03*
X1456804Y1089404D03*
X1449404Y1095813D03*
X1454954Y1092607D03*
X1451254D03*
X1449403Y1089403D03*
X1447554Y1086199D03*
X1453103Y1082994D03*
X1458654Y1092607D03*
X1453103Y1095812D03*
X1447554Y1092607D03*
X1451254Y1086199D03*
X1454954D03*
X1445704Y1102221D03*
X1458653Y1105426D03*
X1456804Y1108630D03*
X1454953Y1099017D03*
X1449404Y1108630D03*
X1453104Y1102221D03*
X1451254Y1099017D03*
X1447553D03*
X1458653Y1111834D03*
X1460504Y1108630D03*
X1451253Y1111834D03*
X1447553D03*
X1454953Y1105426D03*
X1445704Y1108630D03*
X1449404Y1102221D03*
X1458653Y1099017D03*
X1454953Y1111834D03*
X1453104Y1108630D03*
X1447553Y1105426D03*
X1451253D03*
X1460504Y1102221D03*
X1456804D03*
X1445703Y1115039D03*
X1458653Y1118243D03*
X1456803Y1115039D03*
X1454953Y1118243D03*
X1453103Y1115039D03*
X1451253Y1118243D03*
X1447553D03*
X1445704Y1127856D03*
X1460503D03*
X1453103D03*
X1460504Y1115039D03*
X1449404D03*
X1460504Y1121447D03*
X1456804Y1127856D03*
X1453104Y1121447D03*
X1449404Y1127856D03*
X1445704Y1121447D03*
X1458653Y1124651D03*
X1454953D03*
X1451253D03*
X1447553D03*
X1456804Y1121447D03*
X1449404D03*
X1445703Y1140973D03*
X1458653Y1131060D03*
X1454953D03*
X1453103Y1140973D03*
X1451253Y1131060D03*
X1447554Y1137469D03*
Y1131060D03*
X1449403Y1134264D03*
X1460503Y1140973D03*
X1460504Y1134264D03*
X1458654Y1137469D03*
X1453104Y1134264D03*
X1451254Y1137469D03*
X1456803Y1140973D03*
X1454954Y1137469D03*
X1449403Y1140973D03*
X1456804Y1134264D03*
X1445703D03*
X1461517Y1575686D03*
Y1580678D03*
Y1587598D03*
Y1592590D03*
X1469321Y841467D03*
X1461921D03*
X1476721D03*
X1474871Y851380D03*
X1471171D03*
X1467471D03*
X1463771D03*
X1465620Y848176D03*
X1473020D03*
X1461921Y854584D03*
X1474871Y864197D03*
X1471171D03*
X1469321Y854584D03*
X1467471Y864197D03*
X1463771D03*
X1476721Y854584D03*
X1461921Y867401D03*
X1476721D03*
X1469321D03*
X1465620D03*
X1473020D03*
X1465620Y860993D03*
X1473020D03*
X1467471Y857789D03*
X1461920Y860993D03*
X1476720D03*
X1474871Y857789D03*
X1471171D03*
X1465620Y854584D03*
X1463771Y857789D03*
X1473020Y854584D03*
X1469320Y860993D03*
X1461921Y880219D03*
X1471171Y877014D03*
X1476721Y880219D03*
X1474871Y877014D03*
X1469321Y880219D03*
X1467471Y877014D03*
X1463771D03*
Y870606D03*
X1471171D03*
X1461920Y873810D03*
X1467471Y870606D03*
X1469320Y873810D03*
X1474871Y870606D03*
X1476720Y873810D03*
X1465620Y880219D03*
X1467471Y883423D03*
X1473020Y880219D03*
X1474871Y883423D03*
X1463771D03*
X1471171D03*
X1473020Y873810D03*
X1465620D03*
X1474871Y889832D03*
X1465621Y893036D03*
X1476721D03*
X1474871Y896240D03*
X1471171Y889832D03*
X1467471D03*
X1463771D03*
X1473021Y899445D03*
X1465620D03*
X1476720D03*
X1461920D03*
X1469320D03*
Y893036D03*
X1473020D03*
X1461920D03*
X1467471Y896240D03*
X1463771D03*
X1471171D03*
X1461920Y886627D03*
X1469320D03*
X1476720D03*
X1473020D03*
X1465620D03*
X1461920Y905853D03*
X1473020Y912262D03*
X1471171Y909057D03*
X1465620Y912262D03*
Y905853D03*
X1471171Y902649D03*
X1469321Y905853D03*
X1474870Y915466D03*
X1461920Y912262D03*
X1463771Y909057D03*
X1469320Y912262D03*
X1467471Y909057D03*
X1476720Y912262D03*
X1474871Y909057D03*
Y902649D03*
X1463771D03*
X1467471D03*
X1463771Y915466D03*
X1476720Y905853D03*
X1471171Y915466D03*
X1473020Y905853D03*
X1467471Y915466D03*
X1461920Y925079D03*
X1471170Y928283D03*
X1469321Y925079D03*
X1465620D03*
Y918670D03*
X1473021D03*
X1471171Y921875D03*
X1473020Y931488D03*
X1465620D03*
X1476720D03*
X1474871Y921875D03*
X1476720Y918670D03*
X1474871Y928283D03*
X1473020Y925079D03*
X1476720D03*
X1467471Y921875D03*
X1469320Y918670D03*
X1461920Y931488D03*
X1467471Y928283D03*
X1469320Y931488D03*
X1463771Y928283D03*
Y921875D03*
X1461920Y918670D03*
Y944304D03*
X1474871Y934691D03*
X1473021Y937896D03*
X1471171Y941100D03*
X1469321Y944304D03*
X1465620D03*
Y937896D03*
X1471170Y947509D03*
X1474871D03*
Y941100D03*
X1476720Y937896D03*
X1473020Y944304D03*
X1476720D03*
X1463771Y947509D03*
X1467471D03*
X1463771Y941100D03*
X1461920Y937896D03*
X1467471Y941100D03*
X1469320Y937896D03*
X1463771Y934691D03*
X1471171D03*
X1467471D03*
X1474871Y953917D03*
X1473021Y957122D03*
X1471171Y960326D03*
X1465620Y957122D03*
Y950713D03*
X1473020D03*
X1461920Y963530D03*
X1476721D03*
X1471170Y966735D03*
X1469321Y963530D03*
X1465620D03*
X1476720Y950713D03*
X1463771Y966735D03*
X1467471D03*
X1474871D03*
X1473020Y963530D03*
X1461920Y950713D03*
X1469320D03*
X1467471Y960326D03*
X1469320Y957122D03*
X1463771Y960326D03*
X1461920Y957122D03*
X1476720D03*
X1474871Y960326D03*
X1471171Y953917D03*
X1463771D03*
X1467471D03*
X1473021Y976347D03*
X1473020Y969939D03*
X1465620Y976347D03*
Y969939D03*
X1474870Y973143D03*
X1471171Y979552D03*
X1461920Y982756D03*
X1469321D03*
X1465620D03*
X1463771Y979552D03*
X1461920Y976347D03*
X1467471Y979552D03*
X1469320Y976347D03*
X1476720Y982756D03*
X1473020D03*
X1474871Y979552D03*
X1476720Y976347D03*
X1471171Y973143D03*
X1463771D03*
X1467471D03*
X1461920Y969939D03*
X1469320D03*
X1476720D03*
X1475303Y1006093D03*
X1473453Y1009297D03*
X1473454Y1002888D03*
X1471604Y999684D03*
X1466053Y1009297D03*
X1466054Y1002888D03*
X1467903Y1006093D03*
X1464204D03*
X1471603Y1012501D03*
X1477153Y1002888D03*
X1475304Y999684D03*
Y1012501D03*
X1477153Y1009297D03*
X1471604Y1006093D03*
X1462353Y1002888D03*
X1469753D03*
X1464204Y999684D03*
X1467904D03*
X1467903Y1012501D03*
X1469753Y1009297D03*
X1464204Y1012501D03*
X1462353Y1009297D03*
Y1015705D03*
X1473453Y1028523D03*
X1466053D03*
Y1022114D03*
Y1015705D03*
X1477154D03*
X1475303Y1025318D03*
X1473453Y1022114D03*
X1471604Y1018910D03*
X1469754Y1015705D03*
X1471603Y1031727D03*
X1473453Y1015705D03*
X1475304Y1031727D03*
X1477153Y1028523D03*
Y1022114D03*
X1475304Y1018910D03*
X1464204Y1031727D03*
X1462353Y1028523D03*
X1467904Y1031727D03*
X1469753Y1028523D03*
X1462353Y1022114D03*
X1464204Y1018910D03*
X1469753Y1022114D03*
X1467904Y1018910D03*
X1464204Y1025318D03*
X1471604D03*
X1467904D03*
X1462353Y1034931D03*
X1473454Y1041340D03*
X1466053D03*
Y1034931D03*
X1475303Y1044544D03*
X1471604Y1038136D03*
X1469754Y1034931D03*
X1466053Y1047749D03*
X1473453D03*
X1477153Y1041340D03*
X1475304Y1038136D03*
X1477153Y1047749D03*
Y1034931D03*
X1473453D03*
X1462353Y1047749D03*
X1469753D03*
X1462353Y1041340D03*
X1464204Y1038136D03*
X1469753Y1041340D03*
X1467904Y1038136D03*
X1464204Y1044544D03*
X1471604D03*
X1467904D03*
X1462353Y1054157D03*
X1473453Y1060565D03*
X1471604Y1057361D03*
X1466053Y1060565D03*
Y1054157D03*
X1471603Y1050952D03*
X1469753Y1054157D03*
X1475304Y1063770D03*
X1477153Y1060565D03*
X1475304Y1057361D03*
Y1050952D03*
X1477153Y1054157D03*
X1473453D03*
X1462353Y1060565D03*
X1464204Y1057361D03*
X1469753Y1060565D03*
X1467904Y1057361D03*
X1464204Y1050952D03*
X1467904D03*
X1464204Y1063770D03*
X1471604D03*
X1467904D03*
X1462353Y1073383D03*
X1471604Y1076587D03*
X1469754Y1073383D03*
X1466053Y1066974D03*
X1473453D03*
X1471603Y1070178D03*
X1466053Y1073383D03*
X1473454Y1079791D03*
X1466053D03*
X1475304Y1070178D03*
X1477153Y1066974D03*
Y1079791D03*
X1475304Y1076587D03*
X1473453Y1073383D03*
X1477153D03*
X1462353Y1079791D03*
X1464204Y1076587D03*
X1469753Y1079791D03*
X1467904Y1076587D03*
X1464204Y1070178D03*
X1462353Y1066974D03*
X1467904Y1070178D03*
X1469753Y1066974D03*
X1462353Y1092608D03*
X1475303Y1082995D03*
X1473453Y1086200D03*
X1469754Y1092608D03*
X1466053D03*
Y1086200D03*
X1471603Y1089404D03*
X1475304Y1095813D03*
X1471604D03*
X1467904D03*
Y1089404D03*
X1469753Y1086200D03*
X1475304Y1089404D03*
X1477153Y1086200D03*
X1464204Y1089404D03*
X1462353Y1086200D03*
X1473453Y1092608D03*
X1471604Y1082995D03*
X1477153Y1092608D03*
X1464204Y1082995D03*
X1467904D03*
X1464204Y1095813D03*
X1462353Y1105426D03*
X1462354Y1099017D03*
X1475303Y1108630D03*
Y1102221D03*
X1473454Y1105426D03*
X1469753D03*
X1467904Y1102221D03*
X1464203D03*
X1473454Y1111834D03*
X1466053D03*
Y1099017D03*
X1471604Y1102221D03*
X1477153Y1099017D03*
X1469753D03*
X1473453D03*
X1471604Y1108630D03*
X1466053Y1105426D03*
X1462353Y1111834D03*
X1469753D03*
X1467904Y1108630D03*
X1464204D03*
X1477154Y1105426D03*
Y1111833D03*
X1462353Y1118243D03*
X1477153D03*
X1475303Y1115039D03*
X1473453Y1118243D03*
X1471604Y1121447D03*
X1469754Y1118243D03*
X1466053D03*
X1475303Y1127856D03*
X1467903D03*
X1467904Y1115039D03*
X1471604D03*
X1464204Y1127856D03*
X1475304Y1121447D03*
X1471604Y1127856D03*
X1467904Y1121447D03*
X1466053Y1124651D03*
X1462353D03*
X1477153D03*
X1473453D03*
X1469753D03*
X1464204Y1115039D03*
Y1121447D03*
X1462353Y1131060D03*
X1477153D03*
X1475303Y1140973D03*
X1473453Y1131060D03*
X1469753D03*
X1466053D03*
X1467903Y1140973D03*
X1469754Y1137469D03*
X1464203Y1140973D03*
X1477154Y1137469D03*
X1471603Y1140973D03*
X1467904Y1134264D03*
X1466054Y1137469D03*
X1462354D03*
X1475304Y1134264D03*
X1473454Y1137469D03*
X1471604Y1134264D03*
X1464204D03*
X1473577Y1580678D03*
Y1575686D03*
X1466473D03*
Y1580678D03*
X1477755Y1578182D03*
X1462295D03*
X1474355D03*
X1465695D03*
X1471773Y1599884D03*
X1466817D03*
X1473577Y1592590D03*
Y1587598D03*
X1466473D03*
Y1592590D03*
X1477755Y1590094D03*
X1462295D03*
X1474355D03*
X1465695D03*
X1466817Y1611796D03*
X1471773D03*
X1466817Y1604876D03*
X1471773D03*
Y1616788D03*
X1466817D03*
X1467595Y1614292D03*
X1470995D03*
X1467595Y1602380D03*
X1470995D03*
X1491521Y841467D03*
X1484121D03*
X1478571Y851380D03*
X1482271D03*
X1489671D03*
X1485971D03*
X1493371D03*
X1487820Y848176D03*
X1480420D03*
X1478571Y864197D03*
X1491521Y854584D03*
X1489671Y864197D03*
X1485971D03*
X1482271D03*
X1493371D03*
X1491521Y867401D03*
X1484121D03*
Y854584D03*
X1487820Y867401D03*
X1480420D03*
X1487820Y860993D03*
X1480420D03*
X1491520D03*
X1489671Y857789D03*
X1484120Y860993D03*
X1482271Y857789D03*
X1493371D03*
X1487820Y854584D03*
X1485971Y857789D03*
X1480420Y854584D03*
X1478571Y857789D03*
Y877014D03*
X1491521Y880219D03*
X1485971Y877014D03*
X1484121Y880219D03*
X1489671Y877014D03*
X1482271D03*
X1493371D03*
Y870606D03*
X1478571D03*
X1485971D03*
X1489671D03*
X1491520Y873810D03*
X1482271Y870606D03*
X1484120Y873810D03*
X1487820Y880219D03*
X1489671Y883423D03*
X1480420Y880219D03*
X1482271Y883423D03*
X1485971D03*
X1493371D03*
X1478571D03*
X1487820Y873810D03*
X1480420D03*
X1478570Y896240D03*
X1478571Y889832D03*
X1491521Y893036D03*
X1482271Y889832D03*
X1489671D03*
X1485971D03*
X1482270Y896240D03*
X1480421Y893036D03*
X1493371Y889832D03*
X1491520Y899445D03*
X1484120D03*
X1487820D03*
Y893036D03*
X1484120D03*
X1485971Y896240D03*
X1493371D03*
X1489671D03*
X1480420Y899445D03*
X1491520Y886627D03*
X1484120D03*
X1480420D03*
X1487820D03*
X1478571Y909057D03*
Y902649D03*
X1491520Y912262D03*
X1487820Y905853D03*
X1485971Y909057D03*
X1484121Y912262D03*
X1491520Y905853D03*
X1485970Y902649D03*
X1478571Y915466D03*
X1482271D03*
X1489671Y902649D03*
X1493371D03*
X1487820Y912262D03*
X1489671Y909057D03*
X1493371D03*
X1489671Y915466D03*
X1485971D03*
X1493371D03*
X1480420Y912262D03*
X1482271Y909057D03*
Y902649D03*
X1484120Y905853D03*
X1480420D03*
X1478571Y928283D03*
Y921875D03*
X1491520Y925079D03*
Y918670D03*
X1487820Y925079D03*
X1485971Y928283D03*
X1485970Y921875D03*
X1484120Y918670D03*
X1491520Y931488D03*
X1484121D03*
X1487820D03*
X1489671Y928283D03*
X1493371D03*
X1482271D03*
Y921875D03*
X1480420Y918670D03*
X1489671Y921875D03*
X1487820Y918670D03*
X1493371Y921875D03*
X1480420Y931488D03*
Y925079D03*
X1484120D03*
X1478571Y941100D03*
Y934691D03*
X1491520Y944304D03*
Y937896D03*
X1487820Y944304D03*
X1485970Y941100D03*
X1484120Y937896D03*
X1482271Y934691D03*
X1478571Y947509D03*
X1485971D03*
X1489671Y941100D03*
X1487820Y937896D03*
X1493371Y941100D03*
X1489671Y934691D03*
X1485971D03*
X1493371D03*
X1489671Y947509D03*
X1493371D03*
X1482271D03*
Y941100D03*
X1480420Y937896D03*
X1484120Y944304D03*
X1480420D03*
X1478571Y960326D03*
Y953917D03*
X1491520Y957122D03*
Y950713D03*
X1485970Y960326D03*
X1484120Y957122D03*
X1482271Y953917D03*
X1484121Y950713D03*
X1478570Y966735D03*
X1491520Y963530D03*
X1485971Y966735D03*
X1487820Y963530D03*
X1480420D03*
X1487820Y950713D03*
X1489671Y960326D03*
X1487820Y957122D03*
X1493371Y960326D03*
Y966735D03*
X1489671D03*
X1480420Y950713D03*
X1489671Y953917D03*
X1493371D03*
X1485971D03*
X1482271Y966735D03*
X1480420Y957122D03*
X1482271Y960326D03*
X1484120Y963530D03*
X1478571Y979552D03*
Y973143D03*
X1491521Y976347D03*
X1491520Y969939D03*
X1484120Y976347D03*
X1484121Y969939D03*
X1489671Y973143D03*
X1485970Y979552D03*
X1482271Y973143D03*
X1493370D03*
X1491520Y982756D03*
X1487820D03*
X1484120D03*
X1480420D03*
Y976347D03*
X1482271Y979552D03*
X1489671D03*
X1493371D03*
X1487820Y976347D03*
X1485971Y973143D03*
X1487820Y969939D03*
X1480420D03*
X1479004Y999684D03*
X1486403D03*
X1484553Y1002888D03*
X1482704Y1006093D03*
X1479003Y1012501D03*
X1486404D03*
X1491953Y1009297D03*
Y1002888D03*
X1484554Y1009297D03*
X1493804Y1006093D03*
X1490104D03*
X1486404D03*
X1493804Y1012501D03*
X1480853Y1002888D03*
X1482703Y999684D03*
X1490104Y1012501D03*
X1488253Y1009297D03*
X1482704Y1012501D03*
X1480853Y1009297D03*
X1493803Y999684D03*
X1488253Y1002888D03*
X1490104Y999684D03*
X1479004Y1025318D03*
Y1018910D03*
X1491953Y1028523D03*
Y1022114D03*
X1484553Y1028523D03*
X1486403Y1018910D03*
X1484553Y1022114D03*
X1482704Y1025318D03*
X1480853Y1015705D03*
X1479004Y1031727D03*
X1486404D03*
X1488253Y1015705D03*
X1491953D03*
X1490104Y1031727D03*
X1488253Y1028523D03*
X1493804Y1031727D03*
X1488253Y1022114D03*
X1490104Y1018910D03*
X1493804D03*
X1490104Y1025318D03*
X1486404D03*
X1493804D03*
X1484553Y1015705D03*
X1482704Y1031727D03*
X1480853Y1028523D03*
Y1022114D03*
X1482704Y1018910D03*
X1479004Y1044544D03*
Y1038136D03*
X1491953Y1034931D03*
Y1041340D03*
X1488253Y1034931D03*
X1486403Y1038136D03*
X1484553Y1041340D03*
X1482704Y1044544D03*
X1491953Y1047749D03*
X1484553D03*
X1480853Y1041340D03*
X1482704Y1038136D03*
X1488253Y1047749D03*
Y1041340D03*
X1490104Y1038136D03*
X1493804D03*
X1480853Y1047749D03*
X1486404Y1044544D03*
X1484553Y1034931D03*
X1490104Y1044544D03*
X1493804D03*
X1480853Y1034931D03*
X1479004Y1057361D03*
Y1050952D03*
X1491953Y1054157D03*
X1486404Y1057361D03*
X1484553Y1060565D03*
X1488253Y1054157D03*
X1486404Y1050952D03*
X1491953Y1060565D03*
X1479004Y1063770D03*
X1482704D03*
X1488253Y1060565D03*
X1490104Y1057361D03*
X1493804D03*
X1486404Y1063770D03*
X1490104D03*
X1493804D03*
X1490104Y1050952D03*
X1493804D03*
X1480853Y1060565D03*
X1482704Y1057361D03*
Y1050952D03*
X1484553Y1054157D03*
X1480853D03*
X1479004Y1076587D03*
Y1070178D03*
X1486404Y1076587D03*
Y1070178D03*
X1488253Y1073383D03*
X1484553Y1066974D03*
X1491953Y1073383D03*
Y1066974D03*
X1484553Y1079791D03*
X1491953D03*
X1493804Y1070178D03*
X1490104D03*
X1488253Y1066974D03*
X1480853Y1079791D03*
X1482704Y1076587D03*
Y1070178D03*
X1480853Y1066974D03*
X1488253Y1079791D03*
X1490104Y1076587D03*
X1493804D03*
X1484553Y1073383D03*
X1480853D03*
X1479004Y1089404D03*
Y1082995D03*
X1488254Y1092608D03*
X1486404Y1089404D03*
X1484554Y1086200D03*
X1482704Y1082995D03*
X1491954Y1092608D03*
X1491953Y1086200D03*
X1479004Y1095813D03*
X1490103D03*
X1493804D03*
X1490104Y1089404D03*
X1488253Y1086200D03*
X1493804Y1089404D03*
X1490104Y1082995D03*
X1486404D03*
X1493804D03*
X1486404Y1095813D03*
X1482703D03*
X1482704Y1089404D03*
X1480853Y1086200D03*
X1484553Y1092608D03*
X1480853D03*
X1479004Y1102221D03*
X1490104Y1108630D03*
Y1102221D03*
X1488254Y1099017D03*
X1484553D03*
X1482704Y1108630D03*
X1480853Y1099017D03*
X1491953Y1105426D03*
Y1111834D03*
X1493804Y1108630D03*
Y1102221D03*
X1491953Y1099017D03*
X1486404Y1102221D03*
X1479003Y1108629D03*
X1488254Y1105426D03*
X1484554Y1111833D03*
X1482703Y1102220D03*
X1480854Y1111833D03*
Y1105426D03*
X1486403Y1108630D03*
X1488254Y1111833D03*
X1484554Y1105426D03*
X1490103Y1115039D03*
X1488253Y1118243D03*
X1484553D03*
X1480853D03*
X1486403Y1115039D03*
X1491953Y1118243D03*
X1490103Y1127856D03*
X1482703D03*
X1493804Y1115039D03*
Y1127856D03*
X1490104Y1121447D03*
X1486404Y1127856D03*
X1482704Y1121447D03*
X1479004Y1127856D03*
X1491953Y1124651D03*
X1488253D03*
X1484553D03*
X1480853D03*
X1479004Y1115039D03*
Y1121447D03*
X1493804D03*
X1486404D03*
X1482703Y1115038D03*
X1490103Y1140973D03*
X1488253Y1131060D03*
X1484553D03*
X1480853D03*
X1482703Y1140973D03*
X1491953Y1131060D03*
X1493803Y1140973D03*
X1490104Y1134264D03*
X1488254Y1137469D03*
X1482704Y1134264D03*
X1480854Y1137469D03*
X1491954D03*
X1486403Y1140973D03*
X1484554Y1137469D03*
X1479003Y1140973D03*
X1479004Y1134264D03*
X1493804D03*
X1486404D03*
X1490593Y1580678D03*
Y1575686D03*
X1485637D03*
Y1580678D03*
X1478533D03*
Y1575686D03*
X1489815Y1578182D03*
X1486415D03*
X1490937Y1599884D03*
X1478877D03*
X1483833D03*
X1490593Y1587598D03*
X1485637D03*
Y1592590D03*
X1490593D03*
X1478533D03*
Y1587598D03*
X1489815Y1590094D03*
X1486415D03*
X1490937Y1604876D03*
Y1611796D03*
Y1616788D03*
X1483833D03*
X1478877D03*
Y1611796D03*
X1483833D03*
X1478877Y1604876D03*
X1483833D03*
X1491715Y1614292D03*
X1479655D03*
X1483055D03*
X1491715Y1602380D03*
X1479655D03*
X1483055D03*
X1504471Y844671D03*
X1498921Y841467D03*
X1508171Y851380D03*
X1504471D03*
X1500771D03*
X1497071D03*
X1495220Y848176D03*
X1504471Y864197D03*
X1500771D03*
X1508170Y857789D03*
X1497071Y864197D03*
X1506321Y860993D03*
Y854584D03*
X1498921D03*
X1510021Y860993D03*
X1506320Y867401D03*
X1498921D03*
X1510021D03*
X1508171Y864197D03*
X1510021Y854584D03*
X1495220Y867401D03*
X1502621D03*
X1495220Y860993D03*
X1502621D03*
X1504471Y857789D03*
X1498920Y860993D03*
X1497071Y857789D03*
X1502620Y854584D03*
X1500771Y857789D03*
X1495220Y854584D03*
X1504471Y877014D03*
X1498921Y880219D03*
X1508171Y877014D03*
X1497071D03*
X1506321Y880219D03*
X1500771Y877014D03*
X1510021Y880219D03*
Y873810D03*
X1508170Y883423D03*
X1500771Y870606D03*
X1508171D03*
X1497071D03*
X1498920Y873810D03*
X1504471Y870606D03*
X1506321Y873810D03*
X1495220Y880219D03*
X1497071Y883423D03*
X1502621Y880219D03*
X1504471Y883423D03*
X1500771D03*
X1495220Y873810D03*
X1502621D03*
X1508171Y889832D03*
X1504471Y896240D03*
Y889832D03*
X1500771D03*
X1508171Y896240D03*
X1502621Y893036D03*
X1500771Y896240D03*
X1497071Y889832D03*
X1510021Y893036D03*
X1498921Y899445D03*
X1510021D03*
X1502621D03*
X1506320D03*
X1495220D03*
Y893036D03*
X1498920D03*
X1497071Y896240D03*
X1506320Y893036D03*
X1498920Y886627D03*
X1506321D03*
X1495220D03*
X1502621D03*
X1510021D03*
X1495221Y905853D03*
X1504471Y902649D03*
X1498920Y912262D03*
X1497070Y909057D03*
X1497071Y902649D03*
X1508171Y915466D03*
X1504471D03*
X1500770D03*
X1504471Y909057D03*
X1510021Y912262D03*
X1506321D03*
X1508171Y909057D03*
X1500771Y902649D03*
X1508171D03*
X1502621Y912262D03*
X1500771Y909057D03*
X1502621Y905853D03*
X1510021D03*
X1498920D03*
X1506321D03*
X1495220Y912262D03*
X1497071Y915466D03*
X1495221Y925079D03*
X1504471Y921875D03*
X1497070Y928283D03*
X1498921Y918670D03*
X1497071Y921875D03*
X1498920Y931488D03*
X1504471Y928283D03*
X1510021Y918670D03*
X1510020Y931488D03*
X1502621D03*
X1500771Y928283D03*
X1506321Y931488D03*
X1508171Y928283D03*
X1500771Y921875D03*
X1502621Y918670D03*
X1508171Y921875D03*
X1506321Y918670D03*
X1502621Y925079D03*
X1510021D03*
X1498920D03*
X1506321D03*
X1495220Y931488D03*
Y918670D03*
X1495221Y944304D03*
X1504471Y941100D03*
Y934691D03*
X1500770D03*
X1498921Y937896D03*
X1497071Y941100D03*
X1497070Y947509D03*
X1508171Y934691D03*
X1510021Y937896D03*
X1504471Y947509D03*
X1500771Y941100D03*
X1502621Y937896D03*
X1508171Y941100D03*
X1506321Y937896D03*
X1500771Y947509D03*
X1508171D03*
X1495220Y937896D03*
X1510021Y944304D03*
X1497071Y934691D03*
X1502621Y944304D03*
X1506320D03*
X1498920D03*
X1504471Y960326D03*
Y953917D03*
X1500771D03*
X1498921Y957122D03*
X1497071Y960326D03*
X1498920Y950713D03*
X1495221Y963530D03*
X1497070Y966735D03*
X1502621Y963530D03*
X1510021Y957122D03*
X1508171Y953917D03*
X1510021Y950713D03*
X1506320Y963530D03*
X1504471Y966735D03*
X1500771D03*
X1508171D03*
X1498920Y963530D03*
X1502621Y950713D03*
X1506320D03*
X1508171Y960326D03*
X1506320Y957122D03*
X1500771Y960326D03*
X1502621Y957122D03*
X1510021Y963530D03*
X1495220Y950713D03*
Y957122D03*
X1497071Y953917D03*
X1504471Y979552D03*
Y973143D03*
X1498921Y976347D03*
X1498920Y969939D03*
X1500770Y973143D03*
X1497071Y979552D03*
X1510021Y976347D03*
X1495221Y982756D03*
X1510043Y980606D03*
X1510021Y969939D03*
X1508171Y973143D03*
X1502621Y969939D03*
X1506321D03*
X1495220Y976347D03*
Y969939D03*
X1497071Y973143D03*
X1497503Y1012501D03*
Y999684D03*
X1504904Y1006093D03*
Y999684D03*
X1501203Y1006093D03*
X1499353Y1009297D03*
X1499354Y1002888D03*
X1510453Y1009297D03*
Y1002888D03*
X1508603Y1006093D03*
X1504903Y1012501D03*
X1497504Y1006093D03*
X1501204Y1012501D03*
X1508603D03*
X1503053Y1009297D03*
X1506753D03*
X1495653D03*
X1495655Y1002888D03*
X1506753D03*
X1508603Y999684D03*
X1503053Y1002888D03*
X1501204Y999684D03*
X1504904Y1025318D03*
X1499353Y1028523D03*
X1501203Y1025318D03*
X1504904Y1031727D03*
X1497503D03*
X1495654Y1015705D03*
X1497504Y1018910D03*
X1499353Y1022114D03*
X1503054Y1015705D03*
X1504904Y1018910D03*
X1506753Y1015705D03*
X1510453Y1028523D03*
X1510452Y1022114D03*
X1508603Y1025318D03*
X1499353Y1015705D03*
X1510453D03*
X1501204Y1031727D03*
X1503053Y1028523D03*
X1508603Y1031727D03*
X1506753Y1028523D03*
Y1022114D03*
X1508603Y1018910D03*
X1503053Y1022114D03*
X1501204Y1018910D03*
X1495653Y1028523D03*
Y1022114D03*
X1497504Y1025318D03*
X1504904Y1044544D03*
X1501203D03*
X1499354Y1041340D03*
X1497504Y1038136D03*
X1495654Y1034931D03*
X1508604Y1044544D03*
X1499353Y1047749D03*
X1504904Y1038136D03*
X1510453Y1041340D03*
Y1047749D03*
X1503053Y1041340D03*
X1501204Y1038136D03*
X1506753Y1041340D03*
X1508603Y1038136D03*
X1503053Y1047749D03*
X1506753D03*
X1503053Y1034931D03*
X1510453D03*
X1499353D03*
X1506753D03*
X1495653Y1047749D03*
Y1041340D03*
X1497504Y1044544D03*
X1504904Y1057361D03*
Y1050952D03*
X1499354Y1060565D03*
X1497504Y1057361D03*
X1497503Y1050952D03*
X1495654Y1054157D03*
X1504904Y1063770D03*
X1501203D03*
X1510453Y1060565D03*
X1508604Y1063770D03*
X1495653Y1060565D03*
X1503053D03*
X1501204Y1057361D03*
X1506753Y1060565D03*
X1508604Y1057361D03*
X1501203Y1050952D03*
X1508604Y1050953D03*
X1499353Y1054157D03*
X1497504Y1063770D03*
X1510453Y1054157D03*
X1503053D03*
X1506753D03*
X1504904Y1076587D03*
Y1070178D03*
X1497504Y1076587D03*
X1497503Y1070178D03*
X1495654Y1073383D03*
X1499353Y1066974D03*
X1499354Y1079791D03*
X1510453Y1066974D03*
Y1079791D03*
X1506753D03*
X1508604Y1076587D03*
X1501204Y1070178D03*
X1503053Y1066974D03*
X1508604Y1070178D03*
X1506753Y1066974D03*
X1503053Y1079791D03*
X1501204Y1076587D03*
X1499353Y1073383D03*
X1510453D03*
X1503053D03*
X1506753D03*
X1495653Y1066974D03*
Y1079791D03*
X1499353Y1086200D03*
X1497503Y1089404D03*
X1495653Y1092608D03*
X1504904Y1089404D03*
Y1082995D03*
X1501203D03*
X1508604Y1082996D03*
X1510453Y1086200D03*
X1504903Y1095813D03*
X1497504D03*
X1508603D03*
X1501204D03*
Y1089404D03*
X1503053Y1086200D03*
X1508604Y1089404D03*
X1506753Y1086200D03*
X1503053Y1092608D03*
X1510452D03*
X1499353D03*
X1506753D03*
X1495653Y1086200D03*
X1497504Y1082995D03*
X1503053Y1105426D03*
X1497503Y1102221D03*
X1495653Y1105426D03*
X1495654Y1099017D03*
X1508603Y1108630D03*
X1506754Y1111834D03*
X1499353D03*
X1503053Y1099017D03*
X1510453D03*
X1508602Y1102221D03*
X1497504Y1108630D03*
X1501204D03*
X1510453Y1111834D03*
X1499353Y1105426D03*
X1510453D03*
X1504904Y1108630D03*
X1495653Y1111834D03*
X1503053D03*
X1506753Y1099017D03*
Y1105426D03*
X1504904Y1102221D03*
X1501204D03*
X1499354Y1099017D03*
X1506753Y1124651D03*
Y1118243D03*
X1504904Y1121447D03*
X1499353Y1118243D03*
X1497503Y1115039D03*
X1495653Y1118243D03*
X1508603Y1115039D03*
X1504904Y1127856D03*
X1497503D03*
X1501204Y1115039D03*
X1504904D03*
X1503053Y1124651D03*
X1497504Y1121447D03*
X1501204Y1127856D03*
X1499353Y1124651D03*
X1495653D03*
X1503053Y1118243D03*
X1510453D03*
X1501204Y1121447D03*
X1508603Y1121446D03*
X1510453Y1124650D03*
X1508603Y1127855D03*
X1506754Y1137469D03*
X1506753Y1131060D03*
X1503053D03*
X1499353D03*
X1495653D03*
X1504904Y1134264D03*
X1497503Y1140973D03*
X1510453Y1131060D03*
X1508604Y1134264D03*
X1501203Y1140973D03*
X1499354Y1137469D03*
X1510454D03*
X1503054D03*
X1497504Y1134264D03*
X1495654Y1137469D03*
X1501204Y1134264D03*
X1508603Y1140973D03*
X1504903D03*
X1509757Y1575686D03*
Y1580678D03*
X1502653D03*
X1497697D03*
X1502653Y1575686D03*
X1497697D03*
X1501875Y1578182D03*
X1498475D03*
X1502997Y1599884D03*
X1507953D03*
X1495893D03*
X1509757Y1587598D03*
Y1592590D03*
X1502653D03*
X1497697D03*
X1502653Y1587598D03*
X1497697D03*
X1501875Y1590094D03*
X1498475D03*
X1502997Y1616788D03*
X1507953D03*
X1502997Y1604876D03*
Y1611796D03*
X1507953Y1604876D03*
Y1611796D03*
X1495893Y1604876D03*
Y1611796D03*
Y1616788D03*
X1503775Y1614292D03*
X1507175D03*
X1495115D03*
X1503775Y1602380D03*
X1507175D03*
X1495115D03*
X1505315Y1675383D03*
Y1679920D03*
Y1684454D03*
Y1689556D03*
Y1694093D03*
Y1698627D03*
Y1703729D03*
Y1708266D03*
Y1712800D03*
Y1726974D03*
Y1722440D03*
Y1717903D03*
X1511871Y844671D03*
X1513722Y848176D03*
X1511871Y851380D03*
X1519271D03*
X1515571D03*
X1521121Y860993D03*
Y854584D03*
X1515570Y864197D03*
X1513721Y854584D03*
Y860993D03*
X1521121Y867401D03*
X1517421D03*
X1513721D03*
X1511871Y864197D03*
X1519270D03*
X1522970D03*
X1511871Y857789D03*
X1519271D03*
X1515571D03*
X1517421Y860993D03*
Y854584D03*
X1511871Y870606D03*
X1522971D03*
X1517421Y873810D03*
X1511871Y883423D03*
X1517421Y880219D03*
X1522971Y883423D03*
X1515571D03*
X1513720Y880219D03*
X1519271Y883423D03*
X1521121Y880219D03*
X1513720Y873810D03*
X1515571Y870606D03*
X1521121Y873810D03*
X1519271Y870606D03*
X1515570Y877014D03*
X1522970D03*
X1511871D03*
X1519271D03*
X1511871Y889832D03*
X1517421Y886627D03*
X1521121D03*
X1513721D03*
X1526671Y889832D03*
X1524821Y912262D03*
X1511871Y909057D03*
Y902649D03*
X1524821Y905853D03*
X1513721D03*
X1511871Y928283D03*
Y921875D03*
X1524820Y925079D03*
X1513720D03*
X1524820Y931488D03*
X1511871Y941100D03*
X1524820Y944304D03*
X1513720D03*
X1511871Y947509D03*
X1525420Y949619D03*
X1525861Y962436D03*
X1511871Y960326D03*
Y966735D03*
X1524288Y965640D03*
X1513721Y963530D03*
Y982756D03*
X1517421Y969939D03*
X1515571Y973143D03*
X1519871Y984866D03*
X1512303Y999684D03*
X1525396Y1000648D03*
X1512303Y1012501D03*
X1517854Y1015705D03*
X1525254D03*
X1521554D03*
X1514154D03*
X1512303Y1018910D03*
Y1031727D03*
X1525254Y1034931D03*
X1521554D03*
X1517853D03*
X1514153D03*
X1512303Y1038136D03*
X1517853Y1054157D03*
X1514153D03*
X1512303Y1057361D03*
X1521553Y1054157D03*
X1512303Y1050952D03*
X1525564Y1064850D03*
X1523404Y1070178D03*
X1521553Y1066974D03*
X1512303Y1076587D03*
X1512304Y1070178D03*
X1514153Y1073383D03*
X1523404Y1082996D03*
X1514153Y1092608D03*
X1512303Y1089404D03*
X1521553Y1092608D03*
X1523403Y1095813D03*
X1519703D03*
X1512303D03*
X1521554Y1105426D03*
X1517853D03*
X1516003Y1108630D03*
Y1102221D03*
X1512303D03*
X1517853Y1111834D03*
X1521553D03*
X1514153Y1105426D03*
X1512303Y1108630D03*
X1514153Y1111834D03*
X1519703Y1108630D03*
X1521553Y1124651D03*
Y1118243D03*
X1519704Y1115039D03*
X1516004D03*
X1514153Y1124651D03*
X1512303Y1115039D03*
X1517853Y1118243D03*
X1519703Y1121446D03*
X1516003Y1127855D03*
X1512303D03*
Y1121446D03*
X1516003D03*
X1517853Y1124650D03*
X1519703Y1127855D03*
X1517854Y1131560D03*
X1512304Y1134264D03*
X1514154Y1131059D03*
X1521817Y1580678D03*
Y1575686D03*
X1514713D03*
Y1580678D03*
X1525995Y1578182D03*
X1513935D03*
X1522595D03*
X1510535D03*
X1520013Y1599884D03*
X1515057D03*
X1521817Y1592590D03*
Y1587598D03*
X1514713D03*
Y1592590D03*
X1525995Y1590094D03*
X1513935D03*
X1522595D03*
X1510535D03*
X1520013Y1604876D03*
X1515057D03*
X1520013Y1611796D03*
X1515057D03*
Y1616788D03*
X1520013D03*
X1515835Y1614292D03*
X1519235D03*
X1515835Y1602380D03*
X1519235D03*
X1521063Y1675383D03*
Y1679920D03*
X1513189Y1679320D03*
X1521063Y1684454D03*
Y1689556D03*
Y1694093D03*
Y1698627D03*
X1513189Y1688391D03*
Y1693493D03*
Y1698030D03*
Y1683857D03*
X1521063Y1703729D03*
Y1708266D03*
Y1712800D03*
X1513189Y1707666D03*
Y1712203D03*
Y1702564D03*
X1521063Y1726974D03*
Y1722440D03*
Y1717903D03*
X1513189Y1730911D03*
Y1726377D03*
Y1721840D03*
Y1716737D03*
X1527571Y979057D03*
X1526843Y972608D03*
X1527103Y1031726D03*
X1533877Y1575592D03*
X1538833D03*
X1533877Y1580678D03*
X1538833D03*
X1526773D03*
Y1575686D03*
X1538055Y1578182D03*
X1534655D03*
X1539177Y1599790D03*
X1527117Y1599884D03*
X1532073D03*
X1533877Y1587598D03*
X1538833D03*
X1533877Y1592590D03*
X1538833D03*
X1526773D03*
Y1587598D03*
X1538055Y1590094D03*
X1534655D03*
X1539177Y1611796D03*
Y1604876D03*
Y1616788D03*
X1527117D03*
Y1604876D03*
Y1611796D03*
X1532073Y1616788D03*
Y1604876D03*
Y1611796D03*
X1527895Y1614292D03*
X1539955D03*
X1531295D03*
X1527895Y1602380D03*
X1539955D03*
X1531295D03*
X1536811Y1675383D03*
Y1679920D03*
X1528937Y1679320D03*
X1536811Y1684454D03*
Y1689556D03*
Y1694093D03*
Y1698627D03*
X1528937Y1688391D03*
Y1693493D03*
Y1698030D03*
Y1683857D03*
X1536811Y1703729D03*
Y1708266D03*
Y1712800D03*
X1528937Y1707666D03*
Y1712203D03*
Y1702564D03*
X1536811Y1726974D03*
Y1722440D03*
Y1717903D03*
X1528937Y1730911D03*
Y1726377D03*
Y1721840D03*
Y1716737D03*
X1557997Y1575686D03*
Y1580678D03*
X1550893D03*
X1545937D03*
X1550893Y1575686D03*
X1545937D03*
X1550115Y1578182D03*
X1558775D03*
X1546715D03*
X1556193Y1599884D03*
X1551237D03*
X1544133Y1599790D03*
X1557997Y1587598D03*
Y1592590D03*
X1545937D03*
X1550893D03*
Y1587598D03*
X1545937D03*
X1550115Y1590094D03*
X1558775D03*
X1546715D03*
X1551237Y1616788D03*
X1556193D03*
Y1604876D03*
X1551237D03*
X1556193Y1611796D03*
X1551237D03*
X1544133Y1604876D03*
Y1611796D03*
Y1616788D03*
X1552015Y1614292D03*
X1555415D03*
X1543355D03*
X1552015Y1602380D03*
X1555415D03*
X1543355D03*
X1552559Y1675383D03*
Y1679920D03*
X1544685Y1679320D03*
X1552559Y1684454D03*
Y1689556D03*
Y1694093D03*
Y1698627D03*
X1544685Y1688391D03*
Y1693493D03*
Y1698030D03*
Y1683857D03*
X1552559Y1703729D03*
Y1708266D03*
Y1712800D03*
X1544685Y1707666D03*
Y1712203D03*
Y1702564D03*
X1552559Y1726974D03*
Y1722440D03*
Y1717903D03*
X1544685Y1730911D03*
Y1726377D03*
Y1721840D03*
Y1716737D03*
X1570057Y1580678D03*
X1575013D03*
X1570057Y1575686D03*
X1575013D03*
X1562953D03*
Y1580678D03*
X1574235Y1578182D03*
X1562175D03*
X1570835D03*
X1575357Y1599884D03*
X1563297D03*
X1568253D03*
X1570057Y1592590D03*
X1575013D03*
X1570057Y1587598D03*
X1575013D03*
X1562953D03*
Y1592590D03*
X1574235Y1590094D03*
X1562175D03*
X1570835D03*
X1575357Y1616788D03*
Y1604876D03*
Y1611796D03*
X1563297Y1604876D03*
Y1611796D03*
X1568253Y1604876D03*
Y1611796D03*
X1563297Y1616788D03*
X1568253D03*
X1564075Y1614292D03*
X1567475D03*
X1564075Y1602380D03*
X1567475D03*
X1560433Y1679320D03*
X1572244Y1675383D03*
Y1679920D03*
X1560433Y1688391D03*
Y1693493D03*
Y1698030D03*
Y1683857D03*
X1572244Y1684454D03*
Y1689556D03*
Y1694093D03*
Y1698627D03*
X1560433Y1707666D03*
Y1712203D03*
Y1702564D03*
X1572244Y1703729D03*
Y1708266D03*
Y1712800D03*
X1560433Y1730911D03*
Y1726377D03*
Y1721840D03*
Y1716737D03*
X1572244Y1726974D03*
Y1722440D03*
Y1717903D03*
X1582117Y1575686D03*
X1587073D03*
X1582117Y1580678D03*
X1587073D03*
X1586295Y1578182D03*
X1582895D03*
X1587417Y1599884D03*
X1580313D03*
X1582117Y1587598D03*
X1587073D03*
X1582117Y1592590D03*
X1587073D03*
X1586295Y1590094D03*
X1582895D03*
X1587417Y1604876D03*
Y1611796D03*
Y1616788D03*
X1580313D03*
Y1604876D03*
Y1611796D03*
X1588195Y1614292D03*
X1576135D03*
X1591595D03*
X1579535D03*
X1588195Y1602380D03*
X1576135D03*
X1591595D03*
X1579535D03*
X1587992Y1675383D03*
Y1679920D03*
X1580118Y1679320D03*
X1587992Y1684454D03*
Y1689556D03*
Y1694093D03*
Y1698627D03*
X1580118Y1688391D03*
Y1693493D03*
Y1698030D03*
Y1683857D03*
X1587992Y1703729D03*
Y1708266D03*
Y1712800D03*
X1580118Y1707666D03*
Y1712203D03*
Y1702564D03*
X1587992Y1726974D03*
Y1722440D03*
Y1717903D03*
X1580118Y1730911D03*
Y1726377D03*
Y1721840D03*
Y1716737D03*
X1597041Y770144D03*
X1605741D03*
X1605800Y766478D03*
X1605741Y776837D03*
X1597041D03*
X1605741Y783530D03*
X1597041D03*
X1605741Y793570D03*
X1597041D03*
X1596988Y800263D03*
X1605741D03*
X1595774Y806955D03*
X1606934D03*
X1596218Y813648D03*
X1606735D03*
X1597041Y820341D03*
X1605741D03*
X1597041Y830381D03*
X1605741D03*
Y837074D03*
X1597041D03*
Y843766D03*
X1605741D03*
X1596147Y850459D03*
X1606896D03*
X1596200Y857152D03*
X1606623D03*
X1597041Y867192D03*
X1605741D03*
X1597041Y873885D03*
X1605741D03*
X1597041Y880577D03*
X1605741D03*
X1596941Y883924D03*
X1597041Y887270D03*
X1605741D03*
X1606898Y893963D03*
X1597041D03*
X1596941Y890617D03*
Y897310D03*
Y900656D03*
X1605741Y904003D03*
X1597041D03*
Y917389D03*
X1605741D03*
X1597041Y910696D03*
X1605741D03*
X1596941Y914042D03*
Y907349D03*
X1597041Y924081D03*
X1605741D03*
X1606541Y930697D03*
X1596047Y930774D03*
X1596106Y940814D03*
X1606919D03*
X1605741Y947507D03*
X1597041D03*
X1605741Y954200D03*
X1597041D03*
Y964239D03*
X1605741D03*
X1596941Y960892D03*
Y957546D03*
X1597041Y977625D03*
X1605741D03*
Y970932D03*
X1597041D03*
Y984318D03*
X1605741D03*
X1597041Y991011D03*
X1605741D03*
X1601922Y1000198D03*
X1599489Y999665D03*
X1597041Y1024475D03*
X1605741D03*
X1597041Y1017782D03*
X1605741D03*
X1597041Y1031168D03*
X1605741D03*
X1597041Y1037861D03*
X1605741D03*
X1597041Y1044554D03*
X1605741D03*
Y1051247D03*
X1597041D03*
Y1057940D03*
X1605741D03*
X1597041Y1061286D03*
Y1064633D03*
X1605741D03*
X1606541Y1071326D03*
X1596141D03*
X1597041Y1078018D03*
X1605741D03*
Y1094751D03*
X1597041D03*
Y1088058D03*
X1605741D03*
Y1101444D03*
X1597041D03*
Y1108137D03*
X1605741D03*
X1606541Y1114829D03*
X1596241D03*
X1596511Y1124969D03*
X1606505Y1124674D03*
X1605741Y1138255D03*
X1597041D03*
X1605741Y1144948D03*
X1597041D03*
Y1131562D03*
X1605741D03*
Y1151641D03*
X1597041D03*
X1596653Y1161680D03*
X1605975Y1161581D03*
X1605741Y1168373D03*
X1597041D03*
X1605741Y1175066D03*
X1597041D03*
X1605741Y1181759D03*
X1597041D03*
X1606765Y1188452D03*
X1597041D03*
X1596941Y1185105D03*
Y1178412D03*
Y1191798D03*
X1597041Y1198491D03*
X1605741D03*
Y1205184D03*
X1597041D03*
X1596941Y1208530D03*
Y1201837D03*
Y1195144D03*
X1597041Y1211877D03*
X1605741D03*
X1597041Y1218570D03*
X1605741D03*
X1597041Y1225263D03*
X1605741D03*
X1607064Y1235302D03*
X1596178D03*
X1605741Y1241995D03*
X1597041D03*
Y1248688D03*
X1605741D03*
X1606481Y1258649D03*
X1608000Y1261662D03*
X1603788Y1273144D03*
X1601388D03*
X1607897Y1264445D03*
X1606237Y1575686D03*
Y1580678D03*
X1594177D03*
X1599133D03*
X1594177Y1575686D03*
X1599133D03*
X1598355Y1578182D03*
X1607015D03*
X1594955D03*
X1599477Y1599884D03*
X1604433D03*
X1592373D03*
X1606237Y1587598D03*
Y1592590D03*
X1594177D03*
X1599133D03*
X1594177Y1587598D03*
X1599133D03*
X1598355Y1590094D03*
X1607015D03*
X1594955D03*
X1599477Y1616788D03*
X1604433D03*
X1599477Y1604876D03*
Y1611796D03*
X1604433Y1604876D03*
Y1611796D03*
X1592373Y1604876D03*
Y1611796D03*
Y1616788D03*
X1600255Y1614292D03*
X1603655D03*
X1600255Y1602380D03*
X1603655D03*
X1603740Y1675383D03*
Y1679920D03*
X1595866Y1679320D03*
X1603740Y1684454D03*
Y1689556D03*
Y1694093D03*
Y1698627D03*
X1595866Y1688391D03*
Y1693493D03*
Y1698030D03*
Y1683857D03*
X1603740Y1703729D03*
Y1708266D03*
Y1712800D03*
X1595866Y1707666D03*
Y1712203D03*
Y1702564D03*
X1603740Y1726974D03*
Y1722440D03*
Y1717903D03*
X1595866Y1730911D03*
Y1726377D03*
Y1721840D03*
Y1716737D03*
X1613183Y766798D03*
X1621883D03*
Y773491D03*
X1613183D03*
X1621883Y780184D03*
X1613183D03*
X1621883Y790223D03*
X1613183D03*
Y796916D03*
X1621883D03*
X1613183Y803609D03*
X1621883D03*
X1622916Y816995D03*
X1613183D03*
X1612363Y810302D03*
X1622986D03*
X1613183Y827034D03*
X1621883D03*
Y833727D03*
X1613183D03*
Y840420D03*
X1621883D03*
X1613183Y847113D03*
X1621943D03*
X1622060Y863845D03*
X1612408D03*
X1612474Y853955D03*
X1622961Y853806D03*
X1621883Y883924D03*
X1613183D03*
Y870538D03*
X1621883D03*
X1613183Y877231D03*
X1621883D03*
X1613083Y880577D03*
X1613183Y890617D03*
X1621883D03*
X1613183Y900656D03*
X1621883D03*
X1613083Y887270D03*
Y897310D03*
Y893963D03*
X1621883Y907349D03*
X1613183D03*
Y914042D03*
X1621883D03*
X1613083Y910696D03*
Y904003D03*
X1621883Y920735D03*
X1613183D03*
X1622535Y927526D03*
X1612168Y927428D03*
X1622845Y937467D03*
X1612312D03*
X1621883Y944160D03*
X1613183D03*
X1621883Y950853D03*
X1613183D03*
X1621883Y960892D03*
X1613183D03*
X1613083Y957546D03*
Y954200D03*
X1613183Y974278D03*
X1621883D03*
X1613183Y980971D03*
X1621883D03*
X1613183Y967585D03*
X1621883D03*
X1613183Y987664D03*
X1621883D03*
X1616609Y1000735D03*
X1616469Y1003135D03*
X1623539Y1000135D03*
X1620489Y1003135D03*
X1623589Y1002865D03*
X1620399Y1000325D03*
X1621883Y1017782D03*
X1613183D03*
Y1027822D03*
X1621883D03*
X1613183Y1034515D03*
X1621883D03*
X1613183Y1041207D03*
X1621883D03*
X1613183Y1047900D03*
X1621883D03*
Y1054593D03*
X1613183D03*
Y1061286D03*
X1621883D03*
Y1067979D03*
X1612983D03*
X1612283Y1074672D03*
X1622683D03*
X1621883Y1084711D03*
X1612383D03*
X1613183Y1091404D03*
X1621883D03*
Y1104790D03*
X1613183D03*
X1621883Y1098097D03*
X1613183D03*
X1621883Y1111483D03*
X1613183D03*
Y1128915D03*
X1621883Y1128215D03*
X1613183Y1121522D03*
X1621883D03*
Y1141601D03*
X1613183D03*
X1622726Y1135108D03*
X1611886Y1134908D03*
X1621883Y1158333D03*
X1613183D03*
X1621883Y1148294D03*
X1613183D03*
X1621883Y1165026D03*
X1613183D03*
Y1171719D03*
X1621883D03*
X1613083Y1175066D03*
X1621883Y1178412D03*
X1613183D03*
X1621883Y1185105D03*
X1613183D03*
X1613083Y1181759D03*
Y1191798D03*
Y1188451D03*
X1613183Y1195144D03*
X1621883D03*
Y1201837D03*
X1613183D03*
X1621883Y1208530D03*
X1613183D03*
X1613083Y1205184D03*
Y1198491D03*
X1621883Y1215223D03*
X1613183D03*
X1612147Y1221916D03*
X1622712D03*
X1612137Y1231862D03*
X1622681Y1231955D03*
X1621883Y1238648D03*
X1613183D03*
X1610150Y1257172D03*
X1621883Y1245341D03*
X1613183D03*
X1611475Y1259227D03*
X1621983Y1258727D03*
X1624600Y1262074D03*
X1613183Y1252034D03*
X1613027Y1248805D03*
X1609056Y1250602D03*
X1623930Y1252242D03*
X1618888Y1273344D03*
X1616088D03*
X1613019Y1261235D03*
X1618297Y1580678D03*
X1623253D03*
X1618297Y1575686D03*
X1623253D03*
X1611193D03*
Y1580678D03*
X1622475Y1578182D03*
X1610415D03*
X1619075D03*
X1623597Y1599884D03*
X1611537D03*
X1616493D03*
X1618297Y1592590D03*
X1623253D03*
X1618297Y1587598D03*
X1623253D03*
X1611193D03*
Y1592590D03*
X1622475Y1590094D03*
X1610415D03*
X1619075D03*
X1623597Y1616788D03*
Y1604876D03*
Y1611796D03*
X1611537Y1604876D03*
Y1611796D03*
X1616493Y1604876D03*
Y1611796D03*
X1611537Y1616788D03*
X1616493D03*
X1612315Y1614292D03*
X1615715D03*
X1612315Y1602380D03*
X1615715D03*
X1619488Y1675383D03*
Y1679920D03*
X1611614Y1679320D03*
X1619488Y1684454D03*
Y1689556D03*
Y1694093D03*
Y1698627D03*
X1611614Y1688391D03*
Y1693493D03*
Y1698030D03*
Y1683857D03*
X1619488Y1703729D03*
Y1708266D03*
Y1712800D03*
X1611614Y1707666D03*
Y1712203D03*
Y1702564D03*
X1619488Y1726974D03*
Y1722440D03*
Y1717903D03*
X1611614Y1730911D03*
Y1726377D03*
Y1721840D03*
Y1716737D03*
X1626741Y770144D03*
X1635441D03*
X1626741Y766798D03*
Y776837D03*
X1635441D03*
X1626741Y783530D03*
X1635441D03*
X1626741Y793570D03*
X1635441D03*
Y800263D03*
X1626741D03*
X1636341Y820341D03*
X1626741D03*
X1636574Y813648D03*
X1626741D03*
X1635441Y806955D03*
X1626741D03*
X1635441Y830381D03*
X1626741D03*
X1635441Y837074D03*
X1626741D03*
Y843766D03*
X1635441D03*
Y850459D03*
X1626741D03*
X1625705Y867192D03*
X1636441D03*
X1635441Y857152D03*
X1626741D03*
Y880577D03*
X1635441D03*
Y873885D03*
X1626741D03*
Y887270D03*
X1635441D03*
X1626741Y893963D03*
X1635441D03*
X1626741Y904003D03*
X1635441D03*
Y910696D03*
X1626741D03*
X1635441Y917389D03*
X1626741D03*
X1636316Y930774D03*
X1625803D03*
X1636646Y924081D03*
X1626741D03*
X1635441Y940814D03*
X1626741D03*
X1635441Y947507D03*
X1626741D03*
X1635441Y954200D03*
X1626741D03*
Y964239D03*
X1635441D03*
X1626641Y960892D03*
Y957546D03*
X1635441Y977625D03*
X1626741D03*
X1635441Y970932D03*
X1626741D03*
X1635441Y984318D03*
X1626741D03*
Y991011D03*
X1635441D03*
X1626249Y1002825D03*
X1635441Y1024475D03*
X1626741D03*
X1635441Y1017782D03*
X1626741D03*
X1635441Y1031168D03*
X1626741D03*
X1635441Y1037861D03*
X1626741D03*
X1635441Y1044554D03*
X1626741D03*
Y1057940D03*
X1635441D03*
Y1051247D03*
X1626741D03*
X1635441Y1064633D03*
X1626741D03*
X1635441Y1071326D03*
X1626741D03*
X1636241Y1078018D03*
X1625941D03*
Y1088058D03*
X1636241D03*
X1635441Y1094751D03*
X1626741D03*
Y1101444D03*
X1635441D03*
X1626741Y1108137D03*
X1635441D03*
X1626074Y1124640D03*
X1636341Y1124869D03*
X1635441Y1114829D03*
X1626741D03*
X1635441Y1144948D03*
X1626741D03*
X1635441Y1138255D03*
X1626741D03*
X1635441Y1130762D03*
X1626741D03*
Y1161680D03*
X1635441D03*
Y1151641D03*
X1626741D03*
Y1168373D03*
X1635441D03*
X1626741Y1175066D03*
X1635441D03*
X1626741Y1181759D03*
X1635441D03*
X1626741Y1188452D03*
X1635441D03*
X1626741Y1198491D03*
X1635441D03*
X1626741Y1205184D03*
X1635441D03*
Y1211877D03*
X1626741D03*
X1635441Y1218570D03*
X1626741D03*
X1636212Y1225263D03*
X1626055D03*
X1636376Y1235302D03*
X1625843D03*
X1635441Y1241995D03*
X1626741D03*
X1635688Y1257664D03*
X1626741Y1248688D03*
X1635441D03*
X1626741Y1258727D03*
X1629788Y1273344D03*
X1632588D03*
X1625729Y1266766D03*
X1630357Y1575592D03*
X1635313D03*
X1630357Y1580678D03*
X1635313D03*
X1634535Y1578182D03*
X1631135D03*
X1640613Y1599790D03*
X1635657D03*
X1628553Y1599884D03*
X1630357Y1587598D03*
X1635313D03*
X1630357Y1592590D03*
X1635313D03*
X1634535Y1590094D03*
X1631135D03*
X1640613Y1604876D03*
Y1611796D03*
X1635657Y1604876D03*
Y1611796D03*
X1640613Y1616788D03*
X1635657D03*
X1628553D03*
Y1604876D03*
Y1611796D03*
X1636435Y1614292D03*
X1624375D03*
X1639835D03*
X1627775D03*
X1636435Y1602380D03*
X1624375D03*
X1639835D03*
X1627775D03*
X1627362Y1679320D03*
Y1688391D03*
Y1693493D03*
Y1698030D03*
Y1683857D03*
Y1707666D03*
Y1712203D03*
Y1702564D03*
Y1730911D03*
Y1726377D03*
Y1721840D03*
Y1716737D03*
X1651583Y766798D03*
X1642883D03*
X1656441Y770144D03*
Y766798D03*
Y776837D03*
X1642883Y773491D03*
X1651583D03*
X1642883Y780184D03*
X1651583D03*
X1656441Y783530D03*
Y780184D03*
Y773491D03*
Y786877D03*
Y793570D03*
X1642883Y790223D03*
X1651583D03*
X1642883Y796916D03*
X1651583D03*
X1656441Y800263D03*
X1651583Y803609D03*
X1642883D03*
X1656441D03*
Y796916D03*
Y790223D03*
Y806955D03*
Y813648D03*
Y820341D03*
X1651583Y810302D03*
X1642883D03*
X1652545Y816995D03*
X1641945D03*
X1656441D03*
Y810302D03*
Y830381D03*
X1652767Y827034D03*
X1642018D03*
X1651583Y833727D03*
X1642883D03*
X1656441D03*
Y823688D03*
Y827034D03*
Y837074D03*
Y843766D03*
X1642883Y840420D03*
X1651583D03*
X1656441Y850459D03*
X1651583Y847113D03*
X1642883D03*
X1656441D03*
Y840420D03*
X1642058Y863845D03*
X1652742D03*
X1656441Y857152D03*
Y867192D03*
X1652559Y853806D03*
X1642032D03*
X1656441D03*
Y860499D03*
Y863845D03*
Y873885D03*
Y880577D03*
X1642883Y883924D03*
X1651583D03*
Y870538D03*
X1642883D03*
X1651583Y877231D03*
X1642883D03*
X1656441Y883924D03*
Y877231D03*
Y870538D03*
Y887270D03*
Y893963D03*
X1642883Y890617D03*
X1651583D03*
X1642883Y900656D03*
X1651583D03*
X1656441Y890617D03*
Y897310D03*
Y900656D03*
Y904003D03*
Y910696D03*
X1642883Y907349D03*
X1651583D03*
X1656441Y917389D03*
X1651583Y914042D03*
X1642883D03*
X1656441D03*
Y907349D03*
Y924081D03*
Y930774D03*
X1652630Y927428D03*
X1642038D03*
X1651583Y920735D03*
X1642883D03*
X1656441Y927428D03*
Y920735D03*
Y934121D03*
Y940814D03*
Y947507D03*
X1652501Y937467D03*
X1642065D03*
X1651583Y944160D03*
X1642883D03*
X1656441D03*
Y937467D03*
Y954200D03*
X1642883Y950853D03*
X1651583D03*
Y960892D03*
X1642883D03*
X1656441Y964239D03*
Y960892D03*
Y950853D03*
Y957546D03*
X1642783D03*
Y954200D03*
X1656441Y977625D03*
Y970932D03*
X1651583Y967585D03*
X1642883D03*
X1651583Y974278D03*
X1642883D03*
X1651583Y980971D03*
X1642883D03*
X1656441D03*
Y974278D03*
Y967585D03*
Y984318D03*
Y991011D03*
X1651583Y987664D03*
X1642883D03*
X1656441Y994357D03*
Y987664D03*
X1648205Y998632D03*
X1651583Y1017782D03*
X1642883D03*
X1656441D03*
Y1024475D03*
X1651583Y1027822D03*
X1642883D03*
X1656441Y1031168D03*
X1656141Y1027822D03*
X1656441Y1021129D03*
Y1044554D03*
Y1037861D03*
X1651583Y1034515D03*
X1642883D03*
X1651583Y1041207D03*
X1642883D03*
X1651583Y1047900D03*
X1642883D03*
X1656141D03*
Y1041207D03*
Y1034514D03*
X1642883Y1061286D03*
X1651583D03*
X1656441Y1051247D03*
Y1057940D03*
X1651583Y1054593D03*
X1642883D03*
X1656441Y1061286D03*
X1656141Y1054593D03*
X1656441Y1064633D03*
Y1071326D03*
Y1078018D03*
X1652483Y1074672D03*
X1641983D03*
X1651583Y1067979D03*
X1642883D03*
X1656441Y1074672D03*
Y1067979D03*
Y1088058D03*
Y1094751D03*
X1652383Y1084711D03*
X1642083D03*
X1651583Y1091404D03*
X1642883D03*
X1656441D03*
Y1081365D03*
Y1084711D03*
Y1101444D03*
Y1108137D03*
X1642883Y1098097D03*
X1651583D03*
X1642883Y1104790D03*
X1651583D03*
X1642883Y1111483D03*
X1651583D03*
X1656441Y1098097D03*
Y1111483D03*
Y1104790D03*
Y1114829D03*
Y1124869D03*
X1642883Y1121522D03*
X1651583D03*
X1642883Y1128215D03*
X1651583D03*
X1656441D03*
Y1118176D03*
Y1121522D03*
Y1131562D03*
Y1138255D03*
X1642883Y1134908D03*
X1651583D03*
X1642883Y1141601D03*
X1651583D03*
X1656441Y1144948D03*
Y1141601D03*
Y1134908D03*
Y1151641D03*
Y1161680D03*
X1652383Y1158333D03*
X1642083D03*
X1652794Y1148294D03*
X1641744D03*
X1656441D03*
Y1154987D03*
Y1158333D03*
Y1168373D03*
Y1175066D03*
X1642883Y1171719D03*
X1651583D03*
Y1165026D03*
X1642883D03*
X1656441Y1171719D03*
Y1165026D03*
Y1181759D03*
Y1188452D03*
X1651583Y1178412D03*
X1642883D03*
X1651583Y1185105D03*
X1642883D03*
X1656441D03*
Y1178412D03*
Y1191798D03*
Y1198491D03*
Y1205184D03*
X1642883Y1195144D03*
X1651583D03*
X1642883Y1201837D03*
X1651583D03*
X1642883Y1208530D03*
X1651583D03*
X1656441D03*
Y1201837D03*
Y1195144D03*
Y1211877D03*
X1652590Y1221916D03*
X1641793D03*
X1656441Y1225263D03*
Y1218570D03*
X1651583Y1215223D03*
X1642883D03*
X1656441Y1221916D03*
Y1215223D03*
Y1235302D03*
Y1241995D03*
X1652604Y1231955D03*
X1642054D03*
X1651583Y1238648D03*
X1642883D03*
X1656441D03*
Y1228609D03*
Y1231955D03*
Y1248688D03*
X1651583Y1245341D03*
X1642883D03*
X1656441D03*
X1642883Y1255381D03*
Y1258727D03*
Y1252034D03*
X1651679Y1248885D03*
X1653140Y1257862D03*
X1648588Y1273344D03*
X1645788D03*
X1656188Y1264964D03*
X1642788Y1264464D03*
X1642883Y1262074D03*
X1656170Y1260352D03*
X1654600Y1262742D03*
X1647373Y1580678D03*
X1642417D03*
X1647373Y1575686D03*
X1642417D03*
X1646595Y1578182D03*
X1643195D03*
X1647717Y1599884D03*
X1652673D03*
X1647373Y1592590D03*
X1642417D03*
X1647373Y1587598D03*
X1642417D03*
X1646595Y1590094D03*
X1643195D03*
X1647717Y1616788D03*
X1652673D03*
X1647717Y1604876D03*
Y1611796D03*
X1652673Y1604876D03*
Y1611796D03*
X1651895Y1614292D03*
X1648495D03*
X1651895Y1602380D03*
X1648495D03*
X1665141Y770144D03*
X1672583Y766798D03*
Y770144D03*
X1665141Y776837D03*
Y783530D03*
X1672583Y773491D03*
Y780184D03*
Y776837D03*
Y786877D03*
Y783530D03*
X1665141Y793570D03*
Y800263D03*
X1672583Y790223D03*
Y796916D03*
Y803609D03*
Y800263D03*
Y793570D03*
X1665141Y806955D03*
Y813648D03*
X1666030Y820341D03*
X1672583Y810302D03*
Y816995D03*
Y813648D03*
Y806955D03*
Y820341D03*
X1665141Y830381D03*
X1672583Y827034D03*
Y833727D03*
Y830381D03*
Y823688D03*
X1665141Y837074D03*
Y843766D03*
X1672583Y840420D03*
X1665141Y850459D03*
X1672583Y847113D03*
Y850459D03*
Y843766D03*
Y837074D03*
X1666038Y857152D03*
X1665141Y867192D03*
X1672583Y853806D03*
Y863845D03*
Y867192D03*
Y860499D03*
Y857152D03*
X1665141Y873885D03*
Y880577D03*
X1672583Y870538D03*
Y877231D03*
Y883924D03*
Y873885D03*
Y880577D03*
X1665141Y887270D03*
Y893963D03*
X1672583Y890617D03*
Y900656D03*
Y887270D03*
Y897310D03*
Y893963D03*
X1665141Y904003D03*
Y910696D03*
Y917389D03*
X1672583Y907349D03*
Y914042D03*
Y917389D03*
Y910696D03*
Y904003D03*
X1665141Y924081D03*
X1666246Y930774D03*
X1672583Y920735D03*
Y927428D03*
Y924081D03*
Y934121D03*
Y930774D03*
X1665141Y940814D03*
Y947507D03*
X1672583Y937467D03*
Y944160D03*
Y947507D03*
Y940814D03*
X1665141Y954200D03*
Y964239D03*
X1672583Y950853D03*
Y960892D03*
Y964239D03*
Y957546D03*
Y954200D03*
X1665141Y977625D03*
Y970932D03*
X1672583Y967585D03*
Y974278D03*
Y980971D03*
Y977625D03*
Y970932D03*
X1665141Y984318D03*
Y991011D03*
X1672583Y987664D03*
Y991011D03*
Y984318D03*
Y994357D03*
X1665141Y1017782D03*
Y1024475D03*
Y1031168D03*
X1672583Y1017782D03*
Y1027822D03*
Y1021129D03*
Y1024475D03*
Y1031168D03*
X1665141Y1044554D03*
Y1037861D03*
X1672583Y1034515D03*
Y1041207D03*
Y1047900D03*
X1672283Y1044554D03*
Y1037861D03*
X1665141Y1051247D03*
Y1057940D03*
X1672583Y1061286D03*
Y1054593D03*
Y1051247D03*
X1665141Y1064633D03*
Y1071326D03*
Y1077118D03*
X1672583Y1067979D03*
Y1074672D03*
Y1071325D03*
Y1064633D03*
Y1078018D03*
X1665141Y1088058D03*
Y1094751D03*
X1672583Y1084711D03*
Y1091404D03*
Y1094751D03*
Y1088058D03*
Y1081365D03*
X1665141Y1101444D03*
Y1108137D03*
X1672583Y1098097D03*
Y1104790D03*
Y1111483D03*
Y1108136D03*
Y1101444D03*
X1665141Y1114829D03*
Y1124869D03*
X1672583Y1121522D03*
Y1128215D03*
Y1124869D03*
Y1118176D03*
Y1114829D03*
X1665141Y1131562D03*
Y1138255D03*
Y1144948D03*
X1672583Y1134908D03*
Y1141601D03*
Y1144947D03*
Y1138255D03*
Y1131562D03*
X1666141Y1151641D03*
X1665141Y1161680D03*
X1672583Y1148294D03*
Y1158333D03*
Y1161680D03*
Y1154987D03*
Y1151640D03*
X1665141Y1168373D03*
Y1175066D03*
X1672583Y1165026D03*
Y1171719D03*
Y1175066D03*
Y1168373D03*
X1665141Y1181759D03*
Y1188452D03*
X1672583Y1178412D03*
Y1185105D03*
Y1181758D03*
Y1191798D03*
Y1188451D03*
X1665141Y1198491D03*
Y1205184D03*
X1672583Y1195144D03*
Y1201837D03*
Y1208530D03*
Y1205184D03*
Y1198491D03*
X1665141Y1211877D03*
X1665941Y1225263D03*
X1665141Y1218570D03*
X1672583Y1215223D03*
Y1221916D03*
Y1218569D03*
Y1211877D03*
Y1225262D03*
X1665141Y1235302D03*
Y1241995D03*
X1672583Y1231955D03*
Y1238648D03*
Y1241995D03*
Y1235302D03*
Y1228609D03*
X1665141Y1248688D03*
X1672583Y1245341D03*
X1665688Y1257964D03*
X1672583Y1255381D03*
Y1258727D03*
Y1248688D03*
X1659488Y1273344D03*
X1662288D03*
X1672188Y1263764D03*
X1681283Y766798D03*
X1686141Y770144D03*
X1686041Y766798D03*
X1681283Y773491D03*
Y780184D03*
X1686141Y776837D03*
Y783530D03*
X1681283Y790223D03*
Y796916D03*
Y803609D03*
X1686141Y793570D03*
Y800263D03*
X1681283Y810302D03*
Y816995D03*
X1686141Y806955D03*
Y813648D03*
Y820341D03*
X1681283Y827034D03*
Y833727D03*
X1686141Y830381D03*
X1681283Y840420D03*
X1686141Y837074D03*
Y843766D03*
Y850459D03*
X1681283Y847113D03*
X1686141Y857152D03*
Y867192D03*
X1681283Y853806D03*
Y863845D03*
X1686141Y873885D03*
Y880577D03*
X1681283Y870538D03*
Y877231D03*
Y883924D03*
X1686141Y887270D03*
Y893963D03*
X1681283Y890617D03*
Y900656D03*
X1686141Y904003D03*
Y910696D03*
Y917389D03*
X1681283Y907349D03*
Y914042D03*
X1686141Y924081D03*
Y930774D03*
X1681283Y920735D03*
Y927428D03*
X1686141Y940814D03*
Y947507D03*
X1681283Y937467D03*
Y944160D03*
X1686141Y954200D03*
Y964239D03*
X1681283Y950853D03*
Y960892D03*
X1686041D03*
Y957546D03*
X1686141Y970932D03*
Y977625D03*
X1681283Y967585D03*
Y974278D03*
Y980971D03*
X1686141Y967585D03*
Y984318D03*
Y991011D03*
X1681283Y987664D03*
X1686141Y1017782D03*
Y1024475D03*
Y1031168D03*
X1681283Y1017782D03*
Y1027822D03*
X1686141Y1037861D03*
Y1044554D03*
X1681283Y1034515D03*
Y1041207D03*
Y1047900D03*
X1686141Y1051247D03*
Y1057940D03*
X1681283Y1061286D03*
Y1054593D03*
X1686141D03*
Y1064633D03*
Y1071326D03*
Y1078018D03*
X1681283Y1067979D03*
Y1074672D03*
X1686141Y1088058D03*
Y1094751D03*
X1681283Y1084711D03*
Y1091404D03*
X1686141Y1101444D03*
Y1108137D03*
X1681283Y1098097D03*
Y1104790D03*
Y1111483D03*
X1686141Y1114829D03*
Y1124869D03*
X1681283Y1121522D03*
Y1128215D03*
X1686141Y1131562D03*
Y1138255D03*
Y1144948D03*
X1681283Y1134908D03*
Y1141601D03*
X1686141Y1151641D03*
Y1161680D03*
X1681283Y1148294D03*
Y1158333D03*
X1686141Y1168373D03*
Y1175066D03*
X1681283Y1165026D03*
Y1171719D03*
X1686141Y1181759D03*
Y1188452D03*
X1681283Y1178412D03*
Y1185105D03*
X1686141Y1198491D03*
Y1205184D03*
X1681283Y1195144D03*
Y1201837D03*
Y1208530D03*
X1686141Y1211877D03*
Y1218570D03*
Y1225263D03*
X1681283Y1215223D03*
Y1221916D03*
Y1231955D03*
Y1238648D03*
X1686141Y1235302D03*
Y1241995D03*
X1681283Y1245341D03*
X1686141Y1248688D03*
Y1258727D03*
X1681179Y1252034D03*
X1683578Y1253780D03*
X1675488Y1273344D03*
X1678288D03*
X1689188D03*
X1686119Y1264985D03*
X1681309Y1262074D03*
X1683500Y1264312D03*
X1694841Y770144D03*
X1702283Y766798D03*
X1694841Y776837D03*
Y783530D03*
X1702283Y773491D03*
Y780184D03*
X1694841Y793570D03*
Y800263D03*
X1702283Y790223D03*
Y796916D03*
Y803609D03*
X1694841Y806955D03*
Y813648D03*
Y820341D03*
X1702283Y810302D03*
Y816995D03*
X1694841Y830381D03*
X1702283Y827034D03*
Y833727D03*
X1694841Y837074D03*
Y843766D03*
Y850459D03*
X1702283Y840420D03*
Y847113D03*
X1694841Y857152D03*
Y867192D03*
X1702283Y853806D03*
Y863845D03*
X1694841Y873885D03*
Y880577D03*
X1702283Y870538D03*
Y877231D03*
Y883924D03*
X1694841Y887270D03*
Y893963D03*
X1702283Y890617D03*
Y900656D03*
X1694841Y904003D03*
Y910696D03*
Y917389D03*
X1702283Y907349D03*
Y914042D03*
X1694841Y924081D03*
Y930774D03*
X1702283Y920735D03*
Y927428D03*
X1694841Y940814D03*
Y947507D03*
X1702283Y937467D03*
Y944160D03*
X1694841Y954200D03*
Y964239D03*
X1702283Y950853D03*
Y960892D03*
Y964239D03*
X1702183Y957546D03*
Y954200D03*
X1694841Y970932D03*
Y977625D03*
X1702283Y967585D03*
Y974278D03*
Y980971D03*
X1694841Y984318D03*
Y991011D03*
X1702283Y987664D03*
X1702183Y994357D03*
X1694841Y1017782D03*
Y1024475D03*
Y1031168D03*
X1702283Y1017782D03*
Y1027822D03*
Y1021129D03*
Y1024475D03*
X1694841Y1037861D03*
Y1044554D03*
X1702283Y1034515D03*
Y1041207D03*
Y1047900D03*
X1694841Y1051247D03*
Y1057940D03*
X1702283Y1054593D03*
Y1061286D03*
Y1051247D03*
Y1057940D03*
X1694841Y1064633D03*
Y1071326D03*
Y1078018D03*
X1702283Y1067979D03*
Y1074672D03*
X1694841Y1088058D03*
Y1094751D03*
X1702283Y1084711D03*
Y1091404D03*
X1694841Y1101444D03*
Y1108137D03*
X1702283Y1098097D03*
Y1104790D03*
Y1111483D03*
X1694841Y1114829D03*
Y1124869D03*
X1702283Y1121522D03*
Y1128215D03*
X1694841Y1131562D03*
Y1138255D03*
Y1144948D03*
X1702283Y1134908D03*
Y1141601D03*
X1694841Y1151641D03*
Y1161680D03*
X1702283Y1148294D03*
Y1158333D03*
X1694841Y1168373D03*
Y1175066D03*
X1702283Y1165026D03*
Y1171719D03*
X1694841Y1181759D03*
Y1188452D03*
X1702283Y1178412D03*
Y1185105D03*
X1694841Y1198491D03*
Y1205184D03*
X1702283Y1195144D03*
Y1201837D03*
Y1208530D03*
X1694841Y1211877D03*
Y1218570D03*
Y1225263D03*
X1702283Y1215223D03*
Y1221916D03*
X1694841Y1235302D03*
Y1241995D03*
X1702283Y1231955D03*
Y1238648D03*
X1694841Y1248688D03*
X1695188Y1257064D03*
X1702283Y1245341D03*
X1699852Y1245418D03*
X1699089Y1258842D03*
X1702283Y1248688D03*
X1691988Y1273344D03*
X1705188D03*
X1702249Y1265420D03*
X1702283Y1262074D03*
X1699030Y1263912D03*
X1710983Y766798D03*
X1715841Y770144D03*
Y766798D03*
X1710983Y773491D03*
Y780184D03*
X1715841Y783530D03*
Y776837D03*
Y780184D03*
Y773491D03*
Y786877D03*
X1710983Y790223D03*
Y796916D03*
Y803609D03*
X1715841Y793570D03*
Y800263D03*
Y803609D03*
Y796916D03*
Y790223D03*
X1710983Y810302D03*
Y816995D03*
X1715841Y806955D03*
Y813648D03*
Y820341D03*
Y816995D03*
Y810302D03*
X1710983Y827034D03*
Y833727D03*
X1715841Y830381D03*
Y833727D03*
Y823688D03*
Y827034D03*
X1710983Y840420D03*
Y847113D03*
X1715841Y837074D03*
Y843766D03*
Y850459D03*
Y847113D03*
Y840420D03*
X1710983Y853806D03*
Y863845D03*
X1715841Y857152D03*
Y867192D03*
Y853806D03*
Y860499D03*
Y863845D03*
X1710983Y870538D03*
Y877231D03*
Y883924D03*
X1715841Y873885D03*
Y880577D03*
Y883924D03*
Y877231D03*
Y870538D03*
X1710983Y890617D03*
Y900656D03*
X1715841Y893963D03*
Y887270D03*
Y890617D03*
Y897310D03*
Y900656D03*
X1710983Y907349D03*
Y914042D03*
X1715841Y904003D03*
Y910696D03*
Y917389D03*
Y914042D03*
Y907349D03*
X1710983Y920735D03*
Y927428D03*
X1715841Y924081D03*
Y930774D03*
Y927428D03*
Y920735D03*
Y934121D03*
X1710983Y937467D03*
Y944160D03*
X1715841Y940814D03*
Y947507D03*
Y944160D03*
Y937467D03*
X1710983Y950853D03*
Y960892D03*
X1715841Y954200D03*
Y964239D03*
Y960892D03*
Y950853D03*
Y957546D03*
X1710983Y967585D03*
Y974278D03*
Y980971D03*
X1715841Y970932D03*
Y977625D03*
Y980971D03*
Y974278D03*
Y967585D03*
X1710983Y987664D03*
X1715841Y984318D03*
Y991011D03*
Y994357D03*
Y987664D03*
X1710983Y1017782D03*
Y1027822D03*
X1715841Y1017782D03*
Y1024475D03*
Y1031168D03*
Y1027822D03*
Y1021129D03*
X1710983Y1034515D03*
Y1041207D03*
Y1047900D03*
X1715841Y1037861D03*
Y1044554D03*
Y1047900D03*
Y1041207D03*
Y1034514D03*
X1710983Y1054593D03*
Y1061286D03*
X1715841Y1051247D03*
Y1057940D03*
Y1061286D03*
Y1054593D03*
X1710983Y1067979D03*
Y1074672D03*
X1715841Y1071326D03*
Y1064633D03*
Y1078018D03*
Y1074672D03*
Y1067979D03*
X1710983Y1084711D03*
Y1091404D03*
X1715841Y1088058D03*
Y1094751D03*
Y1091404D03*
Y1081365D03*
Y1084711D03*
X1710983Y1098097D03*
Y1104790D03*
Y1111483D03*
X1715841Y1101444D03*
Y1108137D03*
Y1098097D03*
Y1111483D03*
Y1104790D03*
X1710983Y1121522D03*
Y1128215D03*
X1715841Y1114829D03*
Y1124869D03*
Y1128215D03*
Y1118176D03*
Y1121522D03*
X1710983Y1134908D03*
Y1141601D03*
X1715841Y1131562D03*
Y1138255D03*
Y1144948D03*
Y1141601D03*
Y1134908D03*
X1710983Y1148294D03*
Y1158333D03*
X1715841Y1151641D03*
Y1161680D03*
Y1148294D03*
Y1154987D03*
Y1158333D03*
X1710983Y1165026D03*
Y1171719D03*
X1715841Y1168373D03*
Y1175066D03*
Y1171719D03*
Y1165026D03*
X1710983Y1178412D03*
Y1185105D03*
X1715841Y1181759D03*
Y1188452D03*
Y1185105D03*
Y1178412D03*
Y1191798D03*
X1710983Y1195144D03*
Y1201837D03*
Y1208530D03*
X1715841Y1198491D03*
Y1205184D03*
Y1208530D03*
Y1201837D03*
Y1195144D03*
X1710983Y1215223D03*
Y1221916D03*
X1715841Y1211877D03*
Y1218570D03*
Y1225263D03*
Y1221916D03*
Y1215223D03*
X1710983Y1231955D03*
Y1238648D03*
X1715841Y1235302D03*
Y1241995D03*
Y1238648D03*
Y1228609D03*
Y1231955D03*
X1710983Y1245341D03*
X1715841Y1248688D03*
Y1245341D03*
X1713620Y1258512D03*
X1711109Y1252034D03*
X1713930Y1262074D03*
X1714440Y1255381D03*
X1707514Y1273444D03*
X1718888Y1273344D03*
X1721688D03*
X1715839Y1265420D03*
X1737020Y112177D03*
Y109677D03*
X1731983Y766798D03*
X1724541Y770144D03*
X1731983D03*
Y773491D03*
Y780184D03*
X1724541Y783530D03*
Y776837D03*
X1731983D03*
Y786877D03*
Y783530D03*
X1724541Y793570D03*
Y800263D03*
X1731983Y790223D03*
Y796916D03*
Y803609D03*
Y800263D03*
Y793570D03*
X1724541Y806955D03*
Y813648D03*
Y820341D03*
X1731983Y810302D03*
Y816995D03*
Y813648D03*
Y806955D03*
Y820341D03*
X1724541Y830381D03*
X1731983Y827034D03*
Y833727D03*
Y830381D03*
Y823688D03*
X1724541Y837074D03*
Y843766D03*
Y850459D03*
X1731983Y840420D03*
Y847113D03*
Y850459D03*
Y843766D03*
Y837074D03*
X1724541Y857152D03*
Y867192D03*
X1731983Y853806D03*
Y863845D03*
Y867192D03*
Y860499D03*
Y857152D03*
X1724541Y873885D03*
Y880577D03*
X1731983Y870538D03*
Y877231D03*
Y883924D03*
Y873885D03*
Y880577D03*
X1724541Y893963D03*
Y887270D03*
X1731983Y890617D03*
Y900656D03*
Y887270D03*
Y897310D03*
Y893963D03*
X1724541Y904003D03*
Y910696D03*
Y917389D03*
X1731983Y907349D03*
Y914042D03*
Y917389D03*
Y910696D03*
Y904003D03*
X1724541Y924081D03*
Y930774D03*
X1731983Y920735D03*
Y927428D03*
Y924081D03*
Y934121D03*
Y930774D03*
X1724541Y940814D03*
Y947507D03*
X1731983Y937467D03*
Y944160D03*
Y947507D03*
Y940814D03*
X1724541Y954200D03*
Y964239D03*
X1731983Y950853D03*
Y960892D03*
Y964239D03*
Y957546D03*
Y954200D03*
X1724541Y970932D03*
Y977625D03*
X1731983Y967585D03*
Y974278D03*
Y980971D03*
Y977625D03*
X1731883Y970932D03*
X1724541Y984318D03*
Y991011D03*
X1731983Y987664D03*
Y991011D03*
Y984318D03*
Y994357D03*
X1724541Y1017782D03*
Y1024475D03*
Y1031168D03*
X1731983Y1017782D03*
Y1027822D03*
Y1021129D03*
Y1024475D03*
Y1031168D03*
X1724541Y1037861D03*
Y1044554D03*
X1731983Y1034515D03*
Y1041207D03*
Y1047900D03*
X1731683Y1044554D03*
Y1037861D03*
X1724541Y1051247D03*
Y1057940D03*
X1731983Y1054593D03*
Y1061286D03*
Y1051247D03*
X1731683Y1057940D03*
X1724541Y1071326D03*
Y1064633D03*
Y1078018D03*
X1731983Y1074672D03*
Y1067979D03*
X1731818Y1071326D03*
X1731883Y1064633D03*
X1731983Y1078018D03*
X1724541Y1088058D03*
Y1094751D03*
X1731983Y1084711D03*
Y1091404D03*
Y1094751D03*
Y1088058D03*
Y1081365D03*
X1724541Y1101444D03*
Y1108137D03*
X1731983Y1098097D03*
Y1104790D03*
Y1111483D03*
X1731818Y1108137D03*
X1731983Y1101444D03*
X1724541Y1114829D03*
Y1124869D03*
X1731983Y1121522D03*
Y1128215D03*
Y1124869D03*
Y1118176D03*
Y1114829D03*
X1724541Y1131562D03*
Y1138255D03*
Y1144948D03*
X1731983Y1134908D03*
Y1141601D03*
Y1144947D03*
Y1138255D03*
Y1131562D03*
X1724541Y1151641D03*
Y1161680D03*
X1731983Y1148294D03*
Y1158333D03*
Y1161680D03*
Y1154987D03*
Y1151640D03*
X1724541Y1168373D03*
Y1175066D03*
X1731983Y1165026D03*
Y1171719D03*
Y1175066D03*
Y1168373D03*
X1724541Y1181759D03*
Y1188452D03*
X1731983Y1178412D03*
Y1185105D03*
X1731818Y1181759D03*
X1731983Y1191798D03*
X1731818Y1188452D03*
X1724541Y1198491D03*
Y1205184D03*
X1731983Y1195144D03*
Y1201837D03*
Y1208530D03*
Y1205184D03*
Y1198491D03*
X1724541Y1211877D03*
Y1218570D03*
Y1225263D03*
X1731983Y1215223D03*
Y1221916D03*
Y1218569D03*
Y1211877D03*
Y1225262D03*
X1724541Y1235302D03*
Y1241995D03*
X1731983Y1231955D03*
Y1238648D03*
Y1241995D03*
Y1235302D03*
Y1228609D03*
X1724541Y1248688D03*
X1724588Y1257164D03*
X1731983Y1245341D03*
X1727041Y1248688D03*
X1731983Y1255381D03*
Y1258727D03*
Y1252034D03*
Y1248688D03*
X1734888Y1273344D03*
X1737688D03*
X1731939Y1265420D03*
X1731983Y1262074D03*
X1747650Y109677D03*
Y112177D03*
X1744106Y109677D03*
Y112177D03*
X1740563Y109677D03*
Y112177D03*
X1740683Y766798D03*
X1745541Y770144D03*
X1754241D03*
X1745541Y766798D03*
X1740683Y773491D03*
Y780184D03*
X1745541Y776837D03*
X1754241D03*
X1745541Y783530D03*
X1754241D03*
X1740683Y790223D03*
Y796916D03*
Y803609D03*
X1745541Y793570D03*
X1754241D03*
X1745541Y800263D03*
X1754241D03*
X1740683Y810302D03*
Y816995D03*
X1745541Y806955D03*
X1754241D03*
X1745541Y813648D03*
X1754241D03*
X1745541Y820341D03*
X1754241D03*
X1740683Y827034D03*
Y833727D03*
X1745541Y830381D03*
X1754241D03*
X1740683Y840420D03*
Y847113D03*
X1754241Y843766D03*
X1745541D03*
Y837074D03*
X1754241D03*
X1745541Y850459D03*
X1754241D03*
X1740683Y853806D03*
Y863845D03*
X1745541Y857152D03*
X1754241D03*
Y867192D03*
X1745541D03*
X1740683Y870538D03*
Y877231D03*
Y883924D03*
X1745541Y873885D03*
X1754241D03*
X1745541Y880577D03*
X1754241D03*
X1740683Y890617D03*
Y900656D03*
X1754241Y893963D03*
X1745541D03*
Y887270D03*
X1754241D03*
X1740683Y907349D03*
Y914042D03*
X1754241Y904003D03*
X1745541D03*
X1754241Y910696D03*
X1745541D03*
X1754241Y917389D03*
X1745541D03*
X1740683Y920735D03*
Y927428D03*
X1754241Y924081D03*
X1745541D03*
X1754241Y930774D03*
X1745541D03*
X1740683Y937467D03*
Y944160D03*
X1754241Y940814D03*
X1745541D03*
X1754241Y947507D03*
X1745541D03*
X1740683Y950853D03*
Y960892D03*
X1754241Y954200D03*
X1745541D03*
X1754241Y964239D03*
X1745541D03*
Y960892D03*
Y957546D03*
X1740683Y967585D03*
Y974278D03*
Y980971D03*
X1754241Y970932D03*
X1745541D03*
X1754241Y977625D03*
X1745541D03*
Y967585D03*
X1740683Y987664D03*
X1754241Y984318D03*
X1745541D03*
X1754241Y991011D03*
X1745541D03*
X1740683Y1017782D03*
Y1027822D03*
X1754241Y1017782D03*
X1745541D03*
Y1024475D03*
X1754241D03*
X1745541Y1031168D03*
X1754241D03*
X1740683Y1034515D03*
Y1041207D03*
Y1047900D03*
X1754241Y1044554D03*
X1745541D03*
Y1037861D03*
X1754241D03*
X1740683Y1054593D03*
Y1061286D03*
X1745541Y1051247D03*
X1754241D03*
X1745541Y1057940D03*
X1754241D03*
X1745541Y1054593D03*
X1740683Y1074672D03*
Y1067979D03*
X1754241Y1071326D03*
X1745541D03*
Y1064633D03*
X1754241D03*
Y1078018D03*
X1745541D03*
X1740683Y1084711D03*
Y1091404D03*
X1754241Y1088058D03*
X1745541D03*
X1754241Y1094751D03*
X1745541D03*
X1740683Y1098097D03*
Y1104790D03*
Y1111483D03*
X1754241Y1101444D03*
X1745541D03*
X1754241Y1108137D03*
X1745541D03*
X1740683Y1121522D03*
Y1128215D03*
X1754241Y1114829D03*
X1745541D03*
X1754241Y1124869D03*
X1745541D03*
X1740683Y1134908D03*
Y1141601D03*
X1754241Y1131562D03*
X1745541D03*
X1754241Y1138255D03*
X1745541D03*
X1754241Y1144948D03*
X1745541D03*
X1740683Y1148294D03*
Y1158333D03*
X1754241Y1151641D03*
X1745541D03*
X1754241Y1161680D03*
X1745541D03*
X1740683Y1165026D03*
Y1171719D03*
X1745541Y1175066D03*
X1754241D03*
Y1168373D03*
X1745541D03*
X1740683Y1178412D03*
Y1185105D03*
X1745541Y1181759D03*
X1754241D03*
Y1188452D03*
X1745541D03*
X1740683Y1195144D03*
Y1201837D03*
Y1208530D03*
X1754241Y1198491D03*
X1745541D03*
X1754241Y1205184D03*
X1745541D03*
X1740683Y1215223D03*
Y1221916D03*
X1754241Y1211877D03*
X1745541D03*
X1754241Y1218570D03*
X1745541D03*
X1754241Y1225263D03*
X1745541D03*
X1740683Y1231955D03*
Y1238648D03*
X1754241Y1235302D03*
X1745541D03*
X1754241Y1241995D03*
X1745541D03*
X1740683Y1245341D03*
X1754241Y1248688D03*
X1745541D03*
X1754488Y1257264D03*
X1745541Y1258727D03*
X1743710Y1262074D03*
X1742337Y1252300D03*
X1751388Y1273344D03*
X1748588D03*
X1745541Y1265420D03*
X1749088Y1310474D03*
X1746288D03*
X1770383Y766798D03*
X1761683D03*
X1770383Y773491D03*
X1761683D03*
Y780184D03*
X1770383D03*
X1761683Y790223D03*
X1770383D03*
X1761683Y796916D03*
X1770383D03*
X1761683Y803609D03*
X1770383D03*
X1761683Y810302D03*
X1770383D03*
X1761683Y816995D03*
X1770383D03*
X1761683Y827034D03*
X1770383D03*
X1761683Y833727D03*
X1770383D03*
X1761683Y840420D03*
X1770383D03*
X1761683Y847113D03*
X1770383D03*
X1761683Y853806D03*
X1770383D03*
X1761683Y863845D03*
X1770383D03*
X1761683Y870538D03*
X1770383D03*
X1761683Y877231D03*
X1770383D03*
X1761683Y883924D03*
X1770383D03*
X1761683Y890617D03*
X1770383D03*
X1761683Y900656D03*
X1770383D03*
X1761683Y907349D03*
X1770383D03*
X1761683Y914042D03*
X1770383D03*
Y927428D03*
X1761683D03*
Y920735D03*
X1770383D03*
X1761683Y937467D03*
X1770383D03*
X1761683Y944160D03*
X1770383D03*
X1761683Y950853D03*
X1770383D03*
X1761683Y960892D03*
X1770383D03*
X1761683Y964239D03*
Y957546D03*
Y954200D03*
Y967585D03*
X1770383D03*
X1761683Y974278D03*
X1770383D03*
X1761683Y980971D03*
X1770383D03*
X1761683Y987664D03*
X1770383D03*
X1761683Y994357D03*
Y1017782D03*
X1770383D03*
X1761683Y1027822D03*
X1770383D03*
X1761683Y1021129D03*
Y1024475D03*
Y1034515D03*
X1770383D03*
X1761683Y1041207D03*
X1770383D03*
X1761683Y1047900D03*
X1770383D03*
X1761683Y1054593D03*
X1770383D03*
X1761683Y1061286D03*
X1770383D03*
X1761683Y1051247D03*
Y1067979D03*
X1770383D03*
X1761683Y1074672D03*
X1770383D03*
X1761683Y1084711D03*
X1770383D03*
X1761683Y1091404D03*
X1770383D03*
Y1098097D03*
X1761683D03*
Y1104790D03*
X1770383D03*
X1761683Y1111483D03*
X1770383D03*
X1761683Y1121522D03*
X1770383D03*
X1761683Y1128215D03*
X1770383D03*
X1761683Y1134908D03*
X1770383D03*
X1761683Y1141601D03*
X1770383D03*
X1761683Y1148294D03*
X1770383D03*
X1761683Y1158333D03*
X1770383D03*
X1761683Y1165026D03*
X1770383D03*
X1761683Y1171719D03*
X1770383D03*
X1761683Y1178412D03*
X1770383D03*
X1761683Y1185105D03*
X1770383D03*
X1761683Y1195144D03*
X1770383D03*
X1761683Y1201837D03*
X1770383D03*
X1761683Y1208530D03*
X1770383D03*
X1761683Y1215223D03*
X1770383D03*
X1761683Y1221916D03*
X1770383D03*
X1761683Y1231955D03*
X1770383D03*
X1761683Y1238648D03*
X1770383D03*
X1761683Y1245341D03*
X1770383D03*
X1756922Y1247632D03*
X1761683Y1255381D03*
Y1258727D03*
X1770299Y1252034D03*
X1761683Y1248688D03*
X1767388Y1273344D03*
X1764588D03*
X1761683Y1262074D03*
Y1265420D03*
X1775241Y770144D03*
X1783941D03*
X1773559Y767345D03*
X1775241Y776837D03*
X1783941D03*
X1775241Y783530D03*
X1783941D03*
X1775241Y780184D03*
Y773491D03*
Y786877D03*
Y793570D03*
X1783941D03*
X1775241Y800263D03*
X1783941D03*
X1775241Y803609D03*
Y796916D03*
Y790223D03*
Y806955D03*
X1783941D03*
X1775241Y813648D03*
X1783941D03*
X1775241Y820341D03*
X1783941D03*
X1775241Y816995D03*
Y810302D03*
X1783941Y830381D03*
X1775241D03*
Y833727D03*
Y823688D03*
Y827034D03*
Y837074D03*
X1783941D03*
X1775241Y843766D03*
X1783941D03*
X1775241Y850459D03*
X1783941D03*
X1775241Y847113D03*
Y840420D03*
Y857152D03*
X1783941D03*
X1775241Y867192D03*
X1783941D03*
X1775241Y853806D03*
Y860499D03*
Y863845D03*
Y873885D03*
X1783941D03*
X1775241Y880577D03*
X1783941D03*
X1775241Y883924D03*
Y877231D03*
Y870538D03*
Y887270D03*
X1783941D03*
X1775241Y893963D03*
X1783941D03*
X1775241Y890617D03*
Y897310D03*
Y900656D03*
Y904003D03*
X1783941D03*
X1775241Y910696D03*
X1783941D03*
X1775241Y917389D03*
X1783941D03*
X1775241Y914042D03*
Y907349D03*
Y924081D03*
X1783941D03*
X1775241Y930774D03*
X1783941D03*
X1775241Y927428D03*
Y920735D03*
Y934121D03*
Y940814D03*
X1783941D03*
X1775241Y947507D03*
X1783941D03*
X1775241Y944160D03*
Y937467D03*
Y954200D03*
X1783941D03*
X1775241Y964239D03*
X1783941D03*
X1775241Y960892D03*
Y950853D03*
Y957546D03*
Y970932D03*
X1783941D03*
X1775241Y977625D03*
X1783941D03*
X1775241Y980971D03*
Y974278D03*
Y967585D03*
Y984318D03*
X1783941D03*
X1775241Y991011D03*
X1783941D03*
X1775241Y994357D03*
Y987664D03*
Y1017782D03*
X1783941D03*
X1775241Y1024475D03*
X1783941D03*
X1775241Y1031168D03*
X1783941D03*
X1775241Y1027822D03*
Y1021129D03*
Y1037861D03*
X1783941D03*
X1775241Y1044554D03*
X1783941D03*
X1775241Y1047900D03*
Y1041207D03*
Y1034515D03*
Y1051247D03*
X1783941D03*
X1775241Y1057940D03*
X1783941D03*
X1775241Y1061286D03*
Y1054593D03*
Y1064633D03*
X1783941D03*
X1775241Y1071326D03*
X1783941D03*
X1775241Y1078018D03*
X1783941D03*
X1775241Y1074672D03*
Y1067979D03*
Y1088058D03*
X1783941D03*
X1775241Y1094751D03*
X1783941D03*
X1775241Y1091404D03*
Y1081365D03*
Y1084711D03*
Y1101444D03*
X1783941D03*
X1775241Y1108137D03*
X1783941D03*
X1775241Y1098097D03*
Y1111483D03*
Y1104790D03*
Y1114829D03*
X1783941D03*
X1775241Y1124869D03*
X1783941D03*
X1775241Y1128215D03*
Y1118176D03*
Y1121522D03*
Y1131562D03*
X1783941D03*
X1775241Y1138255D03*
X1783941D03*
X1775241Y1144948D03*
X1783941D03*
X1775241Y1141601D03*
Y1134908D03*
X1783941Y1151641D03*
X1775241D03*
Y1161680D03*
X1783941D03*
X1775241Y1148294D03*
Y1154987D03*
Y1158333D03*
Y1168373D03*
X1783941D03*
X1775241Y1175066D03*
X1783941D03*
X1775241Y1171719D03*
Y1165026D03*
Y1181759D03*
X1783941D03*
X1775241Y1188452D03*
X1783941D03*
X1775241Y1185105D03*
Y1178412D03*
Y1191798D03*
Y1198491D03*
X1783941D03*
X1775241Y1205184D03*
X1783941D03*
X1775241Y1208530D03*
Y1201837D03*
Y1195144D03*
Y1211877D03*
X1783941D03*
X1775241Y1218570D03*
X1783941D03*
X1775241Y1225263D03*
X1783941D03*
X1775241Y1221916D03*
Y1215223D03*
Y1235302D03*
X1783941D03*
X1775241Y1241995D03*
X1783941D03*
X1775241Y1238648D03*
Y1228609D03*
Y1231955D03*
X1784188Y1257664D03*
X1775241Y1248688D03*
X1783941D03*
X1775241Y1245341D03*
Y1258727D03*
X1788219Y1259312D03*
X1773390Y1262074D03*
X1773480Y1253692D03*
X1781088Y1273344D03*
X1778288D03*
X1775241Y1265420D03*
X1788360Y1264522D03*
X1791383Y766798D03*
X1800083D03*
X1791383Y770144D03*
Y773491D03*
X1800083D03*
X1791383Y780184D03*
X1800083D03*
X1791383Y776837D03*
Y786877D03*
Y783530D03*
Y790223D03*
X1800083D03*
X1791383Y796916D03*
X1800083D03*
X1791383Y803609D03*
X1800083D03*
X1791383Y800263D03*
Y793570D03*
Y810302D03*
X1800083D03*
X1791383Y816995D03*
X1800083D03*
X1791383Y813648D03*
Y806955D03*
Y820341D03*
Y827034D03*
X1800083D03*
Y833727D03*
X1791383D03*
Y830381D03*
Y823688D03*
Y840420D03*
X1800083D03*
X1791383Y847113D03*
X1800083D03*
X1791383Y850459D03*
Y843766D03*
Y837074D03*
Y853806D03*
X1800083D03*
X1791383Y863845D03*
X1800083D03*
X1791383Y867192D03*
Y860499D03*
Y857152D03*
Y870538D03*
X1800083D03*
X1791383Y877231D03*
X1800083D03*
X1791383Y883924D03*
X1800083D03*
X1791383Y873885D03*
Y880577D03*
Y890617D03*
X1800083D03*
X1791383Y900656D03*
X1800083D03*
X1791383Y887270D03*
Y897310D03*
Y893963D03*
Y907349D03*
X1800083D03*
X1791383Y914042D03*
X1800083D03*
X1791383Y917389D03*
Y910696D03*
Y904003D03*
Y920735D03*
X1800083D03*
X1791383Y927428D03*
X1800083D03*
X1791383Y924081D03*
Y934121D03*
Y930774D03*
Y937467D03*
X1800083D03*
X1791383Y944160D03*
X1800083D03*
X1791383Y947507D03*
Y940814D03*
X1800083Y950853D03*
X1791383D03*
Y960892D03*
X1800083D03*
X1791383Y964239D03*
Y957546D03*
Y954200D03*
Y967585D03*
X1800083D03*
X1791383Y974278D03*
X1800083D03*
X1791383Y980971D03*
X1800083D03*
X1791383Y977625D03*
Y970932D03*
Y987664D03*
X1800083D03*
X1791383Y991011D03*
Y984318D03*
Y994357D03*
Y1017782D03*
X1800083D03*
X1791383Y1027822D03*
X1800083D03*
X1791383Y1021129D03*
Y1024475D03*
Y1031168D03*
Y1034515D03*
X1800083D03*
X1791383Y1041207D03*
X1800083D03*
X1791383Y1047900D03*
X1800083D03*
X1791383Y1044554D03*
Y1037861D03*
Y1054593D03*
X1800083D03*
X1791383Y1061286D03*
X1800083D03*
X1791083Y1051247D03*
X1791383Y1067979D03*
X1800083D03*
X1791383Y1074672D03*
X1800083D03*
X1791383Y1071325D03*
Y1064633D03*
Y1078018D03*
Y1084711D03*
X1800083D03*
X1791383Y1091404D03*
X1800083D03*
X1791383Y1094751D03*
Y1088058D03*
Y1081365D03*
Y1098097D03*
X1800083D03*
X1791383Y1104790D03*
X1800083D03*
X1791383Y1111483D03*
X1800083D03*
X1791383Y1108136D03*
Y1101444D03*
Y1121522D03*
X1800083D03*
X1791383Y1128215D03*
X1800083D03*
X1791383Y1124869D03*
Y1118176D03*
Y1114829D03*
X1800083Y1134908D03*
X1791383D03*
Y1141601D03*
X1800083D03*
X1791383Y1144947D03*
Y1138255D03*
Y1131562D03*
Y1148294D03*
X1800083D03*
X1791383Y1158333D03*
X1800083D03*
X1791383Y1161680D03*
Y1154987D03*
Y1151640D03*
Y1165026D03*
X1800083D03*
X1791383Y1171719D03*
X1800083D03*
X1791383Y1175066D03*
Y1168373D03*
Y1178412D03*
X1800083D03*
X1791383Y1185105D03*
X1800083D03*
X1791383Y1181758D03*
Y1191798D03*
Y1188451D03*
Y1195144D03*
X1800083D03*
X1791383Y1201837D03*
X1800083D03*
X1791383Y1208530D03*
X1800083D03*
X1791383Y1205184D03*
Y1198491D03*
Y1215223D03*
X1800083D03*
X1791383Y1221916D03*
X1800083D03*
X1791383Y1218570D03*
Y1211877D03*
Y1225263D03*
Y1231955D03*
X1800083D03*
X1791383Y1238648D03*
X1800083D03*
X1788373Y1241769D03*
X1791383Y1241995D03*
Y1235302D03*
Y1228609D03*
Y1245341D03*
X1800083D03*
X1800427Y1248125D03*
X1803100Y1262074D03*
X1800019Y1252034D03*
X1791383Y1248688D03*
X1797088Y1273344D03*
X1794288D03*
X1791383Y1265420D03*
Y1262074D03*
X1804941Y770144D03*
X1813641D03*
X1804841Y766798D03*
X1804941Y776837D03*
X1813641D03*
X1804941Y783530D03*
X1813641D03*
X1804941Y793570D03*
X1813641D03*
X1804941Y800263D03*
X1813641D03*
X1804941Y806955D03*
X1813641D03*
X1804941Y813648D03*
X1813641D03*
X1804941Y820341D03*
X1813641D03*
X1804941Y830381D03*
X1813641D03*
X1804941Y843766D03*
X1813641D03*
X1804941Y837074D03*
X1813641D03*
X1804941Y850459D03*
X1813641D03*
X1804941Y857152D03*
X1813641D03*
Y867192D03*
X1804941D03*
Y873885D03*
X1813641D03*
X1804941Y880577D03*
X1813641D03*
X1804941Y887270D03*
X1813641D03*
X1804941Y893963D03*
X1813641D03*
X1804941Y904003D03*
X1813641D03*
X1804941Y910696D03*
X1813641D03*
X1804941Y917389D03*
X1813641D03*
X1804941Y924081D03*
X1813641D03*
X1804941Y930774D03*
X1813641D03*
X1804941Y940814D03*
X1813641D03*
X1804941Y947507D03*
X1813641D03*
X1804941Y954200D03*
X1813641D03*
X1804941Y964239D03*
X1813641D03*
X1804941Y960892D03*
Y957546D03*
Y970932D03*
X1813641D03*
X1804941Y977625D03*
X1813641D03*
X1804941Y967585D03*
Y984318D03*
X1813641D03*
X1804941Y991011D03*
X1813641D03*
X1804941Y1017782D03*
X1813641D03*
X1804941Y1024475D03*
X1813641D03*
X1804941Y1031168D03*
X1813641D03*
X1804941Y1037861D03*
X1813641D03*
X1804941Y1044554D03*
X1813641D03*
Y1057940D03*
X1804941D03*
Y1051247D03*
X1813641D03*
X1804941Y1054593D03*
Y1064633D03*
X1813641D03*
Y1071326D03*
X1804941D03*
X1813641Y1078018D03*
X1804941D03*
X1813641Y1088058D03*
X1804941D03*
X1813641Y1094751D03*
X1804941D03*
X1813641Y1101444D03*
X1804941D03*
X1813641Y1108137D03*
X1804941D03*
X1813641Y1114829D03*
X1804941D03*
X1813641Y1124869D03*
X1804941D03*
X1813641Y1131562D03*
X1804941D03*
X1813641Y1138255D03*
X1804941D03*
X1813641Y1144948D03*
X1804941D03*
X1813641Y1151641D03*
X1804941D03*
X1813641Y1161680D03*
X1804941D03*
X1813641Y1168373D03*
X1804941D03*
X1813641Y1175066D03*
X1804941D03*
X1813641Y1181759D03*
X1804941D03*
X1813641Y1188452D03*
X1804941D03*
X1813641Y1198491D03*
X1804941D03*
X1813641Y1205184D03*
X1804941D03*
X1813641Y1211877D03*
X1804941D03*
X1813641Y1218570D03*
X1804941D03*
X1813641Y1225263D03*
X1804941D03*
X1813641Y1235302D03*
X1804941D03*
X1813641Y1241995D03*
X1804941D03*
X1815063Y1233103D03*
X1813641Y1248688D03*
X1804941D03*
X1819054Y1253986D03*
X1804941Y1258727D03*
X1821083Y1252034D03*
X1813814Y1254693D03*
X1818188Y1273044D03*
X1810788Y1273344D03*
X1807988D03*
X1815388Y1273044D03*
X1804941Y1265420D03*
X1829783Y766798D03*
X1821083D03*
X1829783Y773491D03*
X1821083D03*
X1829783Y780184D03*
X1821083D03*
X1829783Y790223D03*
X1821083D03*
X1829783Y796916D03*
X1821083D03*
X1829783Y803609D03*
X1821083D03*
X1829783Y810302D03*
X1821083D03*
X1829783Y816995D03*
X1821083D03*
X1829783Y827034D03*
X1821083D03*
X1829783Y833727D03*
X1821083D03*
Y847113D03*
X1829783D03*
Y840420D03*
X1821083D03*
X1829783Y853806D03*
X1821083D03*
X1829783Y863845D03*
X1821083D03*
X1829783Y870538D03*
X1821083D03*
X1829783Y877231D03*
X1821083D03*
X1829783Y883924D03*
X1821083D03*
X1829783Y890617D03*
X1821083D03*
X1829783Y900656D03*
X1821083D03*
X1829783Y907349D03*
X1821083D03*
X1829783Y914042D03*
X1821083D03*
X1829783Y920735D03*
X1821083D03*
X1829783Y927428D03*
X1821083D03*
X1829783Y937467D03*
X1821083D03*
X1829783Y944160D03*
X1821083D03*
X1829783Y950853D03*
X1821083D03*
X1829783Y960892D03*
X1821083D03*
Y964239D03*
X1820983Y957546D03*
Y954200D03*
X1829783Y967585D03*
X1821083D03*
X1829783Y974278D03*
X1821083D03*
X1829783Y980971D03*
X1821083D03*
X1829783Y987664D03*
X1821083D03*
X1820983Y994357D03*
X1829783Y1017782D03*
X1821083D03*
X1829783Y1027822D03*
X1821083D03*
Y1021129D03*
Y1024475D03*
X1829783Y1034515D03*
X1821083D03*
X1829783Y1041207D03*
X1821083D03*
X1829783Y1047900D03*
X1821083D03*
X1829783Y1054593D03*
X1821083D03*
X1829783Y1061286D03*
X1821083D03*
Y1051247D03*
X1829783Y1067979D03*
X1821083D03*
Y1074672D03*
X1829783D03*
X1821083Y1084711D03*
X1829783D03*
X1821083Y1091404D03*
X1829783D03*
X1821083Y1098097D03*
X1829783D03*
X1821083Y1104790D03*
X1829783D03*
X1821083Y1111483D03*
X1829783D03*
X1821083Y1121522D03*
X1829783D03*
X1821083Y1128215D03*
X1829783D03*
X1821083Y1134908D03*
X1829783D03*
X1821083Y1141601D03*
X1829783D03*
X1821083Y1148294D03*
X1829783D03*
X1821083Y1158333D03*
X1829783D03*
X1821083Y1165026D03*
X1829783D03*
X1821083Y1171719D03*
X1829783D03*
X1821083Y1178412D03*
X1829783D03*
X1821083Y1185105D03*
X1829783D03*
X1821083Y1195144D03*
X1829783D03*
X1821083Y1201837D03*
X1829783D03*
X1821083Y1208530D03*
X1829783D03*
X1821083Y1215223D03*
X1829783D03*
X1821083Y1221916D03*
X1829783D03*
X1821083Y1231955D03*
X1829783D03*
X1821083Y1238648D03*
X1829783D03*
Y1245341D03*
X1821083D03*
X1830379Y1250358D03*
X1829920Y1258322D03*
X1821139Y1248155D03*
X1821083Y1262074D03*
Y1265420D03*
X1829940Y1263662D03*
G54D204*
X705760Y-26500D03*
Y-16500D03*
D03*
Y-6500D03*
X730760Y-26500D03*
Y-16500D03*
D03*
Y-6500D03*
X822720Y3500D03*
Y13500D03*
D03*
Y23500D03*
X847720Y3500D03*
Y13500D03*
D03*
Y23500D03*
X973180Y-26500D03*
Y-16500D03*
D03*
Y-6500D03*
Y3500D03*
Y13500D03*
Y23500D03*
Y13500D03*
X998180Y-26500D03*
Y-16500D03*
D03*
Y-6500D03*
Y3500D03*
Y13500D03*
Y23500D03*
Y13500D03*
X1015152Y-26511D03*
Y-36511D03*
Y-26511D03*
Y-16511D03*
D03*
Y-6511D03*
D03*
Y3489D03*
D03*
Y13489D03*
D03*
Y23489D03*
X1040152Y-26511D03*
Y-36511D03*
Y-26511D03*
Y-16511D03*
D03*
Y-6511D03*
D03*
Y3489D03*
D03*
Y13489D03*
D03*
Y23489D03*
X1282572Y-36511D03*
Y-26511D03*
D03*
Y-16511D03*
D03*
Y-6511D03*
Y3489D03*
Y-6511D03*
Y3489D03*
Y13489D03*
Y23489D03*
Y13489D03*
X1307572Y-36511D03*
Y-26511D03*
D03*
Y-16511D03*
D03*
Y-6511D03*
Y3489D03*
Y-6511D03*
Y3489D03*
Y13489D03*
Y23489D03*
Y13489D03*
X1324471Y-26511D03*
Y-36511D03*
Y-26511D03*
Y-16511D03*
D03*
Y-6511D03*
D03*
Y3489D03*
D03*
Y13489D03*
D03*
Y23489D03*
X1349471Y-26511D03*
Y-36511D03*
Y-26511D03*
Y-16511D03*
D03*
Y-6511D03*
D03*
Y3489D03*
D03*
Y13489D03*
D03*
Y23489D03*
X1474931Y-36511D03*
Y-26511D03*
D03*
Y-16511D03*
D03*
Y-6511D03*
Y3489D03*
Y-6511D03*
Y3489D03*
Y13489D03*
Y23489D03*
Y13489D03*
X1499931Y-36511D03*
Y-26511D03*
D03*
Y-16511D03*
D03*
Y-6511D03*
Y3489D03*
Y-6511D03*
Y3489D03*
Y13489D03*
Y23489D03*
Y13489D03*
X1565236Y184783D03*
Y264035D03*
G54D312*
X1765429Y276192D03*
G54D30*
X40120Y744554D03*
Y1000853D03*
Y1287664D03*
X69820Y744554D03*
Y1000853D03*
Y1287664D03*
X99520Y744554D03*
Y1000853D03*
Y1287664D03*
X129220Y744554D03*
Y1000853D03*
Y1287664D03*
X158920Y744554D03*
Y1000853D03*
Y1287664D03*
X188620Y744554D03*
Y1000853D03*
Y1287664D03*
X218320Y744554D03*
Y1000853D03*
Y1287664D03*
X248020Y744554D03*
Y1000853D03*
Y1287664D03*
X633320Y744554D03*
Y1000853D03*
Y1287664D03*
X663020Y744554D03*
Y1000853D03*
Y1287664D03*
X692720Y744554D03*
Y1000853D03*
Y1287664D03*
X722420Y744554D03*
Y1000853D03*
Y1287664D03*
X752120Y744554D03*
Y1000853D03*
Y1287664D03*
X781820Y744554D03*
Y1000853D03*
Y1287664D03*
X811520Y744554D03*
Y1000853D03*
Y1287664D03*
X841220Y744554D03*
Y1000853D03*
Y1287664D03*
X1016262Y744554D03*
Y1000853D03*
Y1287664D03*
X1045962Y744554D03*
Y1000853D03*
Y1287664D03*
X1075662Y744554D03*
Y1000853D03*
Y1287664D03*
X1105362Y744554D03*
Y1000853D03*
Y1287664D03*
X1135062Y744554D03*
Y1000853D03*
Y1287664D03*
X1164762Y744554D03*
Y1000853D03*
Y1287664D03*
X1194462Y744554D03*
Y1000853D03*
Y1287664D03*
X1224162Y744554D03*
Y1000853D03*
Y1287664D03*
X1609462Y744554D03*
Y1000853D03*
Y1287664D03*
X1639162Y744554D03*
Y1000853D03*
Y1287664D03*
X1668862Y744554D03*
Y1000853D03*
Y1287664D03*
X1698562Y744554D03*
Y1000853D03*
Y1287664D03*
X1728262Y744554D03*
Y1000853D03*
Y1287664D03*
X1757962Y744554D03*
Y1000853D03*
Y1287664D03*
X1787662Y744554D03*
Y1000853D03*
Y1287664D03*
X1817362Y744554D03*
Y1000853D03*
Y1287664D03*
G54D321*
X1809624Y1502387D03*
G54D340*
G01X1321753Y1028523D02*
Y1026413D01*
G01X1458654Y1052047D02*
X1458653Y1052048D01*
Y1054157D01*
G54D331*
G01X43765Y778479D02*
X43797Y778511D01*
X44773D01*
G01X51617Y771818D02*
X52919D01*
G01X43810Y788550D02*
X43768Y788508D01*
X43765D01*
G01Y801904D02*
X43797Y801936D01*
X44773D01*
G01X51617Y795243D02*
X52919D01*
G01Y791897D02*
X51646D01*
G01X44735D02*
X43802D01*
X43765Y791934D01*
G01Y815290D02*
X43797Y815322D01*
X44773D01*
G01X51617Y808629D02*
X52919D01*
G01X51617Y832054D02*
X52919D01*
G01X43810Y825361D02*
X43768Y825319D01*
X43765D01*
G01X52919Y828708D02*
X51646D01*
G01X44735D02*
X43802D01*
X43765Y828745D01*
G01Y852101D02*
X43797Y852133D01*
X44773D01*
G01X51617Y845440D02*
X52919D01*
G01X43765Y838715D02*
X43797Y838747D01*
X44773D01*
G01X43810Y862172D02*
X43768Y862130D01*
X43765D01*
G01X52919Y865519D02*
X51646D01*
G01X44735D02*
X43802D01*
X43765Y865556D01*
G01X51617Y882251D02*
X52919D01*
G01X43765Y875526D02*
X43797Y875558D01*
X44773D01*
G01X51617Y868865D02*
X52919D01*
G01X43765Y888912D02*
X43797Y888944D01*
X44773D01*
G01X43810Y898983D02*
X43768Y898941D01*
X43765D01*
G01X52919Y902330D02*
X51646D01*
G01X44735D02*
X43802D01*
X43765Y902367D01*
G01Y912337D02*
X43797Y912369D01*
X44773D01*
G01X51617Y905676D02*
X52919D01*
G01X43765Y925723D02*
X43797Y925755D01*
X44773D01*
G01X51617Y919062D02*
X52919D01*
G01X43765Y949148D02*
X43797Y949180D01*
X44773D01*
G01X51617Y942487D02*
X52919D01*
G01X43810Y935794D02*
X43768Y935752D01*
X43765D01*
G01X52919Y939141D02*
X51646D01*
G01X44735D02*
X43802D01*
X43765Y939178D01*
G01X51617Y979298D02*
X52919D01*
G01X51617Y972605D02*
X52919D01*
G01X51617Y992684D02*
X52919D01*
G01X51617Y985991D02*
X52919D01*
G01X51617Y1026149D02*
X52919D01*
G01X43765Y1019510D02*
X43799D01*
X43853Y1019456D01*
G01X51617D02*
X52919D01*
G01X51617Y1046227D02*
X52919D01*
G01X51617Y1039534D02*
X52919D01*
G01X51617Y1032842D02*
X52919D01*
G01X52796Y1059613D02*
X52919D01*
G01X43765Y1072967D02*
X43797Y1072999D01*
X44773D01*
G01X51617Y1066306D02*
X52919D01*
G01X51617Y1089731D02*
X52919D01*
G01X43810Y1083038D02*
X43768Y1082996D01*
X43765D01*
G01X52919Y1086385D02*
X51646D01*
G01X44735D02*
X43802D01*
X43765Y1086422D01*
G01Y1096392D02*
X43797Y1096424D01*
X44773D01*
G01X43765Y1109778D02*
X43797Y1109810D01*
X44773D01*
G01X51617Y1103117D02*
X52919D01*
G01X51617Y1126542D02*
X52919D01*
G01X43810Y1119849D02*
X43768Y1119807D01*
X43765D01*
G01X52919Y1123196D02*
X51646D01*
G01X44735D02*
X43802D01*
X43765Y1123233D01*
G01X51617Y1139928D02*
X52919D01*
G01X43765Y1133203D02*
X43797Y1133235D01*
X44773D01*
G01X43765Y1146589D02*
X43797Y1146621D01*
X44773D01*
G01X43810Y1156660D02*
X43768Y1156618D01*
X43765D01*
G01X52919Y1160007D02*
X51646D01*
G01X44735D02*
X43802D01*
X43765Y1160044D01*
G01X51617Y1176739D02*
X52919D01*
G01X43765Y1170014D02*
X43797Y1170046D01*
X44773D01*
G01X51617Y1163353D02*
X52919D01*
G01X43765Y1183400D02*
X43797Y1183432D01*
X44773D01*
G01X43810Y1193471D02*
X43768Y1193429D01*
X43765D01*
G01Y1206825D02*
X43797Y1206857D01*
X44773D01*
G01X51617Y1200164D02*
X52919D01*
G01Y1196818D02*
X51646D01*
G01X44735D02*
X43802D01*
X43765Y1196855D01*
G01Y1220211D02*
X43797Y1220243D01*
X44773D01*
G01X51617Y1213550D02*
X52919D01*
G01X51617Y1236975D02*
X52919D01*
G01X43810Y1230282D02*
X43768Y1230240D01*
X43765D01*
G01X52919Y1233629D02*
X51646D01*
G01X44735D02*
X43802D01*
X43765Y1233666D01*
G01Y1243636D02*
X43797Y1243668D01*
X44773D01*
G01X57323Y771873D02*
X57379Y771817D01*
X58316D01*
G01X57323Y775124D02*
X57363Y775164D01*
X58367D01*
G01X58298Y785204D02*
X57354D01*
X57323Y785235D01*
G01X58295Y781857D02*
X57345D01*
X57323Y781835D01*
G01Y798550D02*
X57363Y798590D01*
X58367D01*
G01X57323Y795299D02*
X57379Y795243D01*
X58316D01*
G01X57323Y811935D02*
X57363Y811975D01*
X58367D01*
G01X57323Y808684D02*
X57379Y808628D01*
X58316D01*
G01X58295Y818668D02*
X57345D01*
X57323Y818646D01*
G01Y835361D02*
X57363Y835401D01*
X58367D01*
G01X57323Y832110D02*
X57379Y832054D01*
X58316D01*
G01X58298Y822015D02*
X57354D01*
X57323Y822046D01*
G01Y848746D02*
X57363Y848786D01*
X58367D01*
G01X57323Y845495D02*
X57379Y845439D01*
X58316D01*
G01X57323Y868921D02*
X57379Y868865D01*
X58316D01*
G01X58298Y858826D02*
X57354D01*
X57323Y858857D01*
G01X58295Y855479D02*
X57345D01*
X57323Y855457D01*
G01Y872172D02*
X57363Y872212D01*
X58367D01*
G01X57323Y882306D02*
X57379Y882250D01*
X58316D01*
G01X57323Y885557D02*
X57363Y885597D01*
X58367D01*
G01X58298Y895637D02*
X57354D01*
X57323Y895668D01*
G01X58295Y892290D02*
X57345D01*
X57323Y892268D01*
G01Y908983D02*
X57363Y909023D01*
X58367D01*
G01X57323Y905732D02*
X57379Y905676D01*
X58316D01*
G01X57323Y922368D02*
X57363Y922408D01*
X58367D01*
G01X57323Y919118D02*
X57379Y919062D01*
X58316D01*
G01X58298Y932448D02*
X57354D01*
X57323Y932479D01*
G01X58295Y929101D02*
X57345D01*
X57323Y929079D01*
G01Y945794D02*
X57363Y945834D01*
X58367D01*
G01X57323Y942543D02*
X57379Y942487D01*
X58316D01*
G01X57323Y979354D02*
X57379Y979298D01*
X58316D01*
G01X57323Y972661D02*
X57379Y972605D01*
X58316D01*
G01X57323Y992740D02*
X57379Y992684D01*
X58316D01*
G01X57323Y986047D02*
X57379Y985991D01*
X58316D01*
G01X57323Y1032897D02*
X57379Y1032841D01*
X58316D01*
G01X57323Y1046283D02*
X57379Y1046227D01*
X58316D01*
G01X57323Y1039590D02*
X57379Y1039534D01*
X58316D01*
G01X57323Y1069613D02*
X57363Y1069653D01*
X58367D01*
G01X57323Y1066362D02*
X57379Y1066306D01*
X58316D01*
G01X58298Y1079692D02*
X57362D01*
X57324Y1079730D01*
G01X58295Y1076345D02*
X57345D01*
X57323Y1076323D01*
G01Y1093038D02*
X57363Y1093078D01*
X58367D01*
G01X57323Y1089787D02*
X57379Y1089731D01*
X58316D01*
G01X57323Y1106424D02*
X57363Y1106464D01*
X58367D01*
G01X57323Y1103173D02*
X57379Y1103117D01*
X58316D01*
G01X57323Y1126598D02*
X57379Y1126542D01*
X58316D01*
G01X58298Y1116503D02*
X57361D01*
X57323Y1116541D01*
G01X58295Y1113156D02*
X57345D01*
X57323Y1113134D01*
G01Y1143235D02*
X57363Y1143275D01*
X58367D01*
G01X57323Y1139984D02*
X57379Y1139928D01*
X58316D01*
G01X57323Y1129849D02*
X57363Y1129889D01*
X58367D01*
G01X58298Y1153314D02*
X57367D01*
X57329Y1153352D01*
X57323D01*
G01X58294Y1149968D02*
X57346D01*
X57323Y1149945D01*
G01Y1176795D02*
X57379Y1176739D01*
X58316D01*
G01X57323Y1166660D02*
X57363Y1166700D01*
X58367D01*
G01X57323Y1163409D02*
X57379Y1163353D01*
X58316D01*
G01X57323Y1180046D02*
X57363Y1180086D01*
X58367D01*
G01X58298Y1190125D02*
X57367D01*
X57329Y1190163D01*
X57323D01*
G01X58294Y1186779D02*
X57346D01*
X57323Y1186756D01*
G01Y1203471D02*
X57363Y1203511D01*
X58367D01*
G01X57323Y1200220D02*
X57379Y1200164D01*
X58316D01*
G01X57323Y1216857D02*
X57363Y1216897D01*
X58367D01*
G01X57323Y1213606D02*
X57379Y1213550D01*
X58316D01*
G01X58298Y1226936D02*
X57367D01*
X57329Y1226974D01*
X57323D01*
G01X58294Y1223590D02*
X57346D01*
X57323Y1223567D01*
G01Y1240282D02*
X57363Y1240322D01*
X58367D01*
G01X57323Y1237031D02*
X57379Y1236975D01*
X58316D01*
G01X103165Y778479D02*
X103197Y778511D01*
X104173D01*
G01X111017Y771818D02*
X112319D01*
G01X103165Y788508D02*
X103168D01*
X103210Y788550D01*
G01X111017Y795243D02*
X112319D01*
G01X103165Y791934D02*
X103202Y791897D01*
X104135D01*
G01X111046D02*
X112319D01*
G01X103165Y815290D02*
X103197Y815322D01*
X104173D01*
G01X111017Y808629D02*
X112319D01*
G01X103165Y801904D02*
X103197Y801936D01*
X104173D01*
G01X111017Y832054D02*
X112319D01*
G01X103165Y825319D02*
X103168D01*
X103210Y825361D01*
G01X103165Y828745D02*
X103202Y828708D01*
X104135D01*
G01X111046D02*
X112319D01*
G01X111017Y845440D02*
X112319D01*
G01X103165Y838715D02*
X103197Y838747D01*
X104173D01*
G01X103165Y852101D02*
X103197Y852133D01*
X104173D01*
G01X103165Y862130D02*
X103168D01*
X103210Y862172D01*
G01X103165Y865556D02*
X103202Y865519D01*
X104135D01*
G01X111046D02*
X112319D01*
G01X111017Y882251D02*
X112319D01*
G01X103165Y875526D02*
X103197Y875558D01*
X104173D01*
G01X111017Y868865D02*
X112319D01*
G01X103165Y888912D02*
X103197Y888944D01*
X104173D01*
G01X103165Y898941D02*
X103168D01*
X103210Y898983D01*
G01X103166Y902366D02*
X103202Y902330D01*
X104135D01*
G01X111046D02*
X112320D01*
G01X103165Y912337D02*
X103197Y912369D01*
X104173D01*
G01X111017Y905676D02*
X112319D01*
G01X102637Y925755D02*
X104173D01*
G01X112319D02*
X112593D01*
G01X102621Y919062D02*
X103200D01*
G01X111017D02*
X112561D01*
G01X102653Y942487D02*
X103200D01*
G01X111017D02*
X112561D01*
G01X102621Y935794D02*
X103210D01*
G01X112319D02*
X112561D01*
G01X102621Y939141D02*
X104135D01*
G01X112320D02*
X112561D01*
G01X102637Y949180D02*
X104173D01*
G01X112319D02*
X112593D01*
G01X111017Y979298D02*
X112319D01*
G01X111017Y972605D02*
X112319D01*
G01X111017Y992684D02*
X112319D01*
G01X111017Y985991D02*
X112319D01*
G01X111017Y1026149D02*
X112319D01*
G01X103165Y1019510D02*
X103199D01*
X103253Y1019456D01*
G01X111017D02*
X112319D01*
G01X111017Y1039534D02*
X112319D01*
G01X111017Y1032842D02*
X112319D01*
G01X111017Y1059613D02*
X112319D01*
G01X111017Y1046227D02*
X112319D01*
G01X102702Y1072999D02*
X104173D01*
G01X112319D02*
X112594D01*
G01X102687Y1066306D02*
X103200D01*
G01X111017D02*
X112611D01*
G01X102638Y1089731D02*
X103200D01*
G01X111017D02*
X112578D01*
G01X102654Y1083038D02*
X103210D01*
G01X112319D02*
X112578D01*
G01X102654Y1086385D02*
X104135D01*
G01X111046D02*
X112578D01*
G01X102637Y1096424D02*
X104173D01*
G01X112319D02*
X112577D01*
G01X103165Y1109778D02*
X103197Y1109810D01*
X104173D01*
G01X111017Y1103117D02*
X112319D01*
G01X111017Y1126542D02*
X112319D01*
G01X103165Y1119807D02*
X103168D01*
X103210Y1119849D01*
G01X103165Y1123233D02*
X103202Y1123196D01*
X104135D01*
G01X111046D02*
X112319D01*
G01X111017Y1139928D02*
X112319D01*
G01X103165Y1133203D02*
X103197Y1133235D01*
X104173D01*
G01X103165Y1146589D02*
X103197Y1146621D01*
X104173D01*
G01X103165Y1156618D02*
X103168D01*
X103210Y1156660D01*
G01X103165Y1160044D02*
X103202Y1160007D01*
X104135D01*
G01X111046D02*
X112319D01*
G01X103165Y1170014D02*
X103197Y1170046D01*
X104173D01*
G01X111017Y1163353D02*
X112319D01*
G01X103165Y1183400D02*
X103197Y1183432D01*
X104173D01*
G01X111017Y1176739D02*
X112319D01*
G01X103165Y1193429D02*
X103168D01*
X103210Y1193471D01*
G01X103165Y1206825D02*
X103197Y1206857D01*
X104173D01*
G01X111017Y1200164D02*
X112319D01*
G01X103165Y1196855D02*
X103202Y1196818D01*
X104135D01*
G01X111046D02*
X112319D01*
G01X103165Y1220211D02*
X103197Y1220243D01*
X104173D01*
G01X111017Y1213550D02*
X112319D01*
G01X111017Y1236975D02*
X112319D01*
G01X103165Y1230240D02*
X103168D01*
X103210Y1230282D01*
G01X103165Y1233666D02*
X103202Y1233629D01*
X104135D01*
G01X111046D02*
X112319D01*
G01X103165Y1243636D02*
X103197Y1243668D01*
X104173D01*
G01X116723Y771873D02*
X116779Y771817D01*
X117716D01*
G01X116723Y775124D02*
X116763Y775164D01*
X117767D01*
G01X116723Y785235D02*
X116754Y785204D01*
X117698D01*
G01X116723Y781835D02*
X116745Y781857D01*
X117695D01*
G01X116723Y798550D02*
X116763Y798590D01*
X117767D01*
G01X116723Y795299D02*
X116779Y795243D01*
X117716D01*
G01X116723Y811935D02*
X116763Y811975D01*
X117767D01*
G01X116723Y808684D02*
X116779Y808628D01*
X117716D01*
G01X116723Y832110D02*
X116779Y832054D01*
X117716D01*
G01X116723Y822046D02*
X116754Y822015D01*
X117698D01*
G01X116723Y818646D02*
X116745Y818668D01*
X117695D01*
G01X116723Y848746D02*
X116763Y848786D01*
X117767D01*
G01X116723Y845495D02*
X116779Y845439D01*
X117716D01*
G01X116723Y835361D02*
X116763Y835401D01*
X117767D01*
G01X116723Y868921D02*
X116779Y868865D01*
X117716D01*
G01X116723Y858857D02*
X116754Y858826D01*
X117698D01*
G01X116723Y855457D02*
X116745Y855479D01*
X117695D01*
G01X116723Y872172D02*
X116763Y872212D01*
X117767D01*
G01X116723Y882306D02*
X116779Y882250D01*
X117716D01*
G01X116723Y885557D02*
X116763Y885597D01*
X117767D01*
G01X116723Y895668D02*
X116754Y895637D01*
X117698D01*
G01X116723Y892268D02*
X116745Y892290D01*
X117695D01*
G01X116723Y908983D02*
X116763Y909023D01*
X117767D01*
G01X116723Y905732D02*
X116779Y905676D01*
X117716D01*
G01X116175Y922408D02*
X117767D01*
G01X125877D02*
X126163D01*
G01X116207Y919062D02*
X117716D01*
G01X125877D02*
X126131D01*
G01X116160Y932448D02*
X117698D01*
G01X125877D02*
X126084D01*
G01X116160Y929101D02*
X117695D01*
G01X125876D02*
X126084D01*
G01X116192Y945834D02*
X117767D01*
G01X125877D02*
X126147D01*
G01X116193Y942487D02*
X117716D01*
G01X125877D02*
X126148D01*
G01X116723Y979354D02*
X116779Y979298D01*
X117716D01*
G01X116723Y972661D02*
X116779Y972605D01*
X117716D01*
G01X116723Y992740D02*
X116779Y992684D01*
X117716D01*
G01X116723Y986047D02*
X116779Y985991D01*
X117716D01*
G01X116723Y1046283D02*
X116779Y1046227D01*
X117716D01*
G01X116723Y1039590D02*
X116779Y1039534D01*
X117716D01*
G01X116723Y1032897D02*
X116779Y1032841D01*
X117716D01*
G01X116222Y1069653D02*
X117767D01*
G01X125877D02*
X126146D01*
G01X116206Y1066306D02*
X116779D01*
G01X125877D02*
X126098D01*
G01X116206Y1076345D02*
X117695D01*
G01X125876D02*
X126083D01*
G01X116205Y1093078D02*
X117767D01*
G01X126026D02*
X126160D01*
G01X116224Y1089731D02*
X117716D01*
G01X125877D02*
X126164D01*
G01X116206Y1079692D02*
X117698D01*
G01X125877D02*
X126083D01*
G01X116723Y1106424D02*
X116763Y1106464D01*
X117767D01*
G01X116723Y1103173D02*
X116779Y1103117D01*
X117716D01*
G01X116723Y1126598D02*
X116779Y1126542D01*
X117716D01*
G01X116723Y1116541D02*
X116761Y1116503D01*
X117698D01*
G01X116723Y1113134D02*
X116745Y1113156D01*
X117695D01*
G01X116723Y1139984D02*
X116779Y1139928D01*
X117716D01*
G01X116723Y1129849D02*
X116763Y1129889D01*
X117767D01*
G01X116723Y1143235D02*
X116763Y1143275D01*
X117767D01*
G01X116723Y1153352D02*
X116729D01*
X116767Y1153314D01*
X117698D01*
G01X116723Y1149945D02*
X116746Y1149968D01*
X117694D01*
G01X116723Y1176795D02*
X116779Y1176739D01*
X117716D01*
G01X116723Y1166660D02*
X116763Y1166700D01*
X117767D01*
G01X116723Y1163409D02*
X116779Y1163353D01*
X117716D01*
G01X116723Y1180046D02*
X116763Y1180086D01*
X117767D01*
G01X116723Y1190163D02*
X116729D01*
X116767Y1190125D01*
X117698D01*
G01X116723Y1186756D02*
X116746Y1186779D01*
X117694D01*
G01X116723Y1203471D02*
X116763Y1203511D01*
X117767D01*
G01X116723Y1200220D02*
X116779Y1200164D01*
X117716D01*
G01X116723Y1216857D02*
X116763Y1216897D01*
X117767D01*
G01X116723Y1213606D02*
X116779Y1213550D01*
X117716D01*
G01X116723Y1223567D02*
X116746Y1223590D01*
X117694D01*
G01X116723Y1240282D02*
X116763Y1240322D01*
X117767D01*
G01X116723Y1237031D02*
X116779Y1236975D01*
X117716D01*
G01X116723Y1226974D02*
X116729D01*
X116767Y1226936D01*
X117698D01*
G01X163573Y778511D02*
X162597D01*
X162565Y778479D01*
G01X171719Y771818D02*
X170417D01*
G01X162610Y788550D02*
X162568Y788508D01*
X162565D01*
G01X171719Y795243D02*
X170417D01*
G01X171719Y791897D02*
X170446D01*
G01X163535D02*
X162602D01*
X162565Y791934D01*
G01X163573Y815322D02*
X162597D01*
X162565Y815290D01*
G01X171719Y808629D02*
X170417D01*
G01X163573Y801936D02*
X162597D01*
X162565Y801904D01*
G01X171719Y832054D02*
X170417D01*
G01X162610Y825361D02*
X162568Y825319D01*
X162565D01*
G01X171719Y828708D02*
X170446D01*
G01X163535D02*
X162602D01*
X162565Y828745D01*
G01X171719Y845440D02*
X170417D01*
G01X163573Y838747D02*
X162597D01*
X162565Y838715D01*
G01X163573Y852133D02*
X162597D01*
X162565Y852101D01*
G01X162610Y862172D02*
X162568Y862130D01*
X162565D01*
G01X171720Y865519D02*
X170446D01*
G01X163535D02*
X162602D01*
X162566Y865555D01*
G01X171719Y882251D02*
X170417D01*
G01X163573Y875558D02*
X162597D01*
X162565Y875526D01*
G01X171719Y868865D02*
X170417D01*
G01X163573Y888944D02*
X162597D01*
X162565Y888912D01*
G01X162610Y898983D02*
X162568Y898941D01*
X162565D01*
G01X171719Y902330D02*
X170446D01*
G01X163535D02*
X162602D01*
X162565Y902367D01*
G01X163573Y912369D02*
X162597D01*
X162565Y912337D01*
G01X171719Y905676D02*
X170417D01*
G01X163573Y925755D02*
X162597D01*
X162565Y925723D01*
G01X171719Y919062D02*
X170417D01*
G01X171719Y942487D02*
X170417D01*
G01X162610Y935794D02*
X162568Y935752D01*
X162565D01*
G01X171720Y939141D02*
X170446D01*
G01X163535D02*
X162602D01*
X162572Y939171D01*
X162566D01*
G01X163573Y949180D02*
X162597D01*
X162565Y949148D01*
G01X171719Y979298D02*
X170417D01*
G01X171719Y972605D02*
X170417D01*
G01X171719Y992684D02*
X170417D01*
G01X171719Y985991D02*
X170417D01*
G01X171719Y1026149D02*
X170417D01*
G01X171719Y1019456D02*
X170417D01*
G01X162653D02*
X162599Y1019510D01*
X162565D01*
G01X171719Y1039534D02*
X170417D01*
G01X171719Y1032842D02*
X170417D01*
G01X172010Y1059613D02*
X170417D01*
G01X162600D02*
X162038D01*
G01X171719Y1046227D02*
X170417D01*
G01X163573Y1072999D02*
X162597D01*
X162565Y1072967D01*
G01X171719Y1066306D02*
X170417D01*
G01X171719Y1089731D02*
X170417D01*
G01X162610Y1083038D02*
X162568Y1082996D01*
X162565D01*
G01X171719Y1086385D02*
X170446D01*
G01X163535D02*
X162602D01*
X162565Y1086422D01*
G01X163573Y1096424D02*
X162597D01*
X162565Y1096392D01*
G01X163573Y1109810D02*
X162597D01*
X162565Y1109778D01*
G01X171719Y1103117D02*
X170417D01*
G01X171719Y1126542D02*
X170417D01*
G01X162610Y1119849D02*
X162568Y1119807D01*
X162565D01*
G01X171719Y1123196D02*
X170446D01*
G01X163535D02*
X162602D01*
X162565Y1123233D01*
G01X171719Y1139928D02*
X170417D01*
G01X163573Y1133235D02*
X162597D01*
X162565Y1133203D01*
G01X163573Y1146621D02*
X162597D01*
X162565Y1146589D01*
G01X162610Y1156660D02*
X162568Y1156618D01*
X162565D01*
G01X171719Y1160007D02*
X170446D01*
G01X163535D02*
X162602D01*
X162565Y1160044D01*
G01X163573Y1170046D02*
X162597D01*
X162565Y1170014D01*
G01X171719Y1163353D02*
X170417D01*
G01X163573Y1183432D02*
X162597D01*
X162565Y1183400D01*
G01X171719Y1176739D02*
X170417D01*
G01X162610Y1193471D02*
X162568Y1193429D01*
X162565D01*
G01X163573Y1206857D02*
X162597D01*
X162565Y1206825D01*
G01X171719Y1200164D02*
X170417D01*
G01X171719Y1196818D02*
X170446D01*
G01X163535D02*
X162602D01*
X162565Y1196855D01*
G01X163573Y1220243D02*
X162597D01*
X162565Y1220211D01*
G01X171719Y1213550D02*
X170417D01*
G01X171719Y1236975D02*
X170417D01*
G01X162610Y1230282D02*
X162568Y1230240D01*
X162565D01*
G01X171719Y1233629D02*
X170446D01*
G01X163535D02*
X162602D01*
X162565Y1233666D01*
G01X163573Y1243668D02*
X162597D01*
X162565Y1243636D01*
G01X177116Y771817D02*
X176179D01*
X176123Y771873D01*
G01X177167Y775164D02*
X176163D01*
X176123Y775124D01*
G01X177098Y785204D02*
X176154D01*
X176123Y785235D01*
G01X177095Y781857D02*
X176145D01*
X176123Y781835D01*
G01X177167Y798590D02*
X176163D01*
X176123Y798550D01*
G01X177116Y795243D02*
X176179D01*
X176123Y795299D01*
G01X177167Y811975D02*
X176163D01*
X176123Y811935D01*
G01X177116Y808628D02*
X176179D01*
X176123Y808684D01*
G01X177095Y818668D02*
X176145D01*
X176123Y818646D01*
G01X177167Y835401D02*
X176163D01*
X176123Y835361D01*
G01X177116Y832054D02*
X176179D01*
X176123Y832110D01*
G01X177098Y822015D02*
X176154D01*
X176123Y822046D01*
G01X177167Y848786D02*
X176163D01*
X176123Y848746D01*
G01X177116Y845439D02*
X176179D01*
X176123Y845495D01*
G01X177116Y868865D02*
X176179D01*
X176123Y868921D01*
G01X177098Y858826D02*
X176154D01*
X176123Y858857D01*
G01X177095Y855479D02*
X176145D01*
X176123Y855457D01*
G01X177167Y872212D02*
X176163D01*
X176123Y872172D01*
G01X177116Y882250D02*
X176179D01*
X176123Y882306D01*
G01X177167Y885597D02*
X176163D01*
X176123Y885557D01*
G01X177098Y895637D02*
X176154D01*
X176123Y895668D01*
G01X177095Y892290D02*
X176145D01*
X176123Y892268D01*
G01X177167Y909023D02*
X176163D01*
X176123Y908983D01*
G01X177116Y905676D02*
X176179D01*
X176123Y905732D01*
G01X177167Y922408D02*
X176163D01*
X176123Y922368D01*
G01X177116Y919062D02*
X176179D01*
X176123Y919118D01*
G01X177098Y932448D02*
X176154D01*
X176123Y932479D01*
G01X177095Y929101D02*
X176145D01*
X176123Y929079D01*
G01X177167Y945834D02*
X176163D01*
X176123Y945794D01*
G01X177116Y942487D02*
X176179D01*
X176123Y942543D01*
G01X177116Y979298D02*
X176179D01*
X176123Y979354D01*
G01X177116Y972605D02*
X176179D01*
X176123Y972661D01*
G01X177116Y992684D02*
X176179D01*
X176123Y992740D01*
G01X177116Y985991D02*
X176179D01*
X176123Y986047D01*
G01X177116Y1032841D02*
X176179D01*
X176123Y1032897D01*
G01X177116Y1046227D02*
X176179D01*
X176123Y1046283D01*
G01X177116Y1039534D02*
X176179D01*
X176123Y1039590D01*
G01X177167Y1069653D02*
X176163D01*
X176123Y1069613D01*
G01X177116Y1066306D02*
X176179D01*
X176123Y1066362D01*
G01Y1079730D02*
X176161Y1079692D01*
X177098D01*
G01X177095Y1076345D02*
X176145D01*
X176123Y1076323D01*
G01Y1093038D02*
X176163Y1093078D01*
X177167D01*
G01X176123Y1089787D02*
X176179Y1089731D01*
X177116D01*
G01X177167Y1106464D02*
X176163D01*
X176123Y1106424D01*
G01X177116Y1103117D02*
X176179D01*
X176123Y1103173D01*
G01X177116Y1126542D02*
X176179D01*
X176123Y1126598D01*
G01Y1116541D02*
X176161Y1116503D01*
X177098D01*
G01X176123Y1113134D02*
X176145Y1113156D01*
X177095D01*
G01X177167Y1143275D02*
X176163D01*
X176123Y1143235D01*
G01X177116Y1139928D02*
X176179D01*
X176123Y1139984D01*
G01X177167Y1129889D02*
X176163D01*
X176123Y1129849D01*
G01Y1153352D02*
X176129D01*
X176167Y1153314D01*
X177098D01*
G01X177094Y1149968D02*
X176146D01*
X176123Y1149945D01*
G01X177116Y1176739D02*
X176179D01*
X176123Y1176795D01*
G01X177167Y1166700D02*
X176163D01*
X176123Y1166660D01*
G01X177116Y1163353D02*
X176179D01*
X176123Y1163409D01*
G01X177167Y1180086D02*
X176163D01*
X176123Y1180046D01*
G01Y1190163D02*
X176129D01*
X176167Y1190125D01*
X177098D01*
G01X177094Y1186779D02*
X176146D01*
X176123Y1186756D01*
G01X177167Y1203511D02*
X176163D01*
X176123Y1203471D01*
G01X177116Y1200164D02*
X176179D01*
X176123Y1200220D01*
G01X177167Y1216897D02*
X176163D01*
X176123Y1216857D01*
G01X177116Y1213550D02*
X176179D01*
X176123Y1213606D01*
G01X177098Y1226936D02*
X176167D01*
X176129Y1226974D01*
X176123D01*
G01X177094Y1223590D02*
X176146D01*
X176123Y1223567D01*
G01X177167Y1240322D02*
X176163D01*
X176123Y1240282D01*
G01X177116Y1236975D02*
X176179D01*
X176123Y1237031D01*
G01X229817Y778511D02*
X231119D01*
G01X229721Y771817D02*
X231119D01*
G01X229721Y801936D02*
X231119D01*
G01X221965Y795208D02*
X222135D01*
G01X230893Y795243D02*
X231119D01*
G01X221966Y791921D02*
X221990Y791897D01*
G01X231080D02*
X231120Y791937D01*
G01X229721Y815321D02*
X231119D01*
G01X229721Y808629D02*
X231119D01*
G01X229721Y832054D02*
X231119D01*
G01X221966Y828732D02*
X221990Y828708D01*
G01X231080D02*
X231120Y828748D01*
G01X221965Y852087D02*
X221997D01*
G01X229817Y852133D02*
X231119D01*
G01X229817Y845440D02*
X231119D01*
G01X221965Y838584D02*
X222078D01*
G01X229979Y838673D02*
X231119D01*
G01X221965Y862152D02*
X221985Y862172D01*
G01X229847D02*
X231095D01*
X231119Y862148D01*
G01Y882250D02*
X229721D01*
G01X222877D02*
X221990D01*
X221965Y882225D01*
G01Y875505D02*
X222018Y875558D01*
X222877D01*
G01X229721D02*
X231068D01*
X231119Y875507D01*
G01X221965Y868826D02*
X222004Y868865D01*
X222877D01*
G01X229546D02*
X231119D01*
G01Y888943D02*
X229648D01*
G01X222877D02*
X221987D01*
X221965Y888921D01*
G01X231119Y898983D02*
X229847D01*
G01X222035D02*
X222015Y898963D01*
X221965D01*
G01X231119Y902330D02*
X229846D01*
G01X222935D02*
X222020D01*
X221965Y902385D01*
G01X231119Y912305D02*
X229944D01*
G01X222178Y912206D02*
X221965D01*
G01X231119Y905618D02*
X229923D01*
G01X222078Y905513D02*
X221965D01*
G01X220647Y925754D02*
X222877D01*
G01X229721D02*
X232220D01*
G01X221439Y919062D02*
X222877D01*
G01X229721D02*
X231371D01*
G01X231443Y949180D02*
X229721D01*
G01X222877D02*
X221440D01*
G01X221235Y942487D02*
X222877D01*
G01X229721D02*
X231460D01*
G01X222378Y965881D02*
X222477D01*
X222508Y965912D01*
G01X230568D02*
X230604Y965876D01*
X230778D01*
G01X235878Y965978D02*
X236040D01*
X236106Y965912D01*
G01X244070D02*
X244125Y965967D01*
X244378D01*
G01X251978Y965853D02*
X252071D01*
X252130Y965912D01*
G01X260438D02*
X260482Y965868D01*
X260578D01*
G01X287926Y967851D02*
X287973Y967870D01*
G01X221965Y982820D02*
X222173D01*
X222349Y982644D01*
G01X230878D02*
X231119D01*
G01X221965Y976003D02*
X222227D01*
X222279Y975951D01*
G01X230878D02*
X231119D01*
G01X221965Y992581D02*
X222075D01*
X222178Y992684D01*
G01X230878D02*
X231119D01*
G01X221965Y989411D02*
X222104D01*
X222178Y989337D01*
G01X230978D02*
X231119D01*
G01X221965Y1029561D02*
X222112D01*
X222178Y1029495D01*
G01X230878D02*
X231119D01*
G01X221965Y1026083D02*
X222113D01*
X222178Y1026148D01*
G01X230778D02*
X231119D01*
G01X221965Y1046052D02*
X222154D01*
X222329Y1046227D01*
G01X230978D02*
X231119D01*
G01X221965Y1042943D02*
X222022D01*
X222085Y1042880D01*
X222178D01*
G01X230978D02*
X231119D01*
G01X221965Y1036291D02*
X221982D01*
X222085Y1036188D01*
X222178D01*
G01X230978D02*
X231119D01*
G01Y1059613D02*
X231118D01*
G01X223176D02*
X221345D01*
G01X222078Y1052795D02*
X222247D01*
X222372Y1052920D01*
G01X230686D02*
X230768Y1052838D01*
X230978D01*
G01X235523Y1056237D02*
X235655D01*
X235684Y1056266D01*
G01X244258D02*
X244339Y1056185D01*
X244478D01*
G01X251778Y1056298D02*
X251810Y1056266D01*
G01X261240D02*
X261468D01*
G01X220647Y1072999D02*
X222281D01*
G01X230878D02*
X232172D01*
G01X221484Y1066306D02*
X222966D01*
G01X230978D02*
X231329D01*
G01X221582Y1096424D02*
X221965D01*
G01X230978D02*
X231268D01*
G01X221965Y1089625D02*
X222071Y1089731D01*
X224077D01*
G01X230978D02*
X231332D01*
G01X221965Y1109741D02*
X221985D01*
X222054Y1109810D01*
X223091D01*
G01X230878D02*
X231119D01*
G01X221965Y1103042D02*
X222040Y1103117D01*
G01X230978D02*
X231119D01*
G01X221965Y1126486D02*
X222189D01*
X222245Y1126542D01*
G01X231078D02*
X231119D01*
G01X231082Y1119849D02*
X231119D01*
G01X231090Y1123196D02*
X231119D01*
G01X221965Y1139860D02*
X222169D01*
X222237Y1139928D01*
G01X230978D02*
X231119D01*
G01X221965Y1133174D02*
X222240D01*
X222301Y1133235D01*
G01X230983D02*
X231041Y1133177D01*
X231119D01*
G01X221965Y1146521D02*
X222195D01*
X222295Y1146621D01*
G01X230843D02*
X230885Y1146579D01*
X231119D01*
G01Y1176739D02*
X230878D01*
G01X222178D02*
X222055D01*
X221973Y1176657D01*
X221965D01*
G01Y1170014D02*
X222146D01*
X222178Y1170046D01*
G01X230978D02*
X231119D01*
G01X221965Y1163273D02*
X222081D01*
X222161Y1163353D01*
G01X230878D02*
X231119D01*
G01Y1183432D02*
X230978D01*
G01X222178D02*
X222096Y1183350D01*
X221965D01*
G01X222010Y1193471D02*
X221968Y1193429D01*
X221965D01*
G01X231119Y1206857D02*
X230778D01*
G01X222178D02*
X222109D01*
X222063Y1206811D01*
X221965D01*
G01X231119Y1200164D02*
X230878D01*
G01X222178D02*
X222151D01*
X222119Y1200132D01*
X221965D01*
G01X231119Y1196818D02*
X229846D01*
G01X222935D02*
X222002D01*
X221965Y1196855D01*
G01Y1220089D02*
X222011D01*
X222165Y1220243D01*
X222278D01*
G01X230778D02*
X231119D01*
G01X221965Y1213520D02*
X222031D01*
X222061Y1213550D01*
X222178D01*
G01X230878D02*
X231119D01*
G01X221965Y1236910D02*
X222034D01*
X222099Y1236975D01*
G01X230878D02*
X230902Y1236951D01*
X231119D01*
G01Y1243668D02*
X230778D01*
G01X222278D02*
X222085D01*
X222004Y1243587D01*
X221965D01*
G01X235523Y771870D02*
X235576Y771817D01*
X236567D01*
G01X243605D02*
X244677D01*
G01X260778Y778510D02*
X260767D01*
G01X252698D02*
X251613D01*
X251578Y778475D01*
G01X235523Y778587D02*
X235655D01*
X235727Y778515D01*
X236552D01*
G01X243629Y778535D02*
X244677D01*
G01X235523Y781832D02*
X235548Y781857D01*
G01X260678Y798666D02*
X260595D01*
X260518Y798589D01*
G01X252439Y798658D02*
X251878D01*
G01X235523Y801996D02*
X235583Y801936D01*
X235778D01*
G01X244478D02*
X244677D01*
G01X235523Y795306D02*
X235615D01*
X235678Y795243D01*
G01X260678Y808528D02*
X259946D01*
X259846Y808628D01*
G01X252529Y808569D02*
X251578D01*
G01X235523Y815388D02*
X235611D01*
X235678Y815321D01*
G01X243559D02*
X244647D01*
X244677Y815351D01*
G01X235523Y808688D02*
X235583Y808628D01*
X235778D01*
G01X244478D02*
X244677D01*
G01X260478Y801889D02*
X260365D01*
X260318Y801936D01*
G01X252523Y801875D02*
X251778D01*
G01X252078Y832010D02*
X252174D01*
X252218Y832054D01*
G01X259462D02*
X260452D01*
X260478Y832028D01*
G01X235523Y832115D02*
X235698D01*
X235759Y832054D01*
G01X244456D02*
X244677D01*
G01X303774Y896566D02*
X303206Y895998D01*
G01X260578Y845405D02*
X260456D01*
X260422Y845439D01*
G01X252698D02*
X251990D01*
X251946Y845395D01*
X251878D01*
G01X235523Y852172D02*
X235563Y852132D01*
X236567D01*
G01X243605D02*
X244677D01*
G01X235523Y845497D02*
X235577D01*
X235635Y845439D01*
X235678D01*
G01X243559D02*
X244677D01*
G01X260578Y838705D02*
X260423D01*
X260422Y838706D01*
Y838737D01*
X260412Y838747D01*
G01X252698D02*
X251932D01*
X251878Y838693D01*
G01X235523Y838802D02*
X235756D01*
X235811Y838747D01*
G01X244586D02*
X244607Y838768D01*
X244677D01*
G01X235523Y869201D02*
X235778D01*
G01X243659Y868965D02*
X244677D01*
G01X260578Y852096D02*
X260542Y852132D01*
G01X252698D02*
X251924D01*
X251887Y852095D01*
X251878D01*
G01X235523Y875902D02*
X236305D01*
X236609Y875598D01*
G01X243560Y875558D02*
X244607D01*
X244677Y875628D01*
G01Y882253D02*
X244378D01*
G01X235878Y882250D02*
X235651D01*
X235582Y882319D01*
X235523D01*
G01X260578Y875483D02*
X260429D01*
X260354Y875558D01*
G01X252698D02*
X251910D01*
X251878Y875526D01*
G01X259273Y872211D02*
X260791D01*
X260795Y872215D01*
X260815D01*
G01X244677Y888944D02*
X244378D01*
G01X235878D02*
X235793D01*
X235726Y889011D01*
X235523D01*
G01X236867Y895637D02*
X235613D01*
X235523Y895727D01*
G01X235609Y892245D02*
X235523D01*
G01X235033Y919062D02*
X235778D01*
G01X244378D02*
X244909D01*
G01X244677Y912369D02*
X244278D01*
G01X235778D02*
X235687D01*
X235652Y912404D01*
X235523D01*
G01X244677Y905676D02*
X244378D01*
G01X235878D02*
X235723D01*
X235643Y905756D01*
X235523D01*
G01X329449Y941727D02*
X327526Y939804D01*
G01X261944Y925754D02*
X259462D01*
G01X252698D02*
X250308D01*
G01X261103Y919062D02*
X260538D01*
G01X251945D02*
X251084D01*
G01X234978Y925754D02*
X235878D01*
G01X244378D02*
X244934D01*
G01X327259Y949887D02*
X323487Y953659D01*
G01X261056Y942487D02*
X259462D01*
G01X251911D02*
X251211D01*
G01X235011Y949183D02*
X235450D01*
X235453Y949180D01*
G01X244378D02*
X244935D01*
G01X234312Y942487D02*
X235678D01*
G01X244378D02*
X245775D01*
G01X261040Y949180D02*
X260490D01*
G01X252698D02*
X251164D01*
G01X251678Y959219D02*
X251228D01*
G01X244617Y962565D02*
X244378D01*
G01X235986D02*
X235927Y962506D01*
X235878D01*
G01X260578Y982724D02*
X260498Y982644D01*
X259404D01*
G01X252439D02*
X251915D01*
X251878Y982681D01*
G01X235523Y979364D02*
X235812D01*
X235878Y979298D01*
G01X244378D02*
X244677D01*
G01X260578Y976015D02*
X260370D01*
X260306Y975951D01*
G01X251942D02*
X251911Y975982D01*
X251878D01*
G01X260578Y969301D02*
X260433D01*
X260390Y969258D01*
G01X252002D02*
X251911Y969349D01*
X251878D01*
G01X235523Y972638D02*
X235678D01*
X235711Y972605D01*
X235878D01*
G01X244278D02*
X244677D01*
G01X235523Y992761D02*
X235601D01*
X235678Y992684D01*
G01X244478D02*
X244677D01*
G01X251814Y989337D02*
X251729Y989422D01*
X251578D01*
G01X235523Y986068D02*
X235701D01*
X235778Y985991D01*
G01X244378D02*
X244677D01*
G01X235523Y1029465D02*
X235783D01*
X235813Y1029495D01*
G01X244378D02*
X244677D01*
G01X290926Y1011753D02*
X290925D01*
G01X260678Y1029555D02*
X260670D01*
X260610Y1029495D01*
G01X251974D02*
X251930Y1029539D01*
X251878D01*
G01X260578Y1025736D02*
X260567Y1025741D01*
G01X252086Y1026148D02*
X252021Y1026083D01*
X251878D01*
G01X235523Y1042808D02*
X235655D01*
X235727Y1042880D01*
G01X244631D02*
X244677D01*
G01X251878Y1039479D02*
X251975D01*
X252030Y1039534D01*
G01X260540D02*
X260595Y1039479D01*
X260678D01*
G01X235523Y1036132D02*
X235722D01*
X235778Y1036188D01*
G01X244478D02*
X244677D01*
G01X260578Y1032770D02*
X260327D01*
X260256Y1032841D01*
G01X252046D02*
X251986Y1032781D01*
X251878D01*
G01Y1046157D02*
X251998D01*
X252068Y1046227D01*
G01X260526D02*
X260628Y1046125D01*
X260678D01*
G01X260578Y1049638D02*
X260549D01*
X260484Y1049573D01*
G01X252166D02*
X252082Y1049657D01*
X251978D01*
G01X235879Y1049573D02*
X235712Y1049406D01*
X235523D01*
G01X315025Y1021250D02*
X314223Y1022052D01*
G01X260478Y1052899D02*
X260279D01*
X260258Y1052920D01*
G01X252096D02*
X252068Y1052892D01*
X251878D01*
G01X250324Y1072999D02*
X251891D01*
G01X260631D02*
X261865D01*
G01X261858Y1069652D02*
X260323D01*
G01X252266D02*
X250317D01*
G01X234994Y1069587D02*
X236308D01*
G01X244578Y1069652D02*
X244918D01*
G01X235025Y1066306D02*
X235594D01*
G01X244578D02*
X244949D01*
G01X251195Y1093077D02*
X252698D01*
G01X260648D02*
X260865D01*
G01X235089D02*
X235778D01*
G01X244578D02*
X244759D01*
G01X234288Y1089731D02*
X235663D01*
G01X244411D02*
X245702D01*
G01X261066Y1096342D02*
X260984Y1096424D01*
X259486D01*
G01X252822D02*
X251276D01*
X251194Y1096342D01*
G01X251778Y1109783D02*
X252576D01*
G01X259442Y1109772D02*
X260478D01*
G01X260678Y1106508D02*
X259569D01*
G01X252465Y1106544D02*
X251878D01*
G01X235523Y1106403D02*
X236307D01*
X236367Y1106463D01*
G01X243563Y1106459D02*
X244677D01*
G01X235523Y1103181D02*
X235587Y1103117D01*
X236642D01*
G01X243762Y1103139D02*
X244677D01*
G01X251665Y1129946D02*
X251923D01*
X251981Y1129888D01*
G01X235523Y1126605D02*
X236280D01*
G01X243627Y1126615D02*
X244677D01*
G01X235523Y1113115D02*
X235546D01*
G01X306150Y1129163D02*
Y1129313D01*
X306110Y1129353D01*
X306027D01*
G01X260578Y1143295D02*
X259512D01*
G01X252546Y1143327D02*
X251878D01*
G01X235523Y1143193D02*
X235800D01*
X235881Y1143274D01*
G01X244631D02*
X244677D01*
G01X235523Y1139979D02*
X235676D01*
X235727Y1139928D01*
G01X244478D02*
X244677D01*
G01X252470Y1133235D02*
X252390Y1133155D01*
X251778D01*
G01X235523Y1129858D02*
X236424D01*
G01X244553Y1129888D02*
X244610Y1129831D01*
X244677D01*
G01X251778Y1150102D02*
X251963D01*
X252098Y1149967D01*
G01X259782D02*
X259826Y1150011D01*
X259878D01*
G01X244677Y1176739D02*
X244478D01*
G01X235678D02*
X235600Y1176817D01*
X235523D01*
G01X260478Y1169978D02*
X260302D01*
X260234Y1170046D01*
G01X252084D02*
X252021Y1169983D01*
X251778D01*
G01X260578Y1166728D02*
X260435D01*
X260406Y1166699D01*
G01X252220D02*
X252144Y1166775D01*
X251878D01*
G01X235523Y1166643D02*
X235622D01*
X235678Y1166699D01*
G01X244478D02*
X244677D01*
G01X235523Y1163414D02*
X235617D01*
X235678Y1163353D01*
G01X244478D02*
X244677D01*
G01Y1180085D02*
X244631D01*
G01X235778D02*
X235714Y1180021D01*
X235523D01*
G01X236498Y1190125D02*
X235567D01*
X235529Y1190163D01*
X235523D01*
G01X236494Y1186779D02*
X235546D01*
X235523Y1186756D01*
G01X244677Y1203510D02*
X244631D01*
G01X235778D02*
X235635D01*
X235555Y1203430D01*
X235523D01*
G01X244677Y1200164D02*
X244478D01*
G01X235678D02*
X235608Y1200234D01*
X235523D01*
G01X251878Y1220186D02*
X252071D01*
X252128Y1220243D01*
G01X260254D02*
X260316Y1220181D01*
X260578D01*
G01X260678Y1216938D02*
X260464D01*
X260422Y1216896D01*
G01X252108D02*
X252044Y1216960D01*
X251878D01*
G01X235523Y1216850D02*
X235532D01*
X235578Y1216896D01*
G01X244378D02*
X244677D01*
G01X235523Y1213578D02*
X235579D01*
X235607Y1213550D01*
X235778D01*
G01X244378D02*
X244677D01*
G01X260478Y1240365D02*
X260326D01*
X260282Y1240321D01*
G01X252142D02*
X252102Y1240361D01*
X251978D01*
G01X244613Y1240324D02*
X244381D01*
X244378Y1240321D01*
G01X235678D02*
X235519D01*
X235469Y1240271D01*
X235459D01*
G01X235523Y1236975D02*
X235778D01*
G01X244378D02*
X244467D01*
X244498Y1237006D01*
X244677D01*
G01X260578Y1243616D02*
X260410D01*
X260358Y1243668D01*
G01X252182D02*
X252118Y1243604D01*
X251978D01*
G01X303457Y854272D02*
X303454D01*
G01X330301Y940875D02*
X328030Y938604D01*
G01X312589Y1020122D02*
X311841Y1020870D01*
G01X571817Y1011133D02*
X572194D01*
G01X571525Y1008615D02*
X571817D01*
G01X621227Y993046D02*
X621387Y992886D01*
G01X627967Y992684D02*
X629156D01*
X629227Y992755D01*
G01X621227Y771859D02*
X621361D01*
X621403Y771817D01*
G01X621027Y778549D02*
X621066Y778510D01*
X622376D01*
G01X629227Y778573D02*
X629527D01*
G01X621227Y785286D02*
X621246D01*
G01X621227Y781802D02*
X621247D01*
G01X629181Y781774D02*
X629227D01*
G01X621227Y815363D02*
X621361D01*
X621403Y815321D01*
G01X621227Y808670D02*
X621361D01*
X621403Y808628D01*
G01X563228Y839144D02*
X563670Y838702D01*
Y833105D01*
G01X621227Y801978D02*
X621361D01*
X621403Y801936D01*
G01X621227Y795285D02*
X621361D01*
X621403Y795243D01*
G01X621227Y822040D02*
X621253Y822014D01*
X622750D01*
G01X629198Y822071D02*
X629227D01*
G01X621227Y818626D02*
X621269Y818668D01*
X622243D01*
G01X626480D02*
X628055D01*
G01X621227Y845513D02*
X621246D01*
G01X621227Y838828D02*
X621246D01*
G01X621227Y832082D02*
X621255Y832054D01*
G01X620474Y919141D02*
X620553Y919062D01*
X621312D01*
G01X629171D02*
X630045D01*
G01X621227Y875612D02*
X621246D01*
G01X621227Y868917D02*
X621246D01*
G01X621227Y852152D02*
X621246Y852133D01*
G01X621227Y858904D02*
X621306Y858825D01*
G01X621227Y855415D02*
X621246D01*
G01X628700Y855479D02*
X629227D01*
G01X620559Y922373D02*
X620594Y922408D01*
X621281D01*
G01X629167D02*
X629727D01*
X629809Y922326D01*
G01X620402Y945758D02*
X620477Y945833D01*
X621345D01*
G01X629100D02*
X629729D01*
X629804Y945758D01*
G01X621227Y939140D02*
X621246D01*
G01X629170Y939077D02*
X629227D01*
G01X619254Y932531D02*
X619338Y932447D01*
X621474D01*
G01X629156D02*
X631027D01*
G01X619254Y929101D02*
X621273D01*
G01X629115D02*
X631027D01*
G01X585074Y976788D02*
X585121Y976835D01*
G01X621227Y986078D02*
X621234D01*
X621321Y985991D01*
G01X629070Y986033D02*
X629227D01*
G01X621227Y979392D02*
X621319D01*
G01X629070Y979371D02*
X629227D01*
G01X645369Y969356D02*
X645271Y969258D01*
X643924D01*
G01X637388Y969355D02*
X637369D01*
G01X629124Y968804D02*
X629015Y968913D01*
G01X621470Y969179D02*
X621227D01*
G01X658927Y962528D02*
X658790D01*
G01X650205Y962565D02*
X650164D01*
G01X637408Y965865D02*
X637369D01*
G01X620497Y955873D02*
X620413D01*
G01X621351Y972654D02*
X621370D01*
G01X585886Y1016673D02*
X585185Y1016383D01*
G01X571817Y1013651D02*
X572194D01*
G01X621227Y1029454D02*
X621295D01*
G01X576493Y1022372D02*
X576783Y1022662D01*
G01X579334Y1021216D02*
X579588Y1021470D01*
G01X621227Y1042813D02*
X621246D01*
G01X629027Y1042823D02*
X629227D01*
G01X581898Y1020219D02*
X582119Y1020440D01*
G01X583576Y1018335D02*
X583900Y1018659D01*
G01X637570Y1056305D02*
X637551D01*
G01X629227Y1056194D02*
X629221D01*
G01X621246Y1056227D02*
X621227D01*
G01X658927Y1052993D02*
X658854Y1052920D01*
X657042D01*
G01X651070Y1052948D02*
X651051D01*
G01X645051Y1052821D02*
X644957D01*
G01X637670Y1052867D02*
X637651D01*
G01X629227Y1052979D02*
X629168Y1052920D01*
X627585D01*
G01X621246Y1052979D02*
X621227D01*
G01X573353Y1026601D02*
X572834Y1026082D01*
G01X621246Y1049522D02*
X621227D01*
G01X575201Y1024752D02*
X574958Y1024509D01*
G01X620122Y1093077D02*
X621357D01*
G01X629097D02*
X629931D01*
G01X620122Y1086384D02*
X621333D01*
G01X629162D02*
X629931D01*
G01X599311Y1073062D02*
Y1073063D01*
G01X619633Y1069652D02*
X620864D01*
G01X629159D02*
X630752D01*
G01X620567Y1066306D02*
X621217D01*
G01X629204D02*
X629992D01*
G01X620138Y1079691D02*
X621246D01*
G01X629145D02*
X629689D01*
X629761Y1079763D01*
G01X620138Y1076344D02*
X621246D01*
G01X629141Y1076345D02*
X629684D01*
X629770Y1076259D01*
G01X621227Y1126676D02*
X621246D01*
G01X621227Y1109845D02*
X621278D01*
G01X620567Y1103117D02*
X621297D01*
G01X629227Y1103244D02*
X630376D01*
G01X621227Y1113129D02*
X621253D01*
G01X629218Y1113075D02*
X629227D01*
G01X621227Y1146689D02*
X621295Y1146621D01*
X621996D01*
G01X621227Y1140075D02*
X621246D01*
G01X621227Y1133336D02*
X621246D01*
G01X621227Y1153364D02*
X621252D01*
G01X629019Y1153314D02*
X629044Y1153339D01*
X629227D01*
G01X621227Y1149914D02*
X621247D01*
G01X629217Y1149884D02*
X629227D01*
G01X621227Y1170065D02*
X621246Y1170046D01*
G01X621227Y1163506D02*
X621380Y1163353D01*
G01X562137Y1155727D02*
X562765Y1157243D01*
G01X621227Y1213576D02*
X621246D01*
G01X621227Y1237040D02*
X621246D01*
G01X628439Y1236975D02*
X629152D01*
X629188Y1237011D01*
X629227D01*
G01X621451Y1216873D02*
X621470D01*
G01X621227Y1226962D02*
X621246D01*
G01X621227Y1223569D02*
X621247D01*
G01X626480Y1223589D02*
X628055D01*
G01X548944Y1168026D02*
X549145Y1168227D01*
G01X621227Y1243691D02*
X621305D01*
X621328Y1243668D01*
X622271D01*
G01X628687D02*
X629083D01*
X629122Y1243707D01*
X629227D01*
G01X637545Y778511D02*
X637503Y778469D01*
X637369D01*
G01X637545Y771818D02*
X637503Y771776D01*
X637369D01*
G01X637388Y788498D02*
X637369D01*
G01X637545Y795243D02*
X637503Y795201D01*
X637369D01*
G01X637382Y791972D02*
X637369D01*
G01X637545Y815321D02*
X637503Y815279D01*
X637369D01*
G01X637545Y808628D02*
X637503Y808586D01*
X637369D01*
G01X637545Y801936D02*
X637503Y801894D01*
X637369D01*
G01X637388Y831993D02*
X637369D01*
G01X645369Y825320D02*
X645346D01*
G01X637388Y825246D02*
X637369D01*
G01X645369Y828783D02*
X645350D01*
G01X637395Y828770D02*
X637369D01*
G01X645369Y845420D02*
X645266D01*
G01X637499Y845440D02*
X637430D01*
X637369Y845379D01*
G01X637388Y838695D02*
X637369D01*
G01X645369Y852065D02*
X645301Y852133D01*
G01X637498Y852079D02*
X637369D01*
G01X637411Y865570D02*
X637369D01*
G01X636727Y882251D02*
X636648D01*
G01X645369Y875500D02*
X645307D01*
X645249Y875558D01*
G01X637388Y875520D02*
X637369D01*
G01X645369Y868807D02*
X645307D01*
X645249Y868865D01*
G01X637388Y868831D02*
X637369D01*
G01X636833Y888944D02*
X636648D01*
G01X645369Y898888D02*
X645295D01*
G01X636641Y898983D02*
X636599D01*
G01X636646Y902330D02*
X636622D01*
G01X646194Y912369D02*
X645344D01*
G01X636833D02*
X636648D01*
G01X636727Y905676D02*
X636648D01*
G01X646602Y925755D02*
X645325D01*
G01X637509D02*
X635745D01*
X635644Y925654D01*
G01X646011Y918993D02*
X645942Y919062D01*
X645186D01*
G01X637440D02*
X636746D01*
X636694Y919010D01*
G01X646130Y942414D02*
X646057Y942487D01*
X645296D01*
G01X637482D02*
X636770D01*
X636695Y942412D01*
G01X647002Y935794D02*
X645287D01*
G01X637454D02*
X635844D01*
X635778Y935728D01*
G01X647002Y939141D02*
X645297D01*
G01X637464D02*
X635854D01*
X635778Y939217D01*
G01X645821Y949094D02*
X645735Y949180D01*
X644588D01*
G01X637452D02*
X636555D01*
G01X637388Y982728D02*
X637369D01*
G01X637388Y976007D02*
X637369D01*
G01X645369Y992684D02*
X644955D01*
G01X637388Y993422D02*
X637369Y993441D01*
G01X637388Y989389D02*
X637369D01*
G01X637388Y1029648D02*
X637369D01*
G01X645369Y1049619D02*
X645366D01*
G01X637388Y1049636D02*
X637369D01*
G01X646073Y1059613D02*
X644653D01*
G01X637492D02*
X636648D01*
G01X646894Y1072999D02*
X644684D01*
G01X637424D02*
X635775D01*
G01X646073Y1066306D02*
X645289D01*
G01X637699D02*
X636579D01*
X636264Y1065991D01*
G01X646073Y1089731D02*
X645320D01*
G01X637417D02*
X636264D01*
G01X645974Y1082988D02*
X645924Y1083038D01*
X645243D01*
G01X637450D02*
X636001D01*
X635939Y1082976D01*
G01X645974Y1086466D02*
X645893Y1086385D01*
X645136D01*
G01X637432D02*
X636004D01*
X635960Y1086429D01*
G01X646073Y1096022D02*
X645069D01*
G01X637433Y1096424D02*
X636264D01*
G01X637388Y1109773D02*
X637369D01*
G01X637375Y1106534D02*
X637369D01*
G01X637388Y1126498D02*
X637369D01*
G01X637388Y1119787D02*
X637369D01*
G01X637388Y1123242D02*
X637369D01*
G01X645369Y1139893D02*
X645334Y1139928D01*
G01X640599D02*
X637498D01*
X637472Y1139902D01*
X637369D01*
G01X645369Y1133264D02*
X645330D01*
G01X640599Y1133235D02*
X637403D01*
X637369Y1133201D01*
G01X645369Y1146605D02*
X645353Y1146621D01*
G01X640599D02*
X637522D01*
X637490Y1146589D01*
X637369D01*
G01X637388Y1156598D02*
X637369D01*
G01X637388Y1160053D02*
X637369D01*
G01X645369Y1170001D02*
X645324Y1170046D01*
X642183D01*
G01X637438Y1170017D02*
X637369D01*
G01X645369Y1163308D02*
X645324Y1163353D01*
X642183D01*
G01X637438Y1163324D02*
X637369D01*
G01X636833Y1183432D02*
X636648D01*
G01X636727Y1176739D02*
X636648D01*
G01X637388Y1193471D02*
X636590D01*
G01X637388Y1206857D02*
X636387D01*
G01X637388Y1200164D02*
X636656D01*
G01X645369Y1196863D02*
X645322D01*
G01X637388Y1196818D02*
X636590D01*
G01X637388Y1220200D02*
X637369D01*
G01X637388Y1213528D02*
X637369D01*
G01X637388Y1236940D02*
X637369D01*
G01X637388Y1230167D02*
X637369D01*
G01X637388Y1233629D02*
X637369D01*
G01X645369Y1243630D02*
X645324D01*
X645286Y1243668D01*
X644341D01*
G01X637388Y1243521D02*
X637369D01*
G01X651103Y771817D02*
X651061Y771859D01*
X650927D01*
G01X651103Y778510D02*
X651061Y778552D01*
X650927D01*
G01X650946Y785228D02*
X650927D01*
G01X650946Y781829D02*
X650927D01*
G01X651103Y801936D02*
X651061Y801978D01*
X650927D01*
G01X651103Y795243D02*
X651061Y795285D01*
X650927D01*
G01X651103Y815321D02*
X651061Y815363D01*
X650927D01*
G01X651103Y808628D02*
X651061Y808670D01*
X650927D01*
G01X651009Y818588D02*
X650927D01*
G01X651103Y832054D02*
X651061Y832096D01*
X650927D01*
G01X657678Y822014D02*
X656106D01*
G01X651448D02*
X650954D01*
X650931Y822037D01*
X650927D01*
G01X658927Y852186D02*
X658837D01*
G01X650943Y852197D02*
X650927D01*
G01X651103Y845439D02*
X651061Y845481D01*
X650927D01*
G01X651103Y838747D02*
X651061Y838789D01*
X650927D01*
G01X658927Y868939D02*
X658798D01*
X658724Y868865D01*
G01X650967Y868922D02*
X650927D01*
G01X650946Y858850D02*
X650927D01*
G01X650946Y855451D02*
X650927D01*
G01X658927Y875632D02*
X658798D01*
X658724Y875558D01*
G01X650967Y875615D02*
X650927D01*
G01X658927Y882324D02*
X658798D01*
X658724Y882250D01*
G01X650967Y882307D02*
X650927D01*
G01X658927Y889017D02*
X658798D01*
X658724Y888943D01*
G01X650967Y889000D02*
X650927D01*
G01X650946Y895661D02*
X650927D01*
G01X650946Y892262D02*
X650927D01*
G01X659797Y919062D02*
X658823D01*
G01X651082D02*
X650126D01*
G01X650992Y912428D02*
X650927D01*
G01X650996Y905731D02*
X650927D01*
G01X660861Y925821D02*
X660795Y925755D01*
X658883D01*
G01X651051D02*
X650282D01*
X650227Y925810D01*
G01X660494Y932491D02*
X660451Y932448D01*
X658884D01*
G01X650970D02*
X649277D01*
X649253Y932472D01*
G01X660494Y929072D02*
X660465Y929101D01*
X658898D01*
G01X650974D02*
X649253D01*
G01X659310Y945379D02*
X658927Y945762D01*
G01X651056Y945834D02*
X650231D01*
G01X659714Y942580D02*
X659621Y942487D01*
X658847D01*
G01X651034D02*
X650232D01*
X650194Y942525D01*
G01X651003Y979330D02*
X650927D01*
G01X650996Y972667D02*
X650927D01*
G01X650979Y992761D02*
X650927D01*
G01X650996Y986028D02*
X650927D01*
G01X650947Y1032903D02*
X650927D01*
G01X651530Y1046227D02*
X650960D01*
X650927Y1046260D01*
G01X650996Y1039589D02*
X650927D01*
G01X660076Y1072999D02*
X658878D01*
G01X651056D02*
X650267D01*
G01X660076Y1066306D02*
X658629D01*
G01X651111D02*
X650267D01*
G01X660578Y1079692D02*
X658884D01*
G01X650970D02*
X649518D01*
G01X660646Y1076345D02*
X658898D01*
G01X650974D02*
X649497D01*
G01X659210Y1092633D02*
X658765Y1093078D01*
G01X651032D02*
X649822D01*
G01X661050Y1089731D02*
X658512D01*
G01X651064D02*
X649518D01*
G01X650996Y1109845D02*
X650927D01*
G01X650996Y1103149D02*
X650927D01*
G01X658927Y1126587D02*
X658882Y1126542D01*
X655741D01*
G01X650996Y1126571D02*
X650927D01*
G01X650946Y1116527D02*
X650927D01*
G01X650946Y1113128D02*
X650927D01*
G01X658927Y1146666D02*
X658882Y1146621D01*
X655741D01*
G01X650996Y1146650D02*
X650927D01*
G01X658927Y1139973D02*
X658882Y1139928D01*
X655741D01*
G01X650996Y1139957D02*
X650927D01*
G01X658927Y1133280D02*
X658882Y1133235D01*
X655741D01*
G01X650996Y1133264D02*
X650927D01*
G01X650946Y1153338D02*
X650927D01*
G01X650946Y1149940D02*
X650927D01*
G01X658927Y1176784D02*
X658882Y1176739D01*
X655741D01*
G01X650996Y1176768D02*
X650927D01*
G01X658927Y1170091D02*
X658882Y1170046D01*
X655741D01*
G01X650996Y1170075D02*
X650927D01*
G01X658927Y1163398D02*
X658882Y1163353D01*
X655741D01*
G01X650996Y1163382D02*
X650927D01*
G01X658927Y1183470D02*
X658889Y1183432D01*
X656500D01*
G01X650996Y1183454D02*
X650927D01*
G01X650946Y1190145D02*
X650927D01*
G01X650946Y1186759D02*
X650945D01*
X650942Y1186756D01*
X650927D01*
G01X658927Y1206903D02*
X658881Y1206857D01*
X656376D01*
G01X650996Y1206893D02*
X650927D01*
G01X658927Y1200209D02*
X658882Y1200164D01*
X655731D01*
G01X650996Y1200206D02*
X650927D01*
G01X658927Y1220289D02*
X658881Y1220243D01*
X656077D01*
G01X651030Y1220269D02*
X650927D01*
G01X658927Y1213571D02*
X658906Y1213550D01*
X656754D01*
G01X650996Y1213570D02*
X650927D01*
G01X657678Y1226936D02*
X656106D01*
G01X651057D02*
X651027Y1226966D01*
X650927D01*
G01X651045Y1223547D02*
X651023Y1223569D01*
X650927D01*
G01X658927Y1243715D02*
X658690D01*
X658643Y1243668D01*
X658489D01*
G01X651239D02*
X651191Y1243716D01*
X650927D01*
G01X658927Y1237013D02*
X658851D01*
X658813Y1236975D01*
G01X650996Y1237014D02*
X650927D01*
G01X696233Y778511D02*
X696048D01*
G01X696127Y771818D02*
X696048D01*
G01X696150Y788550D02*
X696167D01*
G01X696233Y801936D02*
X696048D01*
G01X696127Y795243D02*
X696048D01*
G01X696150Y791897D02*
X696252D01*
G01X696233Y815322D02*
X696048D01*
G01X696127Y808629D02*
X696048D01*
G01X696127Y832054D02*
X696048D01*
G01X696150Y825361D02*
X696167D01*
G01X696150Y828708D02*
X696252D01*
G01X696233Y852133D02*
X696048D01*
G01X696127Y845440D02*
X696048D01*
G01X696233Y838747D02*
X696048D01*
G01X696150Y862172D02*
X696167D01*
G01X696150Y865519D02*
X696252D01*
G01X696127Y882251D02*
X696048D01*
G01X696233Y875558D02*
X696048D01*
G01X696127Y868865D02*
X696048D01*
G01X696233Y888944D02*
X696048D01*
G01X696150Y898983D02*
X696167D01*
G01X696150Y902330D02*
X696252D01*
G01X696233Y912369D02*
X696048D01*
G01X696127Y905676D02*
X696048D01*
G01X696233Y925755D02*
X696048D01*
G01X696127Y919062D02*
X696048D01*
G01X696233Y949180D02*
X696048D01*
G01X696127Y942487D02*
X696048D01*
G01X696150Y935794D02*
X696167D01*
G01X696150Y939141D02*
X696252D01*
G01X696113Y982644D02*
X696167D01*
G01X696113Y975951D02*
X696167D01*
G01X696113Y989337D02*
X696167D01*
G01X696113Y1029495D02*
X696167D01*
G01X696077Y1019456D02*
X696157D01*
G01X696113Y1049573D02*
X696167D01*
G01X695634Y1042880D02*
X695801D01*
G01X695844Y1036188D02*
X695729D01*
G01X696577Y1059556D02*
X696788D01*
G01X696233Y1072999D02*
X696048D01*
G01X696127Y1066306D02*
X696048D01*
G01X696127Y1089731D02*
X696048D01*
G01X696150Y1083038D02*
X696167D01*
G01X696150Y1086385D02*
X696252D01*
G01X696233Y1096424D02*
X696048D01*
G01X696233Y1109810D02*
X696048D01*
G01X696127Y1103117D02*
X696048D01*
G01X696127Y1126542D02*
X696048D01*
G01X696150Y1119849D02*
X696167D01*
G01X696150Y1123196D02*
X696252D01*
G01X696127Y1139928D02*
X696048D01*
G01X696233Y1133235D02*
X696048D01*
G01X696233Y1146621D02*
X696048D01*
G01X696150Y1156660D02*
X696167D01*
G01X696150Y1160007D02*
X696252D01*
G01X696127Y1176739D02*
X696048D01*
G01X696233Y1170046D02*
X696048D01*
G01X696127Y1163353D02*
X696048D01*
G01X696233Y1183432D02*
X696048D01*
G01X696150Y1193471D02*
X696167D01*
G01X696233Y1206857D02*
X696048D01*
G01X696127Y1200164D02*
X696048D01*
G01X696150Y1196818D02*
X696252D01*
G01X696233Y1220243D02*
X696048D01*
G01X696127Y1213550D02*
X696048D01*
G01X696127Y1236975D02*
X696048D01*
G01X696150Y1230282D02*
X696167D01*
G01X696150Y1233629D02*
X696252D01*
G01X696233Y1243668D02*
X696048D01*
G01X710327Y771845D02*
X710346D01*
G01X710327Y778538D02*
X710346D01*
G01X710327Y785228D02*
X710346D01*
G01X710327Y781829D02*
X710346D01*
G01X710327Y801964D02*
X710346D01*
G01X710327Y795271D02*
X710346D01*
G01X710327Y815349D02*
X710346D01*
G01X710327Y808656D02*
X710346D01*
G01X710327Y818640D02*
X710346D01*
G01X710327Y832082D02*
X710346D01*
G01X710327Y822039D02*
X710346D01*
G01X710327Y852160D02*
X710346D01*
G01X710327Y845467D02*
X710346D01*
G01X710327Y838775D02*
X710346D01*
G01X710327Y868893D02*
X710346D01*
G01X710327Y858850D02*
X710346D01*
G01X710327Y855451D02*
X710346D01*
G01X710327Y875586D02*
X710346D01*
G01X710327Y882278D02*
X710346D01*
G01X710327Y888971D02*
X710346D01*
G01X710327Y895661D02*
X710346D01*
G01X710327Y892262D02*
X710346D01*
G01X710327Y912397D02*
X710346D01*
G01X710327Y905704D02*
X710346D01*
G01X710327Y925782D02*
X710346D01*
G01X710327Y919090D02*
X710346D01*
G01X710327Y932472D02*
X710346D01*
G01X710327Y929073D02*
X710346D01*
G01X710327Y949208D02*
X710346D01*
G01X710327Y942515D02*
X710346D01*
G01X710327Y979340D02*
X710346D01*
G01X710327Y972647D02*
X710346D01*
G01X710327Y992726D02*
X710346D01*
G01X710327Y986033D02*
X710346D01*
G01X710327Y1032883D02*
X710346D01*
G01X710327Y1046269D02*
X710346D01*
G01X710327Y1039576D02*
X710346D01*
G01X710327Y1073027D02*
X710346D01*
G01X710327Y1066334D02*
X710346D01*
G01X710327Y1079716D02*
X710346D01*
G01X710327Y1076317D02*
X710346D01*
G01X710327Y1096452D02*
X710346D01*
G01X710327Y1089759D02*
X710346D01*
G01X710327Y1109838D02*
X710346D01*
G01X710327Y1103145D02*
X710346D01*
G01X710327Y1126570D02*
X710346D01*
G01X710327Y1116527D02*
X710346D01*
G01X710327Y1113128D02*
X710346D01*
G01X710327Y1146649D02*
X710346D01*
G01X710327Y1139956D02*
X710346D01*
G01X710327Y1133263D02*
X710346D01*
G01X710327Y1153338D02*
X710346D01*
G01X710327Y1149940D02*
X710346D01*
G01X710327Y1176767D02*
X710346D01*
G01X710327Y1170074D02*
X710346D01*
G01X710327Y1163381D02*
X710346D01*
G01X710327Y1183460D02*
X710346D01*
G01X710327Y1190149D02*
X710346D01*
G01X710327Y1186751D02*
X710346D01*
G01X710327Y1206885D02*
X710346D01*
G01X710327Y1200192D02*
X710346D01*
G01X710327Y1220271D02*
X710346D01*
G01X710327Y1213578D02*
X710346D01*
G01X710327Y1226960D02*
X710346D01*
G01X710327Y1223562D02*
X710346D01*
G01X710327Y1243696D02*
X710346D01*
G01X710327Y1237003D02*
X710346D01*
G01X755633Y778511D02*
X755448D01*
G01X755527Y771818D02*
X755448D01*
G01X755550Y788550D02*
X755567D01*
G01X755527Y795243D02*
X755448D01*
G01X755550Y791897D02*
X755652D01*
G01X755633Y815322D02*
X755448D01*
G01X755527Y808629D02*
X755448D01*
G01X755633Y801936D02*
X755448D01*
G01X755527Y832054D02*
X755448D01*
G01X755550Y825361D02*
X755567D01*
G01X755550Y828708D02*
X755652D01*
G01X755527Y845440D02*
X755448D01*
G01X755633Y838747D02*
X755448D01*
G01X755633Y852133D02*
X755448D01*
G01X755550Y862172D02*
X755567D01*
G01X755550Y865519D02*
X755652D01*
G01X755527Y882251D02*
X755448D01*
G01X755633Y875558D02*
X755448D01*
G01X755527Y868865D02*
X755448D01*
G01X755633Y888944D02*
X755448D01*
G01X755550Y898983D02*
X755567D01*
G01X755550Y902330D02*
X755652D01*
G01X755633Y912369D02*
X755448D01*
G01X755527Y905676D02*
X755448D01*
G01X764873Y925755D02*
X764729D01*
G01X755633D02*
X755064D01*
G01X764873Y919062D02*
X764729D01*
G01X755633D02*
X755064D01*
G01X764873Y942487D02*
X764729D01*
G01X755633D02*
X755064D01*
G01X755296Y935794D02*
X755567D01*
G01X764148D02*
X764873D01*
G01X755509Y939141D02*
X755652D01*
G01X764145D02*
X764988D01*
G01X764873Y949180D02*
X764729D01*
G01X755633D02*
X755064D01*
G01X755513Y982644D02*
X755567D01*
G01X755513Y975951D02*
X755567D01*
G01X755513Y989337D02*
X755567D01*
G01X755513Y1029495D02*
X755567D01*
G01X755477Y1019456D02*
X755557D01*
G01X755034Y1042880D02*
X755201D01*
G01X755129Y1036188D02*
X755244D01*
G01X764873Y1059613D02*
X764729D01*
G01X755633D02*
X755064D01*
G01X755513Y1049573D02*
X755567D01*
G01X764873Y1072999D02*
X764729D01*
G01X755633D02*
X755064D01*
G01X764873Y1066306D02*
X764729D01*
G01X755633D02*
X755064D01*
G01X764873Y1089731D02*
X764729D01*
G01X755633D02*
X755064D01*
G01X755296Y1083038D02*
X755567D01*
G01X764148D02*
X764873D01*
G01X755509Y1086385D02*
X755652D01*
G01X764145D02*
X764988D01*
G01X764873Y1096424D02*
X764729D01*
G01X755633D02*
X755064D01*
G01X755633Y1109810D02*
X755023D01*
G01X755527Y1103117D02*
X755448D01*
G01X755527Y1126542D02*
X755448D01*
G01X755550Y1119849D02*
X755567D01*
G01X755550Y1123196D02*
X755652D01*
G01X755527Y1139928D02*
X755448D01*
G01X755633Y1133235D02*
X755448D01*
G01X755633Y1146621D02*
X755448D01*
G01X755550Y1156660D02*
X755567D01*
G01X755550Y1160007D02*
X755652D01*
G01X755633Y1170046D02*
X755448D01*
G01X755527Y1163353D02*
X755448D01*
G01X755257Y1183432D02*
X755186D01*
G01X755527Y1176739D02*
X755448D01*
G01X755550Y1193471D02*
X755567D01*
G01X755633Y1206857D02*
X755448D01*
G01X755527Y1200164D02*
X755448D01*
G01X755550Y1196818D02*
X755652D01*
G01X755633Y1220243D02*
X755448D01*
G01X755527Y1213550D02*
X755448D01*
G01X755527Y1236975D02*
X755448D01*
G01X755550Y1230282D02*
X755567D01*
G01X755550Y1233629D02*
X755652D01*
G01X755633Y1243668D02*
X755448D01*
G01X769727Y771845D02*
X769746D01*
G01X769727Y778538D02*
X769746D01*
G01X769727Y785228D02*
X769746D01*
G01X769727Y781829D02*
X769746D01*
G01X769727Y801964D02*
X769746D01*
G01X769727Y795271D02*
X769746D01*
G01X769727Y815349D02*
X769746D01*
G01X769727Y808656D02*
X769746D01*
G01X769727Y832082D02*
X769746D01*
G01X769727Y822039D02*
X769746D01*
G01X769727Y818640D02*
X769746D01*
G01X769727Y852160D02*
X769746D01*
G01X769727Y845467D02*
X769746D01*
G01X769727Y838775D02*
X769746D01*
G01X769727Y868893D02*
X769746D01*
G01X769727Y858850D02*
X769746D01*
G01X769727Y855451D02*
X769746D01*
G01X769727Y875586D02*
X769746D01*
G01X769727Y882278D02*
X769746D01*
G01X769727Y888971D02*
X769746D01*
G01X769727Y895661D02*
X769746D01*
G01X769727Y892262D02*
X769746D01*
G01X769727Y912397D02*
X769746D01*
G01X769727Y905704D02*
X769746D01*
G01X769067Y925754D02*
X769774D01*
G01X777515D02*
X778876D01*
G01X769067Y919062D02*
X769774D01*
G01X777679D02*
X778876D01*
G01X768854Y929101D02*
X769774D01*
G01X777698D02*
X778431D01*
G01X769067Y949180D02*
X769774D01*
G01X777515D02*
X778876D01*
G01X769067Y942487D02*
X769774D01*
G01X777679D02*
X778876D01*
G01X769067Y932448D02*
X769770D01*
G01X777684D02*
X778546D01*
G01X769727Y979340D02*
X769746D01*
G01X769727Y972647D02*
X769746D01*
G01X769727Y992726D02*
X769746D01*
G01X769727Y986033D02*
X769746D01*
G01X769727Y1046269D02*
X769746D01*
G01X769727Y1039576D02*
X769746D01*
G01X769727Y1032883D02*
X769746D01*
G01X769067Y1072999D02*
X769774D01*
G01X777515D02*
X778876D01*
G01X769067Y1066306D02*
X769774D01*
G01X777679D02*
X778876D01*
G01X768854Y1076345D02*
X769774D01*
G01X777698D02*
X778431D01*
G01X769067Y1096424D02*
X769774D01*
G01X777515D02*
X778876D01*
G01X769067Y1089731D02*
X769774D01*
G01X777679D02*
X778876D01*
G01X769067Y1079692D02*
X769770D01*
G01X777684D02*
X778546D01*
G01X769727Y1109838D02*
X769746D01*
G01X769727Y1103145D02*
X769746D01*
G01X769727Y1126570D02*
X769746D01*
G01X769727Y1116527D02*
X769746D01*
G01X769727Y1113128D02*
X769746D01*
G01X769727Y1139956D02*
X769746D01*
G01X769727Y1133263D02*
X769746D01*
G01X769727Y1146649D02*
X769746D01*
G01X769727Y1153338D02*
X769746D01*
G01X769727Y1149940D02*
X769746D01*
G01X769727Y1176767D02*
X769746D01*
G01X769727Y1170074D02*
X769746D01*
G01X769727Y1163381D02*
X769746D01*
G01X769727Y1183460D02*
X769746D01*
G01X769727Y1190149D02*
X769746D01*
G01X769727Y1186751D02*
X769746D01*
G01X769727Y1206885D02*
X769746D01*
G01X769727Y1200192D02*
X769746D01*
G01X769727Y1220271D02*
X769746D01*
G01X769727Y1213578D02*
X769746D01*
G01X769727Y1223562D02*
X769746D01*
G01X769727Y1243696D02*
X769746D01*
G01X769727Y1237003D02*
X769746D01*
G01X769727Y1226960D02*
X769746D01*
G01X815033Y778511D02*
X814848D01*
G01X814927Y771818D02*
X814848D01*
G01X814950Y788550D02*
X814967D01*
G01X814927Y795243D02*
X814848D01*
G01X814950Y791897D02*
X815052D01*
G01X815033Y815322D02*
X814848D01*
G01X814927Y808629D02*
X814848D01*
G01X815033Y801936D02*
X814848D01*
G01X814927Y832054D02*
X814848D01*
G01X814950Y825361D02*
X814967D01*
G01X814950Y828708D02*
X815052D01*
G01X814927Y845440D02*
X814848D01*
G01X815033Y838747D02*
X814848D01*
G01X815033Y852133D02*
X814848D01*
G01X814950Y862172D02*
X814967D01*
G01X814950Y865519D02*
X815052D01*
G01X814927Y882251D02*
X814848D01*
G01X815033Y875558D02*
X814848D01*
G01X814927Y868865D02*
X814848D01*
G01X815033Y888944D02*
X814848D01*
G01X814950Y898983D02*
X814967D01*
G01X814950Y902330D02*
X815052D01*
G01X815033Y912369D02*
X814848D01*
G01X814927Y905676D02*
X814848D01*
G01X815033Y925755D02*
X814848D01*
G01X814927Y919062D02*
X814848D01*
G01X814927Y942487D02*
X814848D01*
G01X814950Y935794D02*
X814967D01*
G01X814950Y939141D02*
X815052D01*
G01X815033Y949180D02*
X814848D01*
G01X814913Y982644D02*
X814967D01*
G01X814913Y975951D02*
X814967D01*
G01X814913Y989337D02*
X814967D01*
G01X814913Y1029495D02*
X814967D01*
G01X814877Y1019456D02*
X814957D01*
G01X814542Y1049573D02*
X814625D01*
G01X814913Y1042880D02*
X814967D01*
G01X814913Y1036188D02*
X814967D01*
G01X815588Y1059613D02*
X814765D01*
G01X815033Y1072999D02*
X814848D01*
G01X814927Y1066306D02*
X814848D01*
G01X814927Y1089731D02*
X814848D01*
G01X814950Y1083038D02*
X814967D01*
G01X814950Y1086385D02*
X815052D01*
G01X815033Y1096424D02*
X814848D01*
G01X815033Y1109810D02*
X814848D01*
G01X814927Y1103117D02*
X814848D01*
G01X814927Y1126542D02*
X814848D01*
G01X814950Y1119849D02*
X814967D01*
G01X814950Y1123196D02*
X815052D01*
G01X814927Y1139928D02*
X814848D01*
G01X815033Y1133235D02*
X814848D01*
G01X815033Y1146621D02*
X814848D01*
G01X814950Y1156660D02*
X814967D01*
G01X814950Y1160007D02*
X815052D01*
G01X815033Y1170046D02*
X814848D01*
G01X814927Y1163353D02*
X814848D01*
G01X815033Y1183432D02*
X814848D01*
G01X814927Y1176739D02*
X814848D01*
G01X814950Y1193471D02*
X814967D01*
G01X815033Y1206857D02*
X814848D01*
G01X814927Y1200164D02*
X814848D01*
G01X814950Y1196818D02*
X815052D01*
G01X815033Y1220243D02*
X814848D01*
G01X814927Y1213550D02*
X814848D01*
G01X814927Y1236975D02*
X814848D01*
G01X814950Y1230282D02*
X814967D01*
G01X814950Y1233629D02*
X815052D01*
G01X815033Y1243668D02*
X814848D01*
G01X829127Y771845D02*
X829146D01*
G01X829127Y778538D02*
X829146D01*
G01X829127Y785228D02*
X829146D01*
G01X829127Y781829D02*
X829146D01*
G01X829127Y801964D02*
X829146D01*
G01X829127Y795271D02*
X829146D01*
G01X829127Y815349D02*
X829146D01*
G01X829127Y808656D02*
X829146D01*
G01X829127Y818640D02*
X829146D01*
G01X829127Y832082D02*
X829146D01*
G01X829127Y822039D02*
X829146D01*
G01X829127Y852160D02*
X829146D01*
G01X829127Y845467D02*
X829146D01*
G01X829127Y838775D02*
X829146D01*
G01X829127Y868893D02*
X829146D01*
G01X829127Y858850D02*
X829146D01*
G01X829127Y855451D02*
X829146D01*
G01X829127Y875586D02*
X829146D01*
G01X829127Y882278D02*
X829146D01*
G01X829127Y888971D02*
X829146D01*
G01X829127Y895661D02*
X829146D01*
G01X829127Y892262D02*
X829146D01*
G01X829127Y912397D02*
X829146D01*
G01X829127Y905704D02*
X829146D01*
G01X829127Y925782D02*
X829146D01*
G01X829127Y919090D02*
X829146D01*
G01X829127Y932472D02*
X829146D01*
G01X829127Y929073D02*
X829146D01*
G01X829127Y949208D02*
X829146D01*
G01X829127Y942515D02*
X829146D01*
G01X829127Y979340D02*
X829146D01*
G01X829127Y972647D02*
X829146D01*
G01X829127Y992726D02*
X829146D01*
G01X829127Y986033D02*
X829146D01*
G01X829127Y1046269D02*
X829146D01*
G01X829127Y1039576D02*
X829146D01*
G01X829127Y1032883D02*
X829146D01*
G01X829127Y1073027D02*
X829146D01*
G01X829127Y1066334D02*
X829146D01*
G01X829127Y1079716D02*
X829146D01*
G01X829127Y1076317D02*
X829146D01*
G01X829127Y1096452D02*
X829146D01*
G01X829127Y1089759D02*
X829146D01*
G01X829127Y1109838D02*
X829146D01*
G01X829127Y1103145D02*
X829146D01*
G01X829127Y1126570D02*
X829146D01*
G01X829127Y1116527D02*
X829146D01*
G01X829127Y1113128D02*
X829146D01*
G01X829127Y1139956D02*
X829146D01*
G01X829127Y1133263D02*
X829146D01*
G01X829127Y1146649D02*
X829146D01*
G01X829127Y1153338D02*
X829146D01*
G01X829127Y1149940D02*
X829146D01*
G01X829127Y1176767D02*
X829146D01*
G01X829127Y1170074D02*
X829146D01*
G01X829127Y1163381D02*
X829146D01*
G01X829127Y1183460D02*
X829146D01*
G01X829127Y1190149D02*
X829146D01*
G01X829127Y1186751D02*
X829146D01*
G01X829127Y1206885D02*
X829146D01*
G01X829127Y1200192D02*
X829146D01*
G01X829127Y1220271D02*
X829146D01*
G01X829127Y1213578D02*
X829146D01*
G01X829127Y1226960D02*
X829146D01*
G01X829127Y1223562D02*
X829146D01*
G01X829127Y1243696D02*
X829146D01*
G01X829127Y1237003D02*
X829146D01*
G01X1020915Y778511D02*
X1019939D01*
X1019907Y778479D01*
G01X1029061Y771818D02*
X1027759D01*
G01X1019952Y788550D02*
X1019910Y788508D01*
X1019907D01*
G01X1020915Y801936D02*
X1019939D01*
X1019907Y801904D01*
G01X1029061Y795243D02*
X1027759D01*
G01X1029061Y791897D02*
X1027788D01*
G01X1020877D02*
X1019944D01*
X1019907Y791934D01*
G01X1020915Y815322D02*
X1019939D01*
X1019907Y815290D01*
G01X1029061Y808629D02*
X1027759D01*
G01X1029061Y832054D02*
X1027759D01*
G01X1019952Y825361D02*
X1019910Y825319D01*
X1019907D01*
G01X1029061Y828708D02*
X1027788D01*
G01X1020877D02*
X1019944D01*
X1019907Y828745D01*
G01X1020915Y852133D02*
X1019939D01*
X1019907Y852101D01*
G01X1029061Y845440D02*
X1027759D01*
G01X1020915Y838747D02*
X1019939D01*
X1019907Y838715D01*
G01X1019952Y862172D02*
X1019910Y862130D01*
X1019907D01*
G01X1029061Y865519D02*
X1027788D01*
G01X1020877D02*
X1019944D01*
X1019907Y865556D01*
G01X1029061Y882251D02*
X1027759D01*
G01X1020915Y875558D02*
X1019939D01*
X1019907Y875526D01*
G01X1029061Y868865D02*
X1027759D01*
G01X1020915Y888944D02*
X1019939D01*
X1019907Y888912D01*
G01X1019952Y898983D02*
X1019910Y898941D01*
X1019907D01*
G01X1029061Y902330D02*
X1027788D01*
G01X1020877D02*
X1019944D01*
X1019907Y902367D01*
G01X1020915Y912369D02*
X1019939D01*
X1019907Y912337D01*
G01X1029061Y905676D02*
X1027759D01*
G01X1020915Y925755D02*
X1019939D01*
X1019907Y925723D01*
G01X1029061Y919062D02*
X1027759D01*
G01X1020915Y949180D02*
X1019939D01*
X1019907Y949148D01*
G01X1029061Y942487D02*
X1027759D01*
G01X1019952Y935794D02*
X1019910Y935752D01*
X1019907D01*
G01X1029061Y939141D02*
X1027788D01*
G01X1020877D02*
X1019944D01*
X1019907Y939178D01*
G01X1029061Y979298D02*
X1027759D01*
G01X1029061Y972605D02*
X1027759D01*
G01X1029061Y992684D02*
X1027759D01*
G01X1029061Y985991D02*
X1027759D01*
G01X1029061Y1026149D02*
X1027759D01*
G01X1029061Y1019456D02*
X1027759D01*
G01X1019995D02*
X1019941Y1019510D01*
X1019907D01*
G01X1029061Y1046227D02*
X1027759D01*
G01X1029061Y1039534D02*
X1027759D01*
G01X1029061Y1032842D02*
X1027759D01*
G01X1029061Y1059613D02*
X1028938D01*
G01X1020915Y1072999D02*
X1019939D01*
X1019907Y1072967D01*
G01X1029061Y1066306D02*
X1027759D01*
G01X1029061Y1089731D02*
X1027759D01*
G01X1019952Y1083038D02*
X1019910Y1082996D01*
X1019907D01*
G01X1029061Y1086385D02*
X1027788D01*
G01X1020877D02*
X1019944D01*
X1019907Y1086422D01*
G01X1020915Y1096424D02*
X1019939D01*
X1019907Y1096392D01*
G01X1020915Y1109810D02*
X1019939D01*
X1019907Y1109778D01*
G01X1029061Y1103117D02*
X1027759D01*
G01X1029061Y1126542D02*
X1027759D01*
G01X1019952Y1119849D02*
X1019910Y1119807D01*
X1019907D01*
G01X1029061Y1123196D02*
X1027788D01*
G01X1020877D02*
X1019944D01*
X1019907Y1123233D01*
G01X1029061Y1139928D02*
X1027759D01*
G01X1020915Y1133235D02*
X1019939D01*
X1019907Y1133203D01*
G01X1020915Y1146621D02*
X1019939D01*
X1019907Y1146589D01*
G01X1019952Y1156660D02*
X1019910Y1156618D01*
X1019907D01*
G01X1029061Y1160007D02*
X1027788D01*
G01X1020877D02*
X1019944D01*
X1019907Y1160044D01*
G01X1029061Y1176739D02*
X1027759D01*
G01X1020915Y1170046D02*
X1019939D01*
X1019907Y1170014D01*
G01X1029061Y1163353D02*
X1027759D01*
G01X1020915Y1183432D02*
X1019939D01*
X1019907Y1183400D01*
G01X1019952Y1193471D02*
X1019910Y1193429D01*
X1019907D01*
G01X1020915Y1206857D02*
X1019939D01*
X1019907Y1206825D01*
G01X1029061Y1200164D02*
X1027759D01*
G01X1029061Y1196818D02*
X1027788D01*
G01X1020877D02*
X1019944D01*
X1019907Y1196855D01*
G01X1020915Y1220243D02*
X1019939D01*
X1019907Y1220211D01*
G01X1029061Y1213550D02*
X1027759D01*
G01X1029061Y1236975D02*
X1027759D01*
G01X1019952Y1230282D02*
X1019910Y1230240D01*
X1019907D01*
G01X1029061Y1233629D02*
X1027788D01*
G01X1020877D02*
X1019944D01*
X1019907Y1233666D01*
G01X1020915Y1243668D02*
X1019939D01*
X1019907Y1243636D01*
G01X1034458Y771817D02*
X1033521D01*
X1033465Y771873D01*
G01X1034509Y775164D02*
X1033505D01*
X1033465Y775124D01*
G01X1034440Y785204D02*
X1033496D01*
X1033465Y785235D01*
G01X1034437Y781857D02*
X1033487D01*
X1033465Y781835D01*
G01X1034509Y798590D02*
X1033505D01*
X1033465Y798550D01*
G01X1034458Y795243D02*
X1033521D01*
X1033465Y795299D01*
G01X1034509Y811975D02*
X1033505D01*
X1033465Y811935D01*
G01X1034458Y808628D02*
X1033521D01*
X1033465Y808684D01*
G01X1034437Y818668D02*
X1033487D01*
X1033465Y818646D01*
G01X1034509Y835401D02*
X1033505D01*
X1033465Y835361D01*
G01X1034458Y832054D02*
X1033521D01*
X1033465Y832110D01*
G01X1034440Y822015D02*
X1033496D01*
X1033465Y822046D01*
G01X1034509Y848786D02*
X1033505D01*
X1033465Y848746D01*
G01X1034458Y845439D02*
X1033521D01*
X1033465Y845495D01*
G01X1034458Y868865D02*
X1033521D01*
X1033465Y868921D01*
G01X1034440Y858826D02*
X1033496D01*
X1033465Y858857D01*
G01X1034437Y855479D02*
X1033487D01*
X1033465Y855457D01*
G01X1034509Y872212D02*
X1033505D01*
X1033465Y872172D01*
G01X1034458Y882250D02*
X1033521D01*
X1033465Y882306D01*
G01X1034509Y885597D02*
X1033505D01*
X1033465Y885557D01*
G01X1034440Y895637D02*
X1033496D01*
X1033465Y895668D01*
G01X1034437Y892290D02*
X1033487D01*
X1033465Y892268D01*
G01X1034509Y909023D02*
X1033505D01*
X1033465Y908983D01*
G01X1034458Y905676D02*
X1033521D01*
X1033465Y905732D01*
G01X1034509Y922408D02*
X1033505D01*
X1033465Y922368D01*
G01X1034458Y919062D02*
X1033521D01*
X1033465Y919118D01*
G01X1034440Y932448D02*
X1033496D01*
X1033465Y932479D01*
G01X1034437Y929101D02*
X1033487D01*
X1033465Y929079D01*
G01X1034509Y945834D02*
X1033505D01*
X1033465Y945794D01*
G01X1034458Y942487D02*
X1033521D01*
X1033465Y942543D01*
G01X1034458Y979298D02*
X1033521D01*
X1033465Y979354D01*
G01X1034458Y972605D02*
X1033521D01*
X1033465Y972661D01*
G01X1034458Y992684D02*
X1033521D01*
X1033465Y992740D01*
G01X1034458Y985991D02*
X1033521D01*
X1033465Y986047D01*
G01X1034458Y1032841D02*
X1033521D01*
X1033465Y1032897D01*
G01X1034458Y1046227D02*
X1033521D01*
X1033465Y1046283D01*
G01X1034458Y1039534D02*
X1033521D01*
X1033465Y1039590D01*
G01X1034509Y1069653D02*
X1033505D01*
X1033465Y1069613D01*
G01X1034458Y1066306D02*
X1033521D01*
X1033465Y1066362D01*
G01X1034440Y1079692D02*
X1033504D01*
X1033466Y1079730D01*
G01X1034437Y1076345D02*
X1033487D01*
X1033465Y1076323D01*
G01X1034509Y1093078D02*
X1033505D01*
X1033465Y1093038D01*
G01X1034458Y1089731D02*
X1033521D01*
X1033465Y1089787D01*
G01X1034509Y1106464D02*
X1033505D01*
X1033465Y1106424D01*
G01X1034458Y1103117D02*
X1033521D01*
X1033465Y1103173D01*
G01X1034458Y1126542D02*
X1033521D01*
X1033465Y1126598D01*
G01X1034440Y1116503D02*
X1033503D01*
X1033465Y1116541D01*
G01X1034437Y1113156D02*
X1033487D01*
X1033465Y1113134D01*
G01X1034509Y1143275D02*
X1033505D01*
X1033465Y1143235D01*
G01X1034458Y1139928D02*
X1033521D01*
X1033465Y1139984D01*
G01X1034509Y1129889D02*
X1033505D01*
X1033465Y1129849D01*
G01X1034440Y1153314D02*
X1033509D01*
X1033471Y1153352D01*
X1033465D01*
G01X1034436Y1149968D02*
X1033488D01*
X1033465Y1149945D01*
G01X1034458Y1176739D02*
X1033521D01*
X1033465Y1176795D01*
G01X1034509Y1166700D02*
X1033505D01*
X1033465Y1166660D01*
G01X1034458Y1163353D02*
X1033521D01*
X1033465Y1163409D01*
G01X1034509Y1180086D02*
X1033505D01*
X1033465Y1180046D01*
G01X1034440Y1190125D02*
X1033509D01*
X1033471Y1190163D01*
X1033465D01*
G01X1034436Y1186779D02*
X1033488D01*
X1033465Y1186756D01*
G01X1034509Y1203511D02*
X1033505D01*
X1033465Y1203471D01*
G01X1034458Y1200164D02*
X1033521D01*
X1033465Y1200220D01*
G01X1034509Y1216897D02*
X1033505D01*
X1033465Y1216857D01*
G01X1034458Y1213550D02*
X1033521D01*
X1033465Y1213606D01*
G01X1034440Y1226936D02*
X1033509D01*
X1033471Y1226974D01*
X1033465D01*
G01X1034436Y1223590D02*
X1033488D01*
X1033465Y1223567D01*
G01X1034509Y1240322D02*
X1033505D01*
X1033465Y1240282D01*
G01X1034458Y1236975D02*
X1033521D01*
X1033465Y1237031D01*
G01X1080315Y778511D02*
X1079339D01*
X1079307Y778479D01*
G01X1088461Y771818D02*
X1087159D01*
G01X1079352Y788550D02*
X1079310Y788508D01*
X1079307D01*
G01X1088461Y795243D02*
X1087159D01*
G01X1088461Y791897D02*
X1087188D01*
G01X1080277D02*
X1079344D01*
X1079307Y791934D01*
G01X1080315Y815322D02*
X1079339D01*
X1079307Y815290D01*
G01X1088461Y808629D02*
X1087159D01*
G01X1080315Y801936D02*
X1079339D01*
X1079307Y801904D01*
G01X1088461Y832054D02*
X1087159D01*
G01X1079352Y825361D02*
X1079310Y825319D01*
X1079307D01*
G01X1088461Y828708D02*
X1087188D01*
G01X1080277D02*
X1079344D01*
X1079307Y828745D01*
G01X1088461Y845440D02*
X1087159D01*
G01X1080315Y838747D02*
X1079339D01*
X1079307Y838715D01*
G01X1080315Y852133D02*
X1079339D01*
X1079307Y852101D01*
G01X1079352Y862172D02*
X1079310Y862130D01*
X1079307D01*
G01X1088461Y865519D02*
X1087188D01*
G01X1080277D02*
X1079344D01*
X1079307Y865556D01*
G01X1088461Y882251D02*
X1087159D01*
G01X1080315Y875558D02*
X1079339D01*
X1079307Y875526D01*
G01X1088461Y868865D02*
X1087159D01*
G01X1080315Y888944D02*
X1079339D01*
X1079307Y888912D01*
G01X1079352Y898983D02*
X1079310Y898941D01*
X1079307D01*
G01X1088462Y902330D02*
X1087188D01*
G01X1080277D02*
X1079344D01*
X1079308Y902366D01*
G01X1080315Y912369D02*
X1079339D01*
X1079307Y912337D01*
G01X1088461Y905676D02*
X1087159D01*
G01X1088735Y925755D02*
X1088461D01*
G01X1080315D02*
X1078779D01*
G01X1088703Y919062D02*
X1087159D01*
G01X1079342D02*
X1078763D01*
G01X1088703Y942487D02*
X1087159D01*
G01X1079342D02*
X1078795D01*
G01X1088703Y935794D02*
X1088461D01*
G01X1079352D02*
X1078763D01*
G01X1088703Y939141D02*
X1088462D01*
G01X1080277D02*
X1078763D01*
G01X1088735Y949180D02*
X1088461D01*
G01X1080315D02*
X1078779D01*
G01X1088461Y979298D02*
X1087159D01*
G01X1088461Y972605D02*
X1087159D01*
G01X1088461Y992684D02*
X1087159D01*
G01X1088461Y985991D02*
X1087159D01*
G01X1088461Y1026149D02*
X1087159D01*
G01X1088461Y1019456D02*
X1087159D01*
G01X1079395D02*
X1079341Y1019510D01*
X1079307D01*
G01X1088461Y1039534D02*
X1087159D01*
G01X1088461Y1032842D02*
X1087159D01*
G01X1088461Y1059613D02*
X1087159D01*
G01X1088461Y1046227D02*
X1087159D01*
G01X1088736Y1072999D02*
X1088461D01*
G01X1080315D02*
X1078844D01*
G01X1088753Y1066306D02*
X1087159D01*
G01X1079342D02*
X1078829D01*
G01X1088720Y1089731D02*
X1087159D01*
G01X1079342D02*
X1078780D01*
G01X1088720Y1083038D02*
X1088461D01*
G01X1079352D02*
X1078796D01*
G01X1088720Y1086385D02*
X1087188D01*
G01X1080277D02*
X1078796D01*
G01X1088719Y1096424D02*
X1088461D01*
G01X1080315D02*
X1078779D01*
G01X1080315Y1109810D02*
X1079339D01*
X1079307Y1109778D01*
G01X1088461Y1103117D02*
X1087159D01*
G01X1088461Y1126542D02*
X1087159D01*
G01X1079352Y1119849D02*
X1079310Y1119807D01*
X1079307D01*
G01X1088461Y1123196D02*
X1087188D01*
G01X1080277D02*
X1079344D01*
X1079307Y1123233D01*
G01X1088461Y1139928D02*
X1087159D01*
G01X1080315Y1133235D02*
X1079339D01*
X1079307Y1133203D01*
G01X1080315Y1146621D02*
X1079339D01*
X1079307Y1146589D01*
G01X1079352Y1156660D02*
X1079310Y1156618D01*
X1079307D01*
G01X1088461Y1160007D02*
X1087188D01*
G01X1080277D02*
X1079344D01*
X1079307Y1160044D01*
G01X1080315Y1170046D02*
X1079339D01*
X1079307Y1170014D01*
G01X1088461Y1163353D02*
X1087159D01*
G01X1080315Y1183432D02*
X1079339D01*
X1079307Y1183400D01*
G01X1088461Y1176739D02*
X1087159D01*
G01X1079352Y1193471D02*
X1079310Y1193429D01*
X1079307D01*
G01X1080315Y1206857D02*
X1079339D01*
X1079307Y1206825D01*
G01X1088461Y1200164D02*
X1087159D01*
G01X1088461Y1196818D02*
X1087188D01*
G01X1080277D02*
X1079344D01*
X1079307Y1196855D01*
G01X1080315Y1220243D02*
X1079339D01*
X1079307Y1220211D01*
G01X1088461Y1213550D02*
X1087159D01*
G01X1088461Y1236975D02*
X1087159D01*
G01X1079352Y1230282D02*
X1079310Y1230240D01*
X1079307D01*
G01X1088461Y1233629D02*
X1087188D01*
G01X1080277D02*
X1079344D01*
X1079307Y1233666D01*
G01X1080315Y1243668D02*
X1079339D01*
X1079307Y1243636D01*
G01X1093858Y771817D02*
X1092921D01*
X1092865Y771873D01*
G01X1093909Y775164D02*
X1092905D01*
X1092865Y775124D01*
G01X1093840Y785204D02*
X1092896D01*
X1092865Y785235D01*
G01X1093837Y781857D02*
X1092887D01*
X1092865Y781835D01*
G01X1093909Y798590D02*
X1092905D01*
X1092865Y798550D01*
G01X1093858Y795243D02*
X1092921D01*
X1092865Y795299D01*
G01X1093909Y811975D02*
X1092905D01*
X1092865Y811935D01*
G01X1093858Y808628D02*
X1092921D01*
X1092865Y808684D01*
G01X1093858Y832054D02*
X1092921D01*
X1092865Y832110D01*
G01X1093840Y822015D02*
X1092896D01*
X1092865Y822046D01*
G01X1093837Y818668D02*
X1092887D01*
X1092865Y818646D01*
G01X1093909Y848786D02*
X1092905D01*
X1092865Y848746D01*
G01X1093858Y845439D02*
X1092921D01*
X1092865Y845495D01*
G01X1093909Y835401D02*
X1092905D01*
X1092865Y835361D01*
G01X1093858Y868865D02*
X1092921D01*
X1092865Y868921D01*
G01X1093840Y858826D02*
X1092896D01*
X1092865Y858857D01*
G01X1093837Y855479D02*
X1092887D01*
X1092865Y855457D01*
G01X1093909Y872212D02*
X1092905D01*
X1092865Y872172D01*
G01X1093858Y882250D02*
X1092921D01*
X1092865Y882306D01*
G01X1093909Y885597D02*
X1092905D01*
X1092865Y885557D01*
G01X1093840Y895637D02*
X1092896D01*
X1092865Y895668D01*
G01X1093837Y892290D02*
X1092887D01*
X1092865Y892268D01*
G01X1093909Y909023D02*
X1092905D01*
X1092865Y908983D01*
G01X1093858Y905676D02*
X1092921D01*
X1092865Y905732D01*
G01X1102305Y922408D02*
X1102019D01*
G01X1093909D02*
X1092317D01*
G01X1102273Y919062D02*
X1102019D01*
G01X1093858D02*
X1092349D01*
G01X1102226Y932448D02*
X1102019D01*
G01X1093840D02*
X1092302D01*
G01X1102226Y929101D02*
X1102018D01*
G01X1093837D02*
X1092302D01*
G01X1102289Y945834D02*
X1102019D01*
G01X1093909D02*
X1092334D01*
G01X1102290Y942487D02*
X1102019D01*
G01X1093858D02*
X1092335D01*
G01X1093858Y979298D02*
X1092921D01*
X1092865Y979354D01*
G01X1093858Y972605D02*
X1092921D01*
X1092865Y972661D01*
G01X1093858Y992684D02*
X1092921D01*
X1092865Y992740D01*
G01X1093858Y985991D02*
X1092921D01*
X1092865Y986047D01*
G01X1093858Y1046227D02*
X1092921D01*
X1092865Y1046283D01*
G01X1093858Y1039534D02*
X1092921D01*
X1092865Y1039590D01*
G01X1093858Y1032841D02*
X1092921D01*
X1092865Y1032897D01*
G01X1102288Y1069653D02*
X1102019D01*
G01X1093909D02*
X1092364D01*
G01X1102240Y1066306D02*
X1102019D01*
G01X1092921D02*
X1092348D01*
G01X1102225Y1076345D02*
X1102018D01*
G01X1093837D02*
X1092348D01*
G01X1102302Y1093078D02*
X1102168D01*
G01X1093909D02*
X1092347D01*
G01X1102306Y1089731D02*
X1102019D01*
G01X1093858D02*
X1092366D01*
G01X1102225Y1079692D02*
X1102019D01*
G01X1093840D02*
X1092348D01*
G01X1093909Y1106464D02*
X1092905D01*
X1092865Y1106424D01*
G01X1093858Y1103117D02*
X1092921D01*
X1092865Y1103173D01*
G01X1093858Y1126542D02*
X1092921D01*
X1092865Y1126598D01*
G01X1093840Y1116503D02*
X1092903D01*
X1092865Y1116541D01*
G01X1093837Y1113156D02*
X1092887D01*
X1092865Y1113134D01*
G01X1093858Y1139928D02*
X1092921D01*
X1092865Y1139984D01*
G01X1093909Y1129889D02*
X1092905D01*
X1092865Y1129849D01*
G01X1093909Y1143275D02*
X1092905D01*
X1092865Y1143235D01*
G01X1093840Y1153314D02*
X1092909D01*
X1092871Y1153352D01*
X1092865D01*
G01X1093836Y1149968D02*
X1092888D01*
X1092865Y1149945D01*
G01X1093858Y1176739D02*
X1092921D01*
X1092865Y1176795D01*
G01X1093909Y1166700D02*
X1092905D01*
X1092865Y1166660D01*
G01X1093858Y1163353D02*
X1092921D01*
X1092865Y1163409D01*
G01X1093909Y1180086D02*
X1092905D01*
X1092865Y1180046D01*
G01X1093840Y1190125D02*
X1092909D01*
X1092871Y1190163D01*
X1092865D01*
G01X1093836Y1186779D02*
X1092888D01*
X1092865Y1186756D01*
G01X1093909Y1203511D02*
X1092905D01*
X1092865Y1203471D01*
G01X1093858Y1200164D02*
X1092921D01*
X1092865Y1200220D01*
G01X1093909Y1216897D02*
X1092905D01*
X1092865Y1216857D01*
G01X1093858Y1213550D02*
X1092921D01*
X1092865Y1213606D01*
G01X1093836Y1223590D02*
X1092888D01*
X1092865Y1223567D01*
G01X1093909Y1240322D02*
X1092905D01*
X1092865Y1240282D01*
G01X1093858Y1236975D02*
X1092921D01*
X1092865Y1237031D01*
G01X1093840Y1226936D02*
X1092909D01*
X1092871Y1226974D01*
X1092865D01*
G01X1139715Y778511D02*
X1138739D01*
X1138707Y778479D01*
G01X1147861Y771818D02*
X1146559D01*
G01X1138752Y788550D02*
X1138710Y788508D01*
X1138707D01*
G01X1147861Y795243D02*
X1146559D01*
G01X1147861Y791897D02*
X1146588D01*
G01X1139677D02*
X1138744D01*
X1138707Y791934D01*
G01X1139715Y815322D02*
X1138739D01*
X1138707Y815290D01*
G01X1147861Y808629D02*
X1146559D01*
G01X1139715Y801936D02*
X1138739D01*
X1138707Y801904D01*
G01X1147861Y832054D02*
X1146559D01*
G01X1138752Y825361D02*
X1138710Y825319D01*
X1138707D01*
G01X1147861Y828708D02*
X1146588D01*
G01X1139677D02*
X1138744D01*
X1138707Y828745D01*
G01X1147861Y845440D02*
X1146559D01*
G01X1139715Y838747D02*
X1138739D01*
X1138707Y838715D01*
G01X1139715Y852133D02*
X1138739D01*
X1138707Y852101D01*
G01X1138752Y862172D02*
X1138710Y862130D01*
X1138707D01*
G01X1147862Y865519D02*
X1146588D01*
G01X1139677D02*
X1138744D01*
X1138708Y865555D01*
G01X1147861Y882251D02*
X1146559D01*
G01X1139715Y875558D02*
X1138739D01*
X1138707Y875526D01*
G01X1147861Y868865D02*
X1146559D01*
G01X1139715Y888944D02*
X1138739D01*
X1138707Y888912D01*
G01X1138752Y898983D02*
X1138710Y898941D01*
X1138707D01*
G01X1147861Y902330D02*
X1146588D01*
G01X1139677D02*
X1138744D01*
X1138707Y902367D01*
G01X1139715Y912369D02*
X1138739D01*
X1138707Y912337D01*
G01X1147861Y905676D02*
X1146559D01*
G01X1139715Y925755D02*
X1138739D01*
X1138707Y925723D01*
G01X1147861Y919062D02*
X1146559D01*
G01X1147861Y942487D02*
X1146559D01*
G01X1138752Y935794D02*
X1138710Y935752D01*
X1138707D01*
G01X1147862Y939141D02*
X1146588D01*
G01X1139677D02*
X1138744D01*
X1138714Y939171D01*
X1138708D01*
G01X1139715Y949180D02*
X1138739D01*
X1138707Y949148D01*
G01X1147861Y979298D02*
X1146559D01*
G01X1147861Y972605D02*
X1146559D01*
G01X1147861Y992684D02*
X1146559D01*
G01X1147861Y985991D02*
X1146559D01*
G01X1147861Y1026149D02*
X1146559D01*
G01X1147861Y1019456D02*
X1146559D01*
G01X1138795D02*
X1138741Y1019510D01*
X1138707D01*
G01X1147861Y1039534D02*
X1146559D01*
G01X1147861Y1032842D02*
X1146559D01*
G01X1148152Y1059613D02*
X1146559D01*
G01X1138742D02*
X1138180D01*
G01X1147861Y1046227D02*
X1146559D01*
G01X1139715Y1072999D02*
X1138739D01*
X1138707Y1072967D01*
G01X1147861Y1066306D02*
X1146559D01*
G01X1147861Y1089731D02*
X1146559D01*
G01X1138752Y1083038D02*
X1138710Y1082996D01*
X1138707D01*
G01X1147861Y1086385D02*
X1146588D01*
G01X1139677D02*
X1138744D01*
X1138707Y1086422D01*
G01X1139715Y1096424D02*
X1138739D01*
X1138707Y1096392D01*
G01X1139715Y1109810D02*
X1138739D01*
X1138707Y1109778D01*
G01X1147861Y1103117D02*
X1146559D01*
G01X1147861Y1126542D02*
X1146559D01*
G01X1138752Y1119849D02*
X1138710Y1119807D01*
X1138707D01*
G01X1147861Y1123196D02*
X1146588D01*
G01X1139677D02*
X1138744D01*
X1138707Y1123233D01*
G01X1147861Y1139928D02*
X1146559D01*
G01X1139715Y1133235D02*
X1138739D01*
X1138707Y1133203D01*
G01X1139715Y1146621D02*
X1138739D01*
X1138707Y1146589D01*
G01X1138752Y1156660D02*
X1138710Y1156618D01*
X1138707D01*
G01X1147861Y1160007D02*
X1146588D01*
G01X1139677D02*
X1138744D01*
X1138707Y1160044D01*
G01X1139715Y1170046D02*
X1138739D01*
X1138707Y1170014D01*
G01X1147861Y1163353D02*
X1146559D01*
G01X1139715Y1183432D02*
X1138739D01*
X1138707Y1183400D01*
G01X1147861Y1176739D02*
X1146559D01*
G01X1138752Y1193471D02*
X1138710Y1193429D01*
X1138707D01*
G01X1139715Y1206857D02*
X1138739D01*
X1138707Y1206825D01*
G01X1147861Y1200164D02*
X1146559D01*
G01X1147861Y1196818D02*
X1146588D01*
G01X1139677D02*
X1138744D01*
X1138707Y1196855D01*
G01X1139715Y1220243D02*
X1138739D01*
X1138707Y1220211D01*
G01X1147861Y1213550D02*
X1146559D01*
G01X1147861Y1236975D02*
X1146559D01*
G01X1138752Y1230282D02*
X1138710Y1230240D01*
X1138707D01*
G01X1147861Y1233629D02*
X1146588D01*
G01X1139677D02*
X1138744D01*
X1138707Y1233666D01*
G01X1139715Y1243668D02*
X1138739D01*
X1138707Y1243636D01*
G01X1153258Y771817D02*
X1152321D01*
X1152265Y771873D01*
G01X1153309Y775164D02*
X1152305D01*
X1152265Y775124D01*
G01X1153240Y785204D02*
X1152296D01*
X1152265Y785235D01*
G01X1153237Y781857D02*
X1152287D01*
X1152265Y781835D01*
G01X1153309Y798590D02*
X1152305D01*
X1152265Y798550D01*
G01X1153258Y795243D02*
X1152321D01*
X1152265Y795299D01*
G01X1153309Y811975D02*
X1152305D01*
X1152265Y811935D01*
G01X1153258Y808628D02*
X1152321D01*
X1152265Y808684D01*
G01X1153237Y818668D02*
X1152287D01*
X1152265Y818646D01*
G01X1153309Y835401D02*
X1152305D01*
X1152265Y835361D01*
G01X1153258Y832054D02*
X1152321D01*
X1152265Y832110D01*
G01X1153240Y822015D02*
X1152296D01*
X1152265Y822046D01*
G01X1153309Y848786D02*
X1152305D01*
X1152265Y848746D01*
G01X1153258Y845439D02*
X1152321D01*
X1152265Y845495D01*
G01X1153258Y868865D02*
X1152321D01*
X1152265Y868921D01*
G01X1153240Y858826D02*
X1152296D01*
X1152265Y858857D01*
G01X1153237Y855479D02*
X1152287D01*
X1152265Y855457D01*
G01X1153309Y872212D02*
X1152305D01*
X1152265Y872172D01*
G01X1153258Y882250D02*
X1152321D01*
X1152265Y882306D01*
G01X1153309Y885597D02*
X1152305D01*
X1152265Y885557D01*
G01X1153240Y895637D02*
X1152296D01*
X1152265Y895668D01*
G01X1153237Y892290D02*
X1152287D01*
X1152265Y892268D01*
G01X1153309Y909023D02*
X1152305D01*
X1152265Y908983D01*
G01X1153258Y905676D02*
X1152321D01*
X1152265Y905732D01*
G01X1153309Y922408D02*
X1152305D01*
X1152265Y922368D01*
G01X1153258Y919062D02*
X1152321D01*
X1152265Y919118D01*
G01X1153240Y932448D02*
X1152296D01*
X1152265Y932479D01*
G01X1153237Y929101D02*
X1152287D01*
X1152265Y929079D01*
G01X1153309Y945834D02*
X1152305D01*
X1152265Y945794D01*
G01X1153258Y942487D02*
X1152321D01*
X1152265Y942543D01*
G01X1153258Y979298D02*
X1152321D01*
X1152265Y979354D01*
G01X1153258Y972605D02*
X1152321D01*
X1152265Y972661D01*
G01X1153258Y992684D02*
X1152321D01*
X1152265Y992740D01*
G01X1153258Y985991D02*
X1152321D01*
X1152265Y986047D01*
G01X1153258Y1032841D02*
X1152321D01*
X1152265Y1032897D01*
G01X1153258Y1046227D02*
X1152321D01*
X1152265Y1046283D01*
G01X1153258Y1039534D02*
X1152321D01*
X1152265Y1039590D01*
G01X1153309Y1069653D02*
X1152305D01*
X1152265Y1069613D01*
G01X1153258Y1066306D02*
X1152321D01*
X1152265Y1066362D01*
G01Y1079730D02*
X1152303Y1079692D01*
X1153240D01*
G01X1153237Y1076345D02*
X1152287D01*
X1152265Y1076323D01*
G01Y1093038D02*
X1152305Y1093078D01*
X1153309D01*
G01X1152265Y1089787D02*
X1152321Y1089731D01*
X1153258D01*
G01X1153309Y1106464D02*
X1152305D01*
X1152265Y1106424D01*
G01X1153258Y1103117D02*
X1152321D01*
X1152265Y1103173D01*
G01X1153258Y1126542D02*
X1152321D01*
X1152265Y1126598D01*
G01Y1116541D02*
X1152303Y1116503D01*
X1153240D01*
G01X1152265Y1113134D02*
X1152287Y1113156D01*
X1153237D01*
G01X1153309Y1143275D02*
X1152305D01*
X1152265Y1143235D01*
G01X1153258Y1139928D02*
X1152321D01*
X1152265Y1139984D01*
G01X1153309Y1129889D02*
X1152305D01*
X1152265Y1129849D01*
G01Y1153352D02*
X1152271D01*
X1152309Y1153314D01*
X1153240D01*
G01X1153236Y1149968D02*
X1152288D01*
X1152265Y1149945D01*
G01X1153258Y1176739D02*
X1152321D01*
X1152265Y1176795D01*
G01X1153309Y1166700D02*
X1152305D01*
X1152265Y1166660D01*
G01X1153258Y1163353D02*
X1152321D01*
X1152265Y1163409D01*
G01X1153309Y1180086D02*
X1152305D01*
X1152265Y1180046D01*
G01Y1190163D02*
X1152271D01*
X1152309Y1190125D01*
X1153240D01*
G01X1153236Y1186779D02*
X1152288D01*
X1152265Y1186756D01*
G01X1153309Y1203511D02*
X1152305D01*
X1152265Y1203471D01*
G01X1153258Y1200164D02*
X1152321D01*
X1152265Y1200220D01*
G01X1153309Y1216897D02*
X1152305D01*
X1152265Y1216857D01*
G01X1153258Y1213550D02*
X1152321D01*
X1152265Y1213606D01*
G01X1153240Y1226936D02*
X1152309D01*
X1152271Y1226974D01*
X1152265D01*
G01X1153236Y1223590D02*
X1152288D01*
X1152265Y1223567D01*
G01Y1240282D02*
X1152305Y1240322D01*
X1153309D01*
G01X1153258Y1236975D02*
X1152321D01*
X1152265Y1237031D01*
G01X1205959Y778511D02*
X1207261D01*
G01X1205863Y771817D02*
X1207261D01*
G01X1205863Y801936D02*
X1207261D01*
G01X1198107Y795208D02*
X1198277D01*
G01X1207035Y795243D02*
X1207261D01*
G01X1198108Y791921D02*
X1198132Y791897D01*
G01X1207222D02*
X1207262Y791937D01*
G01X1205863Y815321D02*
X1207261D01*
G01X1205863Y808629D02*
X1207261D01*
G01X1205863Y832054D02*
X1207261D01*
G01X1198108Y828732D02*
X1198132Y828708D01*
G01X1207222D02*
X1207262Y828748D01*
G01X1198107Y852087D02*
X1198139D01*
G01X1205959Y852133D02*
X1207261D01*
G01X1205959Y845440D02*
X1207261D01*
G01X1198107Y838584D02*
X1198220D01*
G01X1206121Y838673D02*
X1207261D01*
G01X1198107Y862152D02*
X1198127Y862172D01*
G01X1205989D02*
X1207237D01*
X1207261Y862148D01*
G01Y882250D02*
X1205863D01*
G01X1199019D02*
X1198132D01*
X1198107Y882225D01*
G01Y875505D02*
X1198160Y875558D01*
X1199019D01*
G01X1205863D02*
X1207210D01*
X1207261Y875507D01*
G01X1198107Y868826D02*
X1198146Y868865D01*
X1199019D01*
G01X1205688D02*
X1207261D01*
G01Y888943D02*
X1205790D01*
G01X1199019D02*
X1198129D01*
X1198107Y888921D01*
G01X1207261Y898983D02*
X1205989D01*
G01X1198177D02*
X1198157Y898963D01*
X1198107D01*
G01X1207261Y902330D02*
X1205988D01*
G01X1199077D02*
X1198162D01*
X1198107Y902385D01*
G01X1207261Y912305D02*
X1206086D01*
G01X1198320Y912206D02*
X1198107D01*
G01X1207261Y905618D02*
X1206065D01*
G01X1198220Y905513D02*
X1198107D01*
G01X1196789Y925754D02*
X1199019D01*
G01X1205863D02*
X1208362D01*
G01X1197581Y919062D02*
X1199019D01*
G01X1205863D02*
X1207513D01*
G01X1197582Y949180D02*
X1199019D01*
G01X1205863D02*
X1207585D01*
G01X1197377Y942487D02*
X1199019D01*
G01X1205863D02*
X1207602D01*
G01X1198520Y965881D02*
X1198619D01*
X1198650Y965912D01*
G01X1206710D02*
X1206746Y965876D01*
X1206920D01*
G01X1212020Y965978D02*
X1212182D01*
X1212248Y965912D01*
G01X1220212D02*
X1220267Y965967D01*
X1220520D01*
G01X1228120Y965853D02*
X1228213D01*
X1228272Y965912D01*
G01X1236580D02*
X1236624Y965868D01*
X1236720D01*
G01X1264068Y967851D02*
X1264115Y967870D01*
G01X1198107Y982820D02*
X1198315D01*
X1198491Y982644D01*
G01X1207020D02*
X1207261D01*
G01X1198107Y976003D02*
X1198369D01*
X1198421Y975951D01*
G01X1207020D02*
X1207261D01*
G01X1198107Y992581D02*
X1198217D01*
X1198320Y992684D01*
G01X1207020D02*
X1207261D01*
G01X1198107Y989411D02*
X1198246D01*
X1198320Y989337D01*
G01X1207120D02*
X1207261D01*
G01X1198107Y1029561D02*
X1198254D01*
X1198320Y1029495D01*
G01X1207020D02*
X1207261D01*
G01X1198107Y1026083D02*
X1198255D01*
X1198320Y1026148D01*
G01X1206920D02*
X1207261D01*
G01X1198107Y1046052D02*
X1198296D01*
X1198471Y1046227D01*
G01X1207120D02*
X1207261D01*
G01X1198107Y1042943D02*
X1198164D01*
X1198227Y1042880D01*
X1198320D01*
G01X1207120D02*
X1207261D01*
G01X1198107Y1036291D02*
X1198124D01*
X1198227Y1036188D01*
X1198320D01*
G01X1207120D02*
X1207261D01*
G01Y1059613D02*
X1207260D01*
G01X1199318D02*
X1197487D01*
G01X1198220Y1052795D02*
X1198389D01*
X1198514Y1052920D01*
G01X1206828D02*
X1206910Y1052838D01*
X1207120D01*
G01X1211665Y1056237D02*
X1211797D01*
X1211826Y1056266D01*
G01X1220400D02*
X1220481Y1056185D01*
X1220620D01*
G01X1227920Y1056298D02*
X1227952Y1056266D01*
G01X1237382D02*
X1237610D01*
G01X1196789Y1072999D02*
X1198423D01*
G01X1207020D02*
X1208314D01*
G01X1197626Y1066306D02*
X1199108D01*
G01X1207120D02*
X1207471D01*
G01X1197724Y1096424D02*
X1198107D01*
G01X1207120D02*
X1207410D01*
G01X1198107Y1089625D02*
X1198213Y1089731D01*
X1200219D01*
G01X1207120D02*
X1207474D01*
G01X1198107Y1109741D02*
X1198127D01*
X1198196Y1109810D01*
X1199233D01*
G01X1207020D02*
X1207261D01*
G01X1198107Y1103042D02*
X1198182Y1103117D01*
G01X1207120D02*
X1207261D01*
G01X1198107Y1126486D02*
X1198331D01*
X1198387Y1126542D01*
G01X1207220D02*
X1207261D01*
G01X1207224Y1119849D02*
X1207261D01*
G01X1207232Y1123196D02*
X1207261D01*
G01X1198107Y1139860D02*
X1198311D01*
X1198379Y1139928D01*
G01X1207120D02*
X1207261D01*
G01X1198107Y1133174D02*
X1198382D01*
X1198443Y1133235D01*
G01X1207125D02*
X1207183Y1133177D01*
X1207261D01*
G01X1198107Y1146521D02*
X1198337D01*
X1198437Y1146621D01*
G01X1206985D02*
X1207027Y1146579D01*
X1207261D01*
G01Y1176739D02*
X1207020D01*
G01X1198320D02*
X1198197D01*
X1198115Y1176657D01*
X1198107D01*
G01Y1170014D02*
X1198288D01*
X1198320Y1170046D01*
G01X1207120D02*
X1207261D01*
G01X1198107Y1163273D02*
X1198223D01*
X1198303Y1163353D01*
G01X1207020D02*
X1207261D01*
G01Y1183432D02*
X1207120D01*
G01X1198320D02*
X1198238Y1183350D01*
X1198107D01*
G01X1198152Y1193471D02*
X1198110Y1193429D01*
X1198107D01*
G01X1207261Y1206857D02*
X1206920D01*
G01X1198320D02*
X1198251D01*
X1198205Y1206811D01*
X1198107D01*
G01X1207261Y1200164D02*
X1207020D01*
G01X1198320D02*
X1198293D01*
X1198261Y1200132D01*
X1198107D01*
G01X1207261Y1196818D02*
X1205988D01*
G01X1199077D02*
X1198144D01*
X1198107Y1196855D01*
G01Y1220089D02*
X1198153D01*
X1198307Y1220243D01*
X1198420D01*
G01X1206920D02*
X1207261D01*
G01X1198107Y1213520D02*
X1198173D01*
X1198203Y1213550D01*
X1198320D01*
G01X1207020D02*
X1207261D01*
G01X1198107Y1236910D02*
X1198176D01*
X1198241Y1236975D01*
G01X1207020D02*
X1207044Y1236951D01*
X1207261D01*
G01X1198107Y1243587D02*
X1198146D01*
X1198227Y1243668D01*
X1198420D01*
G01X1206920D02*
X1207261D01*
G01X1211665Y771870D02*
X1211718Y771817D01*
X1212709D01*
G01X1219747D02*
X1220819D01*
G01X1236920Y778510D02*
X1236909D01*
G01X1228840D02*
X1227755D01*
X1227720Y778475D01*
G01X1211665Y778587D02*
X1211797D01*
X1211869Y778515D01*
X1212694D01*
G01X1219771Y778535D02*
X1220819D01*
G01X1211665Y781832D02*
X1211690Y781857D01*
G01X1236820Y798666D02*
X1236737D01*
X1236660Y798589D01*
G01X1228581Y798658D02*
X1228020D01*
G01X1211665Y801996D02*
X1211725Y801936D01*
X1211920D01*
G01X1220620D02*
X1220819D01*
G01X1211665Y795306D02*
X1211757D01*
X1211820Y795243D01*
G01X1236820Y808528D02*
X1236088D01*
X1235988Y808628D01*
G01X1228671Y808569D02*
X1227720D01*
G01X1211665Y815388D02*
X1211753D01*
X1211820Y815321D01*
G01X1219701D02*
X1220789D01*
X1220819Y815351D01*
G01X1211665Y808688D02*
X1211725Y808628D01*
X1211920D01*
G01X1220620D02*
X1220819D01*
G01X1236620Y801889D02*
X1236507D01*
X1236460Y801936D01*
G01X1228665Y801875D02*
X1227920D01*
G01X1228220Y832010D02*
X1228316D01*
X1228360Y832054D01*
G01X1235604D02*
X1236594D01*
X1236620Y832028D01*
G01X1211665Y832115D02*
X1211840D01*
X1211901Y832054D01*
G01X1220598D02*
X1220819D01*
G01X1279916Y896566D02*
X1279348Y895998D01*
G01X1236720Y845405D02*
X1236598D01*
X1236564Y845439D01*
G01X1228840D02*
X1228132D01*
X1228088Y845395D01*
X1228020D01*
G01X1211665Y852172D02*
X1211705Y852132D01*
X1212709D01*
G01X1219747D02*
X1220819D01*
G01X1211665Y845497D02*
X1211719D01*
X1211777Y845439D01*
X1211820D01*
G01X1219701D02*
X1220819D01*
G01X1236720Y838705D02*
X1236565D01*
X1236564Y838706D01*
Y838737D01*
X1236554Y838747D01*
G01X1228840D02*
X1228074D01*
X1228020Y838693D01*
G01X1211665Y838802D02*
X1211898D01*
X1211953Y838747D01*
G01X1220728D02*
X1220749Y838768D01*
X1220819D01*
G01X1211665Y869201D02*
X1211920D01*
G01X1219801Y868965D02*
X1220819D01*
G01X1236720Y852096D02*
X1236684Y852132D01*
G01X1228840D02*
X1228066D01*
X1228029Y852095D01*
X1228020D01*
G01X1211665Y875902D02*
X1212447D01*
X1212751Y875598D01*
G01X1219702Y875558D02*
X1220749D01*
X1220819Y875628D01*
G01Y882253D02*
X1220520D01*
G01X1212020Y882250D02*
X1211793D01*
X1211724Y882319D01*
X1211665D01*
G01X1236720Y875483D02*
X1236571D01*
X1236496Y875558D01*
G01X1228840D02*
X1228052D01*
X1228020Y875526D01*
G01X1235415Y872211D02*
X1236933D01*
X1236937Y872215D01*
X1236957D01*
G01X1220819Y888944D02*
X1220520D01*
G01X1212020D02*
X1211935D01*
X1211868Y889011D01*
X1211665D01*
G01X1213009Y895637D02*
X1211755D01*
X1211665Y895727D01*
G01X1211751Y892245D02*
X1211665D01*
G01X1211175Y919062D02*
X1211920D01*
G01X1220520D02*
X1221051D01*
G01X1220819Y912369D02*
X1220420D01*
G01X1211920D02*
X1211829D01*
X1211794Y912404D01*
X1211665D01*
G01X1220819Y905676D02*
X1220520D01*
G01X1212020D02*
X1211865D01*
X1211785Y905756D01*
X1211665D01*
G01X1305591Y941727D02*
X1303668Y939804D01*
G01X1238086Y925754D02*
X1235604D01*
G01X1228840D02*
X1226450D01*
G01X1237245Y919062D02*
X1236680D01*
G01X1228087D02*
X1227226D01*
G01X1211120Y925754D02*
X1212020D01*
G01X1220520D02*
X1221076D01*
G01X1303401Y949887D02*
X1299629Y953659D01*
G01X1237198Y942487D02*
X1235604D01*
G01X1228053D02*
X1227353D01*
G01X1211153Y949183D02*
X1211592D01*
X1211595Y949180D01*
G01X1220520D02*
X1221077D01*
G01X1210454Y942487D02*
X1211820D01*
G01X1220520D02*
X1221917D01*
G01X1237182Y949180D02*
X1236632D01*
G01X1228840D02*
X1227306D01*
G01X1227820Y959219D02*
X1227370D01*
G01X1220759Y962565D02*
X1220520D01*
G01X1212128D02*
X1212069Y962506D01*
X1212020D01*
G01X1236720Y982724D02*
X1236640Y982644D01*
X1235546D01*
G01X1228581D02*
X1228057D01*
X1228020Y982681D01*
G01X1211665Y979364D02*
X1211954D01*
X1212020Y979298D01*
G01X1220520D02*
X1220819D01*
G01X1236720Y976015D02*
X1236512D01*
X1236448Y975951D01*
G01X1228084D02*
X1228053Y975982D01*
X1228020D01*
G01X1236720Y969301D02*
X1236575D01*
X1236532Y969258D01*
G01X1228144D02*
X1228053Y969349D01*
X1228020D01*
G01X1211665Y972638D02*
X1211820D01*
X1211853Y972605D01*
X1212020D01*
G01X1220420D02*
X1220819D01*
G01X1211665Y992761D02*
X1211743D01*
X1211820Y992684D01*
G01X1220620D02*
X1220819D01*
G01X1227956Y989337D02*
X1227871Y989422D01*
X1227720D01*
G01X1211665Y986068D02*
X1211843D01*
X1211920Y985991D01*
G01X1220520D02*
X1220819D01*
G01X1211665Y1029465D02*
X1211925D01*
X1211955Y1029495D01*
G01X1220520D02*
X1220819D01*
G01X1267068Y1011753D02*
X1267067D01*
G01X1236820Y1029555D02*
X1236812D01*
X1236752Y1029495D01*
G01X1228116D02*
X1228072Y1029539D01*
X1228020D01*
G01X1236720Y1025736D02*
X1236709Y1025741D01*
G01X1228228Y1026148D02*
X1228163Y1026083D01*
X1228020D01*
G01X1211665Y1042808D02*
X1211797D01*
X1211869Y1042880D01*
G01X1220773D02*
X1220819D01*
G01X1228020Y1039479D02*
X1228117D01*
X1228172Y1039534D01*
G01X1236682D02*
X1236737Y1039479D01*
X1236820D01*
G01X1211665Y1036132D02*
X1211864D01*
X1211920Y1036188D01*
G01X1220620D02*
X1220819D01*
G01X1236720Y1032770D02*
X1236469D01*
X1236398Y1032841D01*
G01X1228188D02*
X1228128Y1032781D01*
X1228020D01*
G01Y1046157D02*
X1228140D01*
X1228210Y1046227D01*
G01X1236668D02*
X1236770Y1046125D01*
X1236820D01*
G01X1236720Y1049638D02*
X1236691D01*
X1236626Y1049573D01*
G01X1228308D02*
X1228224Y1049657D01*
X1228120D01*
G01X1212021Y1049573D02*
X1211854Y1049406D01*
X1211665D01*
G01X1291167Y1021250D02*
X1290365Y1022052D01*
G01X1236620Y1052899D02*
X1236421D01*
X1236400Y1052920D01*
G01X1228238D02*
X1228210Y1052892D01*
X1228020D01*
G01X1226466Y1072999D02*
X1228033D01*
G01X1236773D02*
X1238007D01*
G01X1238000Y1069652D02*
X1236465D01*
G01X1228408D02*
X1226459D01*
G01X1211136Y1069587D02*
X1212450D01*
G01X1220720Y1069652D02*
X1221060D01*
G01X1211167Y1066306D02*
X1211736D01*
G01X1220720D02*
X1221091D01*
G01X1227337Y1093077D02*
X1228840D01*
G01X1236790D02*
X1237007D01*
G01X1211231D02*
X1211920D01*
G01X1220720D02*
X1220901D01*
G01X1210430Y1089731D02*
X1211805D01*
G01X1220553D02*
X1221844D01*
G01X1237208Y1096342D02*
X1237126Y1096424D01*
X1235628D01*
G01X1228964D02*
X1227418D01*
X1227336Y1096342D01*
G01X1227920Y1109783D02*
X1228718D01*
G01X1235584Y1109772D02*
X1236620D01*
G01X1236820Y1106508D02*
X1235711D01*
G01X1228607Y1106544D02*
X1228020D01*
G01X1211665Y1106403D02*
X1212449D01*
X1212509Y1106463D01*
G01X1219705Y1106459D02*
X1220819D01*
G01X1211665Y1103181D02*
X1211729Y1103117D01*
X1212784D01*
G01X1219904Y1103139D02*
X1220819D01*
G01X1227807Y1129946D02*
X1228065D01*
X1228123Y1129888D01*
G01X1211665Y1126605D02*
X1212422D01*
G01X1219769Y1126615D02*
X1220819D01*
G01X1211665Y1113115D02*
X1211688D01*
G01X1282292Y1129163D02*
Y1129313D01*
X1282252Y1129353D01*
X1282169D01*
G01X1236720Y1143295D02*
X1235654D01*
G01X1228688Y1143327D02*
X1228020D01*
G01X1211665Y1143193D02*
X1211942D01*
X1212023Y1143274D01*
G01X1220773D02*
X1220819D01*
G01X1211665Y1139979D02*
X1211818D01*
X1211869Y1139928D01*
G01X1220620D02*
X1220819D01*
G01X1228612Y1133235D02*
X1228532Y1133155D01*
X1227920D01*
G01X1211665Y1129858D02*
X1212566D01*
G01X1220695Y1129888D02*
X1220752Y1129831D01*
X1220819D01*
G01X1227920Y1150102D02*
X1228105D01*
X1228240Y1149967D01*
G01X1235924D02*
X1235968Y1150011D01*
X1236020D01*
G01X1220819Y1176739D02*
X1220620D01*
G01X1211820D02*
X1211742Y1176817D01*
X1211665D01*
G01X1236620Y1169978D02*
X1236444D01*
X1236376Y1170046D01*
G01X1228226D02*
X1228163Y1169983D01*
X1227920D01*
G01X1236720Y1166728D02*
X1236577D01*
X1236548Y1166699D01*
G01X1228362D02*
X1228286Y1166775D01*
X1228020D01*
G01X1211665Y1166643D02*
X1211764D01*
X1211820Y1166699D01*
G01X1220620D02*
X1220819D01*
G01X1211665Y1163414D02*
X1211759D01*
X1211820Y1163353D01*
G01X1220620D02*
X1220819D01*
G01Y1180085D02*
X1220773D01*
G01X1211920D02*
X1211856Y1180021D01*
X1211665D01*
G01X1212640Y1190125D02*
X1211709D01*
X1211671Y1190163D01*
X1211665D01*
G01X1212636Y1186779D02*
X1211688D01*
X1211665Y1186756D01*
G01X1220819Y1203510D02*
X1220773D01*
G01X1211920D02*
X1211777D01*
X1211697Y1203430D01*
X1211665D01*
G01X1220819Y1200164D02*
X1220620D01*
G01X1211820D02*
X1211750Y1200234D01*
X1211665D01*
G01X1228020Y1220186D02*
X1228213D01*
X1228270Y1220243D01*
G01X1236396D02*
X1236458Y1220181D01*
X1236720D01*
G01X1236820Y1216938D02*
X1236606D01*
X1236564Y1216896D01*
G01X1228250D02*
X1228186Y1216960D01*
X1228020D01*
G01X1211665Y1216850D02*
X1211674D01*
X1211720Y1216896D01*
G01X1220520D02*
X1220819D01*
G01X1211665Y1213578D02*
X1211721D01*
X1211749Y1213550D01*
X1211920D01*
G01X1220520D02*
X1220819D01*
G01X1236620Y1240365D02*
X1236468D01*
X1236424Y1240321D01*
G01X1228284D02*
X1228244Y1240361D01*
X1228120D01*
G01X1211601Y1240271D02*
X1211611D01*
X1211661Y1240321D01*
X1211820D01*
G01X1220520D02*
X1220523Y1240324D01*
X1220755D01*
G01X1211665Y1236975D02*
X1211920D01*
G01X1220520D02*
X1220609D01*
X1220640Y1237006D01*
X1220819D01*
G01X1236720Y1243616D02*
X1236552D01*
X1236500Y1243668D01*
G01X1228324D02*
X1228260Y1243604D01*
X1228120D01*
G01X1279599Y854272D02*
X1279596D01*
G01X1306443Y940875D02*
X1304172Y938604D01*
G01X1288731Y1020122D02*
X1287983Y1020870D01*
G01X1547959Y1011133D02*
X1548336D01*
G01X1547667Y1008615D02*
X1547959D01*
G01X1597369Y993046D02*
X1597529Y992886D01*
G01X1604109Y992684D02*
X1605298D01*
X1605369Y992755D01*
G01X1597369Y771859D02*
X1597503D01*
X1597545Y771817D01*
G01X1597169Y778549D02*
X1597208Y778510D01*
X1598518D01*
G01X1605369Y778573D02*
X1605669D01*
G01X1597369Y785286D02*
X1597388D01*
G01X1597369Y781802D02*
X1597389D01*
G01X1605323Y781774D02*
X1605369D01*
G01X1597369Y815363D02*
X1597503D01*
X1597545Y815321D01*
G01X1597369Y808670D02*
X1597503D01*
X1597545Y808628D01*
G01X1539370Y839144D02*
X1539812Y838702D01*
Y833105D01*
G01X1597369Y801978D02*
X1597503D01*
X1597545Y801936D01*
G01X1597369Y795285D02*
X1597503D01*
X1597545Y795243D01*
G01X1597369Y822040D02*
X1597395Y822014D01*
X1598892D01*
G01X1605340Y822071D02*
X1605369D01*
G01X1597369Y818626D02*
X1597411Y818668D01*
X1598385D01*
G01X1602622D02*
X1604197D01*
G01X1597369Y845513D02*
X1597388D01*
G01X1597369Y838828D02*
X1597388D01*
G01X1597369Y832082D02*
X1597397Y832054D01*
G01X1596616Y919141D02*
X1596695Y919062D01*
X1597454D01*
G01X1605313D02*
X1606187D01*
G01X1597369Y875612D02*
X1597388D01*
G01X1597369Y868917D02*
X1597388D01*
G01X1597369Y852152D02*
X1597388Y852133D01*
G01X1597369Y858904D02*
X1597448Y858825D01*
G01X1597369Y855415D02*
X1597388D01*
G01X1604842Y855479D02*
X1605369D01*
G01X1596701Y922373D02*
X1596736Y922408D01*
X1597423D01*
G01X1605309D02*
X1605869D01*
X1605951Y922326D01*
G01X1596544Y945758D02*
X1596619Y945833D01*
X1597487D01*
G01X1605242D02*
X1605871D01*
X1605946Y945758D01*
G01X1597369Y939140D02*
X1597388D01*
G01X1605312Y939077D02*
X1605369D01*
G01X1595396Y932531D02*
X1595480Y932447D01*
X1597616D01*
G01X1605298D02*
X1607169D01*
G01X1595396Y929101D02*
X1597415D01*
G01X1605257D02*
X1607169D01*
G01X1561216Y976788D02*
X1561263Y976835D01*
G01X1597369Y986078D02*
X1597376D01*
X1597463Y985991D01*
G01X1605212Y986033D02*
X1605369D01*
G01X1597369Y979392D02*
X1597461D01*
G01X1605212Y979371D02*
X1605369D01*
G01X1597369Y969179D02*
X1597612D01*
G01X1605157Y968913D02*
X1605266Y968804D01*
G01X1613511Y969355D02*
X1613530D01*
G01X1620066Y969258D02*
X1621413D01*
X1621511Y969356D01*
G01X1613511Y965865D02*
X1613550D01*
G01X1626306Y962565D02*
X1626347D01*
G01X1634932Y962528D02*
X1635069D01*
G01X1596555Y955873D02*
X1596639D01*
G01X1597512Y972654D02*
X1597493D01*
G01X1561327Y1016383D02*
X1562028Y1016673D01*
G01X1547959Y1013651D02*
X1548336D01*
G01X1597369Y1029454D02*
X1597437D01*
G01X1552635Y1022372D02*
X1552925Y1022662D01*
G01X1555476Y1021216D02*
X1555730Y1021470D01*
G01X1597369Y1042813D02*
X1597388D01*
G01X1605169Y1042823D02*
X1605369D01*
G01X1558040Y1020219D02*
X1558261Y1020440D01*
G01X1559718Y1018335D02*
X1560042Y1018659D01*
G01X1597369Y1056227D02*
X1597388D01*
G01X1605363Y1056194D02*
X1605369D01*
G01X1613693Y1056305D02*
X1613712D01*
G01X1548976Y1026082D02*
X1549495Y1026601D01*
G01X1597369Y1052979D02*
X1597388D01*
G01X1603727Y1052920D02*
X1605310D01*
X1605369Y1052979D01*
G01X1613793Y1052867D02*
X1613812D01*
G01X1621099Y1052821D02*
X1621193D01*
G01X1627193Y1052948D02*
X1627212D01*
G01X1633184Y1052920D02*
X1634996D01*
X1635069Y1052993D01*
G01X1551100Y1024509D02*
X1551343Y1024752D01*
G01X1597369Y1049522D02*
X1597388D01*
G01X1596264Y1093077D02*
X1597499D01*
G01X1605239D02*
X1606073D01*
G01X1596264Y1086384D02*
X1597475D01*
G01X1605304D02*
X1606073D01*
G01X1575453Y1073062D02*
Y1073063D01*
G01X1595775Y1069652D02*
X1597006D01*
G01X1605301D02*
X1606894D01*
G01X1596709Y1066306D02*
X1597359D01*
G01X1605346D02*
X1606134D01*
G01X1596280Y1079691D02*
X1597388D01*
G01X1605287D02*
X1605831D01*
X1605903Y1079763D01*
G01X1596280Y1076344D02*
X1597388D01*
G01X1605283Y1076345D02*
X1605826D01*
X1605912Y1076259D01*
G01X1597369Y1126676D02*
X1597388D01*
G01X1597369Y1109845D02*
X1597420D01*
G01X1596709Y1103117D02*
X1597439D01*
G01X1605369Y1103244D02*
X1606518D01*
G01X1597369Y1113129D02*
X1597395D01*
G01X1605360Y1113075D02*
X1605369D01*
G01X1597369Y1146689D02*
X1597437Y1146621D01*
X1598138D01*
G01X1597369Y1140075D02*
X1597388D01*
G01X1597369Y1133336D02*
X1597388D01*
G01X1597369Y1153364D02*
X1597394D01*
G01X1605161Y1153314D02*
X1605186Y1153339D01*
X1605369D01*
G01X1597369Y1149914D02*
X1597389D01*
G01X1605359Y1149884D02*
X1605369D01*
G01X1597369Y1170065D02*
X1597388Y1170046D01*
G01X1597369Y1163506D02*
X1597522Y1163353D01*
G01X1538279Y1155727D02*
X1538907Y1157243D01*
G01X1597369Y1213576D02*
X1597388D01*
G01X1597369Y1237040D02*
X1597388D01*
G01X1604581Y1236975D02*
X1605294D01*
X1605330Y1237011D01*
X1605369D01*
G01X1597593Y1216873D02*
X1597612D01*
G01X1597369Y1226962D02*
X1597388D01*
G01X1597369Y1223569D02*
X1597389D01*
G01X1602622Y1223589D02*
X1604197D01*
G01X1525086Y1168026D02*
X1525287Y1168227D01*
G01X1597369Y1243691D02*
X1597447D01*
X1597470Y1243668D01*
X1598413D01*
G01X1604829D02*
X1605225D01*
X1605264Y1243707D01*
X1605369D01*
G01X1613687Y778511D02*
X1613645Y778469D01*
X1613511D01*
G01X1613687Y771818D02*
X1613645Y771776D01*
X1613511D01*
G01X1613530Y788498D02*
X1613511D01*
G01X1613687Y795243D02*
X1613645Y795201D01*
X1613511D01*
G01X1613524Y791972D02*
X1613511D01*
G01X1613687Y815321D02*
X1613645Y815279D01*
X1613511D01*
G01X1613687Y808628D02*
X1613645Y808586D01*
X1613511D01*
G01X1613687Y801936D02*
X1613645Y801894D01*
X1613511D01*
G01X1613530Y831993D02*
X1613511D01*
G01X1621511Y825320D02*
X1621488D01*
G01X1613530Y825246D02*
X1613511D01*
G01X1621511Y828783D02*
X1621492D01*
G01X1613537Y828770D02*
X1613511D01*
G01X1621511Y845420D02*
X1621408D01*
G01X1613641Y845440D02*
X1613572D01*
X1613511Y845379D01*
G01X1613530Y838695D02*
X1613511D01*
G01X1621511Y852065D02*
X1621443Y852133D01*
G01X1613640Y852079D02*
X1613511D01*
G01X1613553Y865570D02*
X1613511D01*
G01X1612790Y882251D02*
X1612869D01*
G01X1621511Y875500D02*
X1621449D01*
X1621391Y875558D01*
G01X1613530Y875520D02*
X1613511D01*
G01X1621511Y868807D02*
X1621449D01*
X1621391Y868865D01*
G01X1613530Y868831D02*
X1613511D01*
G01X1612790Y888944D02*
X1612975D01*
G01X1621511Y898888D02*
X1621437D01*
G01X1612783Y898983D02*
X1612741D01*
G01X1612788Y902330D02*
X1612764D01*
G01X1612790Y912369D02*
X1612975D01*
G01X1621486D02*
X1622336D01*
G01X1612790Y905676D02*
X1612869D01*
G01X1622744Y925755D02*
X1621467D01*
G01X1613651D02*
X1611887D01*
X1611786Y925654D01*
G01X1622153Y918993D02*
X1622084Y919062D01*
X1621328D01*
G01X1613582D02*
X1612888D01*
X1612836Y919010D01*
G01X1622272Y942414D02*
X1622199Y942487D01*
X1621438D01*
G01X1613624D02*
X1612912D01*
X1612837Y942412D01*
G01X1611920Y935728D02*
X1611986Y935794D01*
X1613596D01*
G01X1621429D02*
X1623144D01*
G01Y939141D02*
X1621439D01*
G01X1613606D02*
X1611996D01*
X1611920Y939217D01*
G01X1621963Y949094D02*
X1621877Y949180D01*
X1620730D01*
G01X1613594D02*
X1612697D01*
G01X1613530Y982728D02*
X1613511D01*
G01X1613530Y976007D02*
X1613511D01*
G01X1621511Y992684D02*
X1621097D01*
G01X1613530Y993422D02*
X1613511Y993441D01*
G01X1613530Y989389D02*
X1613511D01*
G01X1613530Y1029648D02*
X1613511D01*
G01X1621511Y1049619D02*
X1621508D01*
G01X1613530Y1049636D02*
X1613511D01*
G01X1622215Y1059613D02*
X1620795D01*
G01X1613634D02*
X1612790D01*
G01X1623036Y1072999D02*
X1620826D01*
G01X1613566D02*
X1611917D01*
G01X1622215Y1066306D02*
X1621431D01*
G01X1613841D02*
X1612721D01*
X1612406Y1065991D01*
G01X1622215Y1089731D02*
X1621462D01*
G01X1613559D02*
X1612406D01*
G01X1622116Y1082988D02*
X1622066Y1083038D01*
X1621385D01*
G01X1613592D02*
X1612143D01*
X1612081Y1082976D01*
G01X1622116Y1086466D02*
X1622035Y1086385D01*
X1621278D01*
G01X1613574D02*
X1612146D01*
X1612102Y1086429D01*
G01X1622215Y1096022D02*
X1621211D01*
G01X1613575Y1096424D02*
X1612406D01*
G01X1613530Y1109773D02*
X1613511D01*
G01X1613517Y1106534D02*
X1613511D01*
G01X1613530Y1126498D02*
X1613511D01*
G01X1613530Y1119787D02*
X1613511D01*
G01X1613530Y1123242D02*
X1613511D01*
G01X1621511Y1139893D02*
X1621476Y1139928D01*
G01X1616741D02*
X1613640D01*
X1613614Y1139902D01*
X1613511D01*
G01X1621511Y1133264D02*
X1621472D01*
G01X1616741Y1133235D02*
X1613545D01*
X1613511Y1133201D01*
G01X1621511Y1146605D02*
X1621495Y1146621D01*
G01X1616741D02*
X1613664D01*
X1613632Y1146589D01*
X1613511D01*
G01X1613530Y1156598D02*
X1613511D01*
G01X1613530Y1160053D02*
X1613511D01*
G01X1621511Y1170001D02*
X1621466Y1170046D01*
X1618325D01*
G01X1613580Y1170017D02*
X1613511D01*
G01X1621511Y1163308D02*
X1621466Y1163353D01*
X1618325D01*
G01X1613580Y1163324D02*
X1613511D01*
G01X1612790Y1183432D02*
X1612975D01*
G01X1612790Y1176739D02*
X1612869D01*
G01X1613530Y1193471D02*
X1612732D01*
G01X1613530Y1206857D02*
X1612529D01*
G01X1613530Y1200164D02*
X1612798D01*
G01X1621511Y1196863D02*
X1621464D01*
G01X1613530Y1196818D02*
X1612732D01*
G01X1613530Y1220200D02*
X1613511D01*
G01X1613530Y1213528D02*
X1613511D01*
G01X1613530Y1236940D02*
X1613511D01*
G01X1613530Y1230167D02*
X1613511D01*
G01X1613530Y1233629D02*
X1613511D01*
G01X1621511Y1243630D02*
X1621466D01*
X1621428Y1243668D01*
X1620483D01*
G01X1613530Y1243521D02*
X1613511D01*
G01X1627245Y771817D02*
X1627203Y771859D01*
X1627069D01*
G01X1627245Y778510D02*
X1627203Y778552D01*
X1627069D01*
G01X1627088Y785228D02*
X1627069D01*
G01X1627088Y781829D02*
X1627069D01*
G01X1627245Y801936D02*
X1627203Y801978D01*
X1627069D01*
G01X1627245Y795243D02*
X1627203Y795285D01*
X1627069D01*
G01X1627245Y815321D02*
X1627203Y815363D01*
X1627069D01*
G01X1627245Y808628D02*
X1627203Y808670D01*
X1627069D01*
G01X1627151Y818588D02*
X1627069D01*
G01X1627245Y832054D02*
X1627203Y832096D01*
X1627069D01*
G01X1633820Y822014D02*
X1632248D01*
G01X1627590D02*
X1627096D01*
X1627073Y822037D01*
X1627069D01*
G01X1635069Y852186D02*
X1634979D01*
G01X1627085Y852197D02*
X1627069D01*
G01X1627245Y845439D02*
X1627203Y845481D01*
X1627069D01*
G01X1627245Y838747D02*
X1627203Y838789D01*
X1627069D01*
G01X1635069Y868939D02*
X1634940D01*
X1634866Y868865D01*
G01X1627109Y868922D02*
X1627069D01*
G01X1627088Y858850D02*
X1627069D01*
G01X1627088Y855451D02*
X1627069D01*
G01X1635069Y875632D02*
X1634940D01*
X1634866Y875558D01*
G01X1627109Y875615D02*
X1627069D01*
G01X1635069Y882324D02*
X1634940D01*
X1634866Y882250D01*
G01X1627109Y882307D02*
X1627069D01*
G01X1635069Y889017D02*
X1634940D01*
X1634866Y888943D01*
G01X1627109Y889000D02*
X1627069D01*
G01X1627088Y895661D02*
X1627069D01*
G01X1627088Y892262D02*
X1627069D01*
G01X1635939Y919062D02*
X1634965D01*
G01X1627224D02*
X1626268D01*
G01X1627134Y912428D02*
X1627069D01*
G01X1627138Y905731D02*
X1627069D01*
G01X1637003Y925821D02*
X1636937Y925755D01*
X1635025D01*
G01X1627193D02*
X1626424D01*
X1626369Y925810D01*
G01X1636636Y932491D02*
X1636593Y932448D01*
X1635026D01*
G01X1627112D02*
X1625419D01*
X1625395Y932472D01*
G01X1636636Y929072D02*
X1636607Y929101D01*
X1635040D01*
G01X1627116D02*
X1625395D01*
G01X1635452Y945379D02*
X1635069Y945762D01*
G01X1627198Y945834D02*
X1626373D01*
G01X1635856Y942580D02*
X1635763Y942487D01*
X1634989D01*
G01X1627176D02*
X1626374D01*
X1626336Y942525D01*
G01X1627145Y979330D02*
X1627069D01*
G01X1627138Y972667D02*
X1627069D01*
G01X1627121Y992761D02*
X1627069D01*
G01X1627138Y986028D02*
X1627069D01*
G01X1627089Y1032903D02*
X1627069D01*
G01X1627672Y1046227D02*
X1627102D01*
X1627069Y1046260D01*
G01X1627138Y1039589D02*
X1627069D01*
G01X1636218Y1072999D02*
X1635020D01*
G01X1627198D02*
X1626409D01*
G01X1636218Y1066306D02*
X1634771D01*
G01X1627253D02*
X1626409D01*
G01X1636720Y1079692D02*
X1635026D01*
G01X1627112D02*
X1625660D01*
G01X1636788Y1076345D02*
X1635040D01*
G01X1627116D02*
X1625639D01*
G01X1635352Y1092633D02*
X1634907Y1093078D01*
G01X1627174D02*
X1625964D01*
G01X1637192Y1089731D02*
X1634654D01*
G01X1627206D02*
X1625660D01*
G01X1627138Y1109845D02*
X1627069D01*
G01X1627138Y1103149D02*
X1627069D01*
G01X1635069Y1126587D02*
X1635024Y1126542D01*
X1631883D01*
G01X1627138Y1126571D02*
X1627069D01*
G01X1627088Y1116527D02*
X1627069D01*
G01X1627088Y1113128D02*
X1627069D01*
G01X1635069Y1146666D02*
X1635024Y1146621D01*
X1631883D01*
G01X1627138Y1146650D02*
X1627069D01*
G01X1635069Y1139973D02*
X1635024Y1139928D01*
X1631883D01*
G01X1627138Y1139957D02*
X1627069D01*
G01X1635069Y1133280D02*
X1635024Y1133235D01*
X1631883D01*
G01X1627138Y1133264D02*
X1627069D01*
G01X1627088Y1153338D02*
X1627069D01*
G01X1627088Y1149940D02*
X1627069D01*
G01X1635069Y1176784D02*
X1635024Y1176739D01*
X1631883D01*
G01X1627138Y1176768D02*
X1627069D01*
G01X1635069Y1170091D02*
X1635024Y1170046D01*
X1631883D01*
G01X1627138Y1170075D02*
X1627069D01*
G01X1635069Y1163398D02*
X1635024Y1163353D01*
X1631883D01*
G01X1627138Y1163382D02*
X1627069D01*
G01X1635069Y1183470D02*
X1635031Y1183432D01*
X1632642D01*
G01X1627138Y1183454D02*
X1627069D01*
G01X1627088Y1190145D02*
X1627069D01*
G01X1627088Y1186759D02*
X1627087D01*
X1627084Y1186756D01*
X1627069D01*
G01X1635069Y1206903D02*
X1635023Y1206857D01*
X1632518D01*
G01X1627138Y1206893D02*
X1627069D01*
G01X1635069Y1200209D02*
X1635024Y1200164D01*
X1631873D01*
G01X1627138Y1200206D02*
X1627069D01*
G01X1635069Y1220289D02*
X1635023Y1220243D01*
X1632219D01*
G01X1627172Y1220269D02*
X1627069D01*
G01X1635069Y1213571D02*
X1635048Y1213550D01*
X1632896D01*
G01X1627138Y1213570D02*
X1627069D01*
G01X1633820Y1226936D02*
X1632248D01*
G01X1627199D02*
X1627169Y1226966D01*
X1627069D01*
G01X1627187Y1223547D02*
X1627165Y1223569D01*
X1627069D01*
G01X1635069Y1243715D02*
X1634832D01*
X1634785Y1243668D01*
X1634631D01*
G01X1627381D02*
X1627333Y1243716D01*
X1627069D01*
G01X1635069Y1237013D02*
X1634993D01*
X1634955Y1236975D01*
G01X1627138Y1237014D02*
X1627069D01*
G01X1672375Y778511D02*
X1672190D01*
G01X1672269Y771818D02*
X1672190D01*
G01X1672292Y788550D02*
X1672309D01*
G01X1672375Y801936D02*
X1672190D01*
G01X1672269Y795243D02*
X1672190D01*
G01X1672292Y791897D02*
X1672394D01*
G01X1672375Y815322D02*
X1672190D01*
G01X1672269Y808629D02*
X1672190D01*
G01X1672269Y832054D02*
X1672190D01*
G01X1672292Y825361D02*
X1672309D01*
G01X1672292Y828708D02*
X1672394D01*
G01X1672375Y852133D02*
X1672190D01*
G01X1672269Y845440D02*
X1672190D01*
G01X1672375Y838747D02*
X1672190D01*
G01X1672292Y862172D02*
X1672309D01*
G01X1672292Y865519D02*
X1672394D01*
G01X1672269Y882251D02*
X1672190D01*
G01X1672375Y875558D02*
X1672190D01*
G01X1672269Y868865D02*
X1672190D01*
G01X1672375Y888944D02*
X1672190D01*
G01X1672292Y898983D02*
X1672309D01*
G01X1672292Y902330D02*
X1672394D01*
G01X1672375Y912369D02*
X1672190D01*
G01X1672269Y905676D02*
X1672190D01*
G01X1672375Y925755D02*
X1672190D01*
G01X1672269Y919062D02*
X1672190D01*
G01X1672375Y949180D02*
X1672190D01*
G01X1672269Y942487D02*
X1672190D01*
G01X1672292Y935794D02*
X1672309D01*
G01X1672292Y939141D02*
X1672394D01*
G01X1672255Y982644D02*
X1672309D01*
G01X1672255Y975951D02*
X1672309D01*
G01X1672255Y989337D02*
X1672309D01*
G01X1672255Y1029495D02*
X1672309D01*
G01X1672219Y1019456D02*
X1672299D01*
G01X1672255Y1049573D02*
X1672309D01*
G01X1671776Y1042880D02*
X1671943D01*
G01X1671986Y1036188D02*
X1671871D01*
G01X1672719Y1059556D02*
X1672930D01*
G01X1672375Y1072999D02*
X1672190D01*
G01X1672269Y1066306D02*
X1672190D01*
G01X1672269Y1089731D02*
X1672190D01*
G01X1672292Y1083038D02*
X1672309D01*
G01X1672292Y1086385D02*
X1672394D01*
G01X1672375Y1096424D02*
X1672190D01*
G01X1672375Y1109810D02*
X1672190D01*
G01X1672269Y1103117D02*
X1672190D01*
G01X1672269Y1126542D02*
X1672190D01*
G01X1672292Y1119849D02*
X1672309D01*
G01X1672292Y1123196D02*
X1672394D01*
G01X1672269Y1139928D02*
X1672190D01*
G01X1672375Y1133235D02*
X1672190D01*
G01X1672375Y1146621D02*
X1672190D01*
G01X1672292Y1156660D02*
X1672309D01*
G01X1672292Y1160007D02*
X1672394D01*
G01X1672269Y1176739D02*
X1672190D01*
G01X1672375Y1170046D02*
X1672190D01*
G01X1672269Y1163353D02*
X1672190D01*
G01X1672375Y1183432D02*
X1672190D01*
G01X1672292Y1193471D02*
X1672309D01*
G01X1672375Y1206857D02*
X1672190D01*
G01X1672269Y1200164D02*
X1672190D01*
G01X1672292Y1196818D02*
X1672394D01*
G01X1672375Y1220243D02*
X1672190D01*
G01X1672269Y1213550D02*
X1672190D01*
G01X1672269Y1236975D02*
X1672190D01*
G01X1672292Y1230282D02*
X1672309D01*
G01X1672292Y1233629D02*
X1672394D01*
G01X1672375Y1243668D02*
X1672190D01*
G01X1686469Y771845D02*
X1686488D01*
G01X1686469Y778538D02*
X1686488D01*
G01X1686469Y785228D02*
X1686488D01*
G01X1686469Y781829D02*
X1686488D01*
G01X1686469Y801964D02*
X1686488D01*
G01X1686469Y795271D02*
X1686488D01*
G01X1686469Y815349D02*
X1686488D01*
G01X1686469Y808656D02*
X1686488D01*
G01X1686469Y818640D02*
X1686488D01*
G01X1686469Y832082D02*
X1686488D01*
G01X1686469Y822039D02*
X1686488D01*
G01X1686469Y852160D02*
X1686488D01*
G01X1686469Y845467D02*
X1686488D01*
G01X1686469Y838775D02*
X1686488D01*
G01X1686469Y868893D02*
X1686488D01*
G01X1686469Y858850D02*
X1686488D01*
G01X1686469Y855451D02*
X1686488D01*
G01X1686469Y875586D02*
X1686488D01*
G01X1686469Y882278D02*
X1686488D01*
G01X1686469Y888971D02*
X1686488D01*
G01X1686469Y895661D02*
X1686488D01*
G01X1686469Y892262D02*
X1686488D01*
G01X1686469Y912397D02*
X1686488D01*
G01X1686469Y905704D02*
X1686488D01*
G01X1686469Y925782D02*
X1686488D01*
G01X1686469Y919090D02*
X1686488D01*
G01X1686469Y932472D02*
X1686488D01*
G01X1686469Y929073D02*
X1686488D01*
G01X1686469Y949208D02*
X1686488D01*
G01X1686469Y942515D02*
X1686488D01*
G01X1686469Y979340D02*
X1686488D01*
G01X1686469Y972647D02*
X1686488D01*
G01X1686469Y992726D02*
X1686488D01*
G01X1686469Y986033D02*
X1686488D01*
G01X1686469Y1032883D02*
X1686488D01*
G01X1686469Y1046269D02*
X1686488D01*
G01X1686469Y1039576D02*
X1686488D01*
G01Y1073027D02*
X1686469D01*
G01Y1066334D02*
X1686488D01*
G01X1686469Y1079716D02*
X1686488D01*
G01X1686469Y1076317D02*
X1686488D01*
G01X1686469Y1096452D02*
X1686488D01*
G01X1686469Y1089759D02*
X1686488D01*
G01Y1109838D02*
X1686469D01*
G01Y1103145D02*
X1686488D01*
G01X1686469Y1126570D02*
X1686488D01*
G01X1686469Y1116527D02*
X1686488D01*
G01X1686469Y1113128D02*
X1686488D01*
G01Y1146649D02*
X1686469D01*
G01Y1139956D02*
X1686488D01*
G01X1686469Y1133263D02*
X1686488D01*
G01X1686469Y1153338D02*
X1686488D01*
G01Y1149940D02*
X1686469D01*
G01Y1176767D02*
X1686488D01*
G01X1686469Y1170074D02*
X1686488D01*
G01X1686469Y1163381D02*
X1686488D01*
G01Y1183460D02*
X1686469D01*
G01Y1190149D02*
X1686488D01*
G01Y1186751D02*
X1686469D01*
G01Y1206885D02*
X1686488D01*
G01X1686469Y1200192D02*
X1686488D01*
G01Y1220271D02*
X1686469D01*
G01Y1213578D02*
X1686488D01*
G01X1686469Y1226960D02*
X1686488D01*
G01Y1223562D02*
X1686469D01*
G01Y1243696D02*
X1686488D01*
G01X1686469Y1237003D02*
X1686488D01*
G01X1731775Y778511D02*
X1731590D01*
G01X1731669Y771818D02*
X1731590D01*
G01X1731692Y788550D02*
X1731709D01*
G01X1731669Y795243D02*
X1731590D01*
G01X1731692Y791897D02*
X1731794D01*
G01X1731775Y815322D02*
X1731590D01*
G01X1731669Y808629D02*
X1731590D01*
G01X1731775Y801936D02*
X1731590D01*
G01X1731669Y832054D02*
X1731590D01*
G01X1731692Y825361D02*
X1731709D01*
G01X1731692Y828708D02*
X1731794D01*
G01X1731669Y845440D02*
X1731590D01*
G01X1731775Y838747D02*
X1731590D01*
G01X1731775Y852133D02*
X1731590D01*
G01X1731692Y862172D02*
X1731709D01*
G01X1731692Y865519D02*
X1731794D01*
G01X1731669Y882251D02*
X1731590D01*
G01X1731775Y875558D02*
X1731590D01*
G01X1731669Y868865D02*
X1731590D01*
G01X1731775Y888944D02*
X1731590D01*
G01X1731692Y898983D02*
X1731709D01*
G01X1731692Y902330D02*
X1731794D01*
G01X1731775Y912369D02*
X1731590D01*
G01X1731669Y905676D02*
X1731590D01*
G01X1741015Y925755D02*
X1740871D01*
G01X1731775D02*
X1731206D01*
G01X1741015Y919062D02*
X1740871D01*
G01X1731775D02*
X1731206D01*
G01X1741015Y942487D02*
X1740871D01*
G01X1731775D02*
X1731206D01*
G01X1731438Y935794D02*
X1731709D01*
G01X1740290D02*
X1741015D01*
G01X1731651Y939141D02*
X1731794D01*
G01X1740287D02*
X1741130D01*
G01X1741015Y949180D02*
X1740871D01*
G01X1731775D02*
X1731206D01*
G01X1731655Y982644D02*
X1731709D01*
G01X1731655Y975951D02*
X1731709D01*
G01X1731655Y989337D02*
X1731709D01*
G01X1731655Y1029495D02*
X1731709D01*
G01X1731619Y1019456D02*
X1731699D01*
G01X1731176Y1042880D02*
X1731343D01*
G01X1731271Y1036188D02*
X1731386D01*
G01X1741015Y1059613D02*
X1740871D01*
G01X1731775D02*
X1731206D01*
G01X1731655Y1049573D02*
X1731709D01*
G01X1741015Y1072999D02*
X1740871D01*
G01X1731775D02*
X1731206D01*
G01X1741015Y1066306D02*
X1740871D01*
G01X1731775D02*
X1731206D01*
G01X1741015Y1089731D02*
X1740871D01*
G01X1731775D02*
X1731206D01*
G01X1731438Y1083038D02*
X1731709D01*
G01X1740290D02*
X1741015D01*
G01X1731651Y1086385D02*
X1731794D01*
G01X1740287D02*
X1741130D01*
G01X1741015Y1096424D02*
X1740871D01*
G01X1731775D02*
X1731206D01*
G01X1731775Y1109810D02*
X1731165D01*
G01X1731669Y1103117D02*
X1731590D01*
G01X1731669Y1126542D02*
X1731590D01*
G01X1731692Y1119849D02*
X1731709D01*
G01X1731692Y1123196D02*
X1731794D01*
G01X1731669Y1139928D02*
X1731590D01*
G01X1731775Y1133235D02*
X1731590D01*
G01X1731775Y1146621D02*
X1731590D01*
G01X1731692Y1156660D02*
X1731709D01*
G01X1731692Y1160007D02*
X1731794D01*
G01X1731775Y1170046D02*
X1731590D01*
G01X1731669Y1163353D02*
X1731590D01*
G01X1731399Y1183432D02*
X1731328D01*
G01X1731669Y1176739D02*
X1731590D01*
G01X1731692Y1193471D02*
X1731709D01*
G01X1731775Y1206857D02*
X1731590D01*
G01X1731669Y1200164D02*
X1731590D01*
G01X1731692Y1196818D02*
X1731794D01*
G01X1731775Y1220243D02*
X1731590D01*
G01X1731669Y1213550D02*
X1731590D01*
G01X1731669Y1236975D02*
X1731590D01*
G01X1731692Y1230282D02*
X1731709D01*
G01X1731692Y1233629D02*
X1731794D01*
G01X1731775Y1243668D02*
X1731590D01*
G01X1745869Y771845D02*
X1745888D01*
G01X1745869Y778538D02*
X1745888D01*
G01X1745869Y785228D02*
X1745888D01*
G01X1745869Y781829D02*
X1745888D01*
G01X1745869Y801964D02*
X1745888D01*
G01X1745869Y795271D02*
X1745888D01*
G01X1745869Y815349D02*
X1745888D01*
G01X1745869Y808656D02*
X1745888D01*
G01X1745869Y832082D02*
X1745888D01*
G01X1745869Y822039D02*
X1745888D01*
G01X1745869Y818640D02*
X1745888D01*
G01X1745869Y852160D02*
X1745888D01*
G01X1745869Y845467D02*
X1745888D01*
G01X1745869Y838775D02*
X1745888D01*
G01X1745869Y868893D02*
X1745888D01*
G01X1745869Y858850D02*
X1745888D01*
G01X1745869Y855451D02*
X1745888D01*
G01X1745869Y875586D02*
X1745888D01*
G01X1745869Y882278D02*
X1745888D01*
G01X1745869Y888971D02*
X1745888D01*
G01X1745869Y895661D02*
X1745888D01*
G01X1745869Y892262D02*
X1745888D01*
G01X1745869Y912397D02*
X1745888D01*
G01X1745869Y905704D02*
X1745888D01*
G01X1745209Y925754D02*
X1745916D01*
G01X1753657D02*
X1755018D01*
G01X1745209Y919062D02*
X1745916D01*
G01X1753821D02*
X1755018D01*
G01X1744996Y929101D02*
X1745916D01*
G01X1753840D02*
X1754573D01*
G01X1745209Y949180D02*
X1745916D01*
G01X1753657D02*
X1755018D01*
G01X1745209Y942487D02*
X1745916D01*
G01X1753821D02*
X1755018D01*
G01X1745209Y932448D02*
X1745912D01*
G01X1753826D02*
X1754688D01*
G01X1745869Y979340D02*
X1745888D01*
G01X1745869Y972647D02*
X1745888D01*
G01X1745869Y992726D02*
X1745888D01*
G01X1745869Y986033D02*
X1745888D01*
G01X1745869Y1046269D02*
X1745888D01*
G01X1745869Y1039576D02*
X1745888D01*
G01X1745869Y1032883D02*
X1745888D01*
G01X1745209Y1072999D02*
X1745916D01*
G01X1753657D02*
X1755018D01*
G01X1745209Y1066306D02*
X1745916D01*
G01X1753821D02*
X1755018D01*
G01X1744996Y1076345D02*
X1745916D01*
G01X1753840D02*
X1754573D01*
G01X1745209Y1096424D02*
X1745916D01*
G01X1753657D02*
X1755018D01*
G01X1745209Y1089731D02*
X1745916D01*
G01X1753821D02*
X1755018D01*
G01X1745209Y1079692D02*
X1745912D01*
G01X1753826D02*
X1754688D01*
G01X1745869Y1109838D02*
X1745888D01*
G01X1745869Y1103145D02*
X1745888D01*
G01X1745869Y1126570D02*
X1745888D01*
G01X1745869Y1116527D02*
X1745888D01*
G01X1745869Y1113128D02*
X1745888D01*
G01X1745869Y1139956D02*
X1745888D01*
G01X1745869Y1133263D02*
X1745888D01*
G01X1745869Y1146649D02*
X1745888D01*
G01X1745869Y1153338D02*
X1745888D01*
G01X1745869Y1149940D02*
X1745888D01*
G01X1745869Y1176767D02*
X1745888D01*
G01X1745869Y1170074D02*
X1745888D01*
G01X1745869Y1163381D02*
X1745888D01*
G01X1745869Y1183460D02*
X1745888D01*
G01X1745869Y1190149D02*
X1745888D01*
G01X1745869Y1186751D02*
X1745888D01*
G01X1745869Y1206885D02*
X1745888D01*
G01X1745869Y1200192D02*
X1745888D01*
G01X1745869Y1220271D02*
X1745888D01*
G01X1745869Y1213578D02*
X1745888D01*
G01X1745869Y1223562D02*
X1745888D01*
G01X1745869Y1243696D02*
X1745888D01*
G01X1745869Y1237003D02*
X1745888D01*
G01X1745869Y1226960D02*
X1745888D01*
G01X1791175Y778511D02*
X1790990D01*
G01X1791069Y771818D02*
X1790990D01*
G01X1791109Y788550D02*
X1791092D01*
G01X1791069Y795243D02*
X1790990D01*
G01X1791194Y791897D02*
X1791092D01*
G01X1791175Y815322D02*
X1790990D01*
G01X1791069Y808629D02*
X1790990D01*
G01X1791175Y801936D02*
X1790990D01*
G01X1791069Y832054D02*
X1790990D01*
G01X1791092Y825361D02*
X1791109D01*
G01X1791092Y828708D02*
X1791194D01*
G01X1791069Y845440D02*
X1790990D01*
G01X1791175Y838747D02*
X1790990D01*
G01X1791175Y852133D02*
X1790990D01*
G01X1791109Y862172D02*
X1791092D01*
G01X1791194Y865519D02*
X1791092D01*
G01X1791069Y882251D02*
X1790990D01*
G01X1791175Y875558D02*
X1790990D01*
G01X1791069Y868865D02*
X1790990D01*
G01X1791175Y888944D02*
X1790990D01*
G01X1791109Y898983D02*
X1791092D01*
G01X1791194Y902330D02*
X1791092D01*
G01X1791175Y912369D02*
X1790990D01*
G01X1791069Y905676D02*
X1790990D01*
G01X1791175Y925755D02*
X1790990D01*
G01X1791069Y919062D02*
X1790990D01*
G01X1791069Y942487D02*
X1790990D01*
G01X1791109Y935794D02*
X1791092D01*
G01X1791194Y939141D02*
X1791092D01*
G01X1791175Y949180D02*
X1790990D01*
G01X1791055Y982644D02*
X1791109D01*
G01X1791055Y975951D02*
X1791109D01*
G01X1791055Y989337D02*
X1791109D01*
G01X1791055Y1029495D02*
X1791109D01*
G01X1791019Y1019456D02*
X1791099D01*
G01X1790684Y1049573D02*
X1790767D01*
G01X1791055Y1042880D02*
X1791109D01*
G01X1791055Y1036188D02*
X1791109D01*
G01X1791730Y1059613D02*
X1790907D01*
G01X1791175Y1072999D02*
X1790990D01*
G01X1791069Y1066306D02*
X1790990D01*
G01X1791069Y1089731D02*
X1790990D01*
G01X1791109Y1083038D02*
X1791092D01*
G01X1791194Y1086385D02*
X1791092D01*
G01X1791175Y1096424D02*
X1790990D01*
G01X1791175Y1109810D02*
X1790990D01*
G01X1791069Y1103117D02*
X1790990D01*
G01X1791069Y1126542D02*
X1790990D01*
G01X1791109Y1119849D02*
X1791092D01*
G01X1791194Y1123196D02*
X1791092D01*
G01X1791069Y1139928D02*
X1790990D01*
G01X1791175Y1133235D02*
X1790990D01*
G01X1791175Y1146621D02*
X1790990D01*
G01X1791109Y1156660D02*
X1791092D01*
G01X1791194Y1160007D02*
X1791092D01*
G01X1791175Y1170046D02*
X1790990D01*
G01X1791069Y1163353D02*
X1790990D01*
G01X1791175Y1183432D02*
X1790990D01*
G01X1791069Y1176739D02*
X1790990D01*
G01X1791109Y1193471D02*
X1791092D01*
G01X1791175Y1206857D02*
X1790990D01*
G01X1791069Y1200164D02*
X1790990D01*
G01X1791194Y1196818D02*
X1791092D01*
G01X1791175Y1220243D02*
X1790990D01*
G01X1791069Y1213550D02*
X1790990D01*
G01X1791069Y1236975D02*
X1790990D01*
G01X1791092Y1230282D02*
X1791109D01*
G01X1791092Y1233629D02*
X1791194D01*
G01X1791175Y1243668D02*
X1790990D01*
G01X1805269Y771845D02*
X1805288D01*
G01X1805269Y778538D02*
X1805288D01*
G01Y785228D02*
X1805269D01*
G01X1805288Y781829D02*
X1805269D01*
G01Y801964D02*
X1805288D01*
G01X1805269Y795271D02*
X1805288D01*
G01X1805269Y815349D02*
X1805288D01*
G01X1805269Y808656D02*
X1805288D01*
G01X1805269Y818640D02*
X1805288D01*
G01X1805269Y832082D02*
X1805288D01*
G01X1805269Y822039D02*
X1805288D01*
G01X1805269Y852160D02*
X1805288D01*
G01X1805269Y845467D02*
X1805288D01*
G01X1805269Y838775D02*
X1805288D01*
G01X1805269Y868893D02*
X1805288D01*
G01Y858850D02*
X1805269D01*
G01X1805288Y855451D02*
X1805269D01*
G01Y875586D02*
X1805288D01*
G01X1805269Y882278D02*
X1805288D01*
G01X1805269Y888971D02*
X1805288D01*
G01Y895661D02*
X1805269D01*
G01X1805288Y892262D02*
X1805269D01*
G01Y912397D02*
X1805288D01*
G01X1805269Y905704D02*
X1805288D01*
G01X1805269Y925782D02*
X1805288D01*
G01X1805269Y919090D02*
X1805288D01*
G01Y932472D02*
X1805269D01*
G01X1805288Y929073D02*
X1805269D01*
G01Y949208D02*
X1805288D01*
G01X1805269Y942515D02*
X1805288D01*
G01X1805269Y979340D02*
X1805288D01*
G01X1805269Y972647D02*
X1805288D01*
G01X1805269Y992726D02*
X1805288D01*
G01X1805269Y986033D02*
X1805288D01*
G01X1805269Y1046269D02*
X1805288D01*
G01X1805269Y1039576D02*
X1805288D01*
G01X1805269Y1032883D02*
X1805288D01*
G01X1805269Y1073027D02*
X1805288D01*
G01X1805269Y1066334D02*
X1805288D01*
G01Y1079716D02*
X1805269D01*
G01X1805288Y1076317D02*
X1805269D01*
G01Y1096452D02*
X1805288D01*
G01X1805269Y1089759D02*
X1805288D01*
G01X1805269Y1109838D02*
X1805288D01*
G01X1805269Y1103145D02*
X1805288D01*
G01X1805269Y1126570D02*
X1805288D01*
G01Y1116527D02*
X1805269D01*
G01X1805288Y1113128D02*
X1805269D01*
G01Y1139956D02*
X1805288D01*
G01X1805269Y1133263D02*
X1805288D01*
G01X1805269Y1146649D02*
X1805288D01*
G01Y1153338D02*
X1805269D01*
G01Y1149940D02*
X1805288D01*
G01X1805269Y1176767D02*
X1805288D01*
G01X1805269Y1170074D02*
X1805288D01*
G01X1805269Y1163381D02*
X1805288D01*
G01X1805269Y1183460D02*
X1805288D01*
G01Y1190149D02*
X1805269D01*
G01Y1186751D02*
X1805288D01*
G01X1805269Y1206885D02*
X1805288D01*
G01X1805269Y1200192D02*
X1805288D01*
G01X1805269Y1220271D02*
X1805288D01*
G01X1805269Y1213578D02*
X1805288D01*
G01X1805269Y1226960D02*
X1805288D01*
G01X1805269Y1223562D02*
X1805288D01*
G01X1805269Y1243696D02*
X1805288D01*
G01X1805269Y1237003D02*
X1805288D01*
G54D31*
X48191Y766798D03*
Y770144D03*
X32049Y766798D03*
Y770144D03*
X48191Y773491D03*
Y776837D03*
Y780184D03*
Y783530D03*
Y786877D03*
X32049Y773491D03*
Y776837D03*
Y780184D03*
Y783530D03*
Y786877D03*
X48191Y790223D03*
Y793570D03*
Y796916D03*
Y800263D03*
Y803609D03*
X32049Y790223D03*
Y793570D03*
Y796916D03*
Y800263D03*
Y803609D03*
X48191Y806955D03*
Y810302D03*
Y813648D03*
Y816995D03*
Y820341D03*
X32049Y806955D03*
Y810302D03*
Y813648D03*
Y816995D03*
Y820341D03*
X48191Y823688D03*
Y827034D03*
Y830381D03*
Y833727D03*
X32049Y823688D03*
Y827034D03*
Y830381D03*
Y833727D03*
X48191Y837074D03*
Y840420D03*
Y843766D03*
Y847113D03*
Y850459D03*
X32049Y837074D03*
Y840420D03*
Y843766D03*
Y847113D03*
Y850459D03*
X48191Y853806D03*
Y857152D03*
Y860499D03*
Y863845D03*
Y867192D03*
X32049Y853806D03*
Y857152D03*
Y860499D03*
Y863845D03*
Y867192D03*
X48191Y870538D03*
Y873885D03*
Y877231D03*
Y880577D03*
Y883924D03*
X32049Y870538D03*
Y873885D03*
Y877231D03*
Y880577D03*
Y883924D03*
X48191Y887270D03*
Y890617D03*
Y893963D03*
Y897310D03*
Y900656D03*
X32049Y887270D03*
Y890617D03*
Y893963D03*
Y897310D03*
Y900656D03*
X48191Y904003D03*
Y907349D03*
Y910696D03*
Y914042D03*
Y917389D03*
X32049Y904003D03*
Y907349D03*
Y910696D03*
Y914042D03*
Y917389D03*
X48191Y920735D03*
Y924081D03*
Y927428D03*
Y930774D03*
Y934121D03*
X32049Y920735D03*
Y924081D03*
Y927428D03*
Y930774D03*
Y934121D03*
X48191Y937467D03*
Y940814D03*
Y944160D03*
Y947507D03*
X32049Y937467D03*
Y940814D03*
Y944160D03*
Y947507D03*
X48191Y950853D03*
Y954200D03*
Y957546D03*
Y960892D03*
Y964239D03*
X32049Y950853D03*
Y954200D03*
Y957546D03*
Y960892D03*
Y964239D03*
X48191Y967585D03*
Y970932D03*
Y974278D03*
Y977625D03*
Y980971D03*
X32049Y967585D03*
Y970932D03*
Y974278D03*
Y977625D03*
Y980971D03*
X48191Y984318D03*
Y987664D03*
Y991011D03*
Y994357D03*
X32049Y984318D03*
Y987664D03*
Y991011D03*
Y994357D03*
X48191Y1017782D03*
Y1021129D03*
Y1024475D03*
Y1027822D03*
Y1031168D03*
X32049Y1017782D03*
Y1021129D03*
Y1024475D03*
Y1027822D03*
Y1031168D03*
X48191Y1034515D03*
Y1037861D03*
Y1041207D03*
Y1044554D03*
Y1047900D03*
X32049Y1034515D03*
Y1037861D03*
Y1041207D03*
Y1044554D03*
Y1047900D03*
X48191Y1051247D03*
Y1054593D03*
Y1057940D03*
Y1061286D03*
X32049Y1051247D03*
Y1054593D03*
Y1057940D03*
Y1061286D03*
X48191Y1064633D03*
Y1067979D03*
Y1071326D03*
Y1074672D03*
Y1078018D03*
X32049Y1064633D03*
Y1067979D03*
Y1071326D03*
Y1074672D03*
Y1078018D03*
X48191Y1081365D03*
Y1084711D03*
Y1088058D03*
Y1091404D03*
Y1094751D03*
X32049Y1081365D03*
Y1084711D03*
Y1088058D03*
Y1091404D03*
Y1094751D03*
X48191Y1098097D03*
Y1101444D03*
Y1104790D03*
Y1108137D03*
Y1111483D03*
X32049Y1098097D03*
Y1101444D03*
Y1104790D03*
Y1108137D03*
Y1111483D03*
X48191Y1114829D03*
Y1118176D03*
Y1121522D03*
Y1124869D03*
Y1128215D03*
X32049Y1114829D03*
Y1118176D03*
Y1121522D03*
Y1124869D03*
Y1128215D03*
X48191Y1131562D03*
Y1134908D03*
Y1138255D03*
Y1141601D03*
Y1144948D03*
X32049Y1131562D03*
Y1134908D03*
Y1138255D03*
Y1141601D03*
Y1144948D03*
X48191Y1148294D03*
Y1151641D03*
Y1154987D03*
Y1158333D03*
Y1161680D03*
X32049Y1148294D03*
Y1151641D03*
Y1154987D03*
Y1158333D03*
Y1161680D03*
X48191Y1165026D03*
Y1168373D03*
Y1171719D03*
Y1175066D03*
X32049Y1165026D03*
Y1168373D03*
Y1171719D03*
Y1175066D03*
X48191Y1178412D03*
Y1181759D03*
Y1185105D03*
Y1188452D03*
Y1191798D03*
X32049Y1178412D03*
Y1181759D03*
Y1185105D03*
Y1188452D03*
Y1191798D03*
X48191Y1195144D03*
Y1198491D03*
Y1201837D03*
Y1205184D03*
Y1208530D03*
X32049Y1195144D03*
Y1198491D03*
Y1201837D03*
Y1205184D03*
Y1208530D03*
X48191Y1211877D03*
Y1215223D03*
Y1218570D03*
Y1221916D03*
Y1225263D03*
X32049Y1211877D03*
Y1215223D03*
Y1218570D03*
Y1221916D03*
Y1225263D03*
X48191Y1228609D03*
Y1231955D03*
Y1235302D03*
Y1238648D03*
Y1241995D03*
X32049Y1228609D03*
Y1231955D03*
Y1235302D03*
Y1238648D03*
Y1241995D03*
X48191Y1245341D03*
Y1248688D03*
Y1252034D03*
Y1255381D03*
Y1258727D03*
X32049Y1245341D03*
Y1248688D03*
Y1252034D03*
Y1255381D03*
Y1258727D03*
X48191Y1262074D03*
Y1265420D03*
X32049Y1262074D03*
Y1265420D03*
X61749Y766798D03*
Y770144D03*
Y773491D03*
Y776837D03*
Y780184D03*
Y783530D03*
Y786877D03*
Y790223D03*
Y793570D03*
Y796916D03*
Y800263D03*
Y803609D03*
Y806955D03*
Y810302D03*
Y813648D03*
Y816995D03*
Y820341D03*
Y823688D03*
Y827034D03*
Y830381D03*
Y833727D03*
Y837074D03*
Y840420D03*
Y843766D03*
Y847113D03*
Y850459D03*
Y853806D03*
Y857152D03*
Y860499D03*
Y863845D03*
Y867192D03*
Y870538D03*
Y873885D03*
Y877231D03*
Y880577D03*
Y883924D03*
Y887270D03*
Y890617D03*
Y893963D03*
Y897310D03*
Y900656D03*
Y904003D03*
Y907349D03*
Y910696D03*
Y914042D03*
Y917389D03*
Y920735D03*
Y924081D03*
Y927428D03*
Y930774D03*
Y934121D03*
Y937467D03*
Y940814D03*
Y944160D03*
Y947507D03*
Y950853D03*
Y954200D03*
Y957546D03*
Y960892D03*
Y964239D03*
Y967585D03*
Y970932D03*
Y974278D03*
Y977625D03*
Y980971D03*
Y984318D03*
Y987664D03*
Y991011D03*
Y994357D03*
Y1017782D03*
Y1021129D03*
Y1024475D03*
Y1027822D03*
Y1031168D03*
Y1034515D03*
Y1037861D03*
Y1041207D03*
Y1044554D03*
Y1047900D03*
Y1051247D03*
Y1054593D03*
Y1057940D03*
Y1061286D03*
Y1064633D03*
Y1067979D03*
Y1071326D03*
Y1074672D03*
Y1078018D03*
Y1081365D03*
Y1084711D03*
Y1088058D03*
Y1091404D03*
Y1094751D03*
Y1098097D03*
Y1101444D03*
Y1104790D03*
Y1108137D03*
Y1111483D03*
Y1114829D03*
Y1118176D03*
Y1121522D03*
Y1124869D03*
Y1128215D03*
Y1131562D03*
Y1134908D03*
Y1138255D03*
Y1141601D03*
Y1144948D03*
Y1148294D03*
Y1151641D03*
Y1154987D03*
Y1158333D03*
Y1161680D03*
Y1165026D03*
Y1168373D03*
Y1171719D03*
Y1175066D03*
Y1178412D03*
Y1181759D03*
Y1185105D03*
Y1188452D03*
Y1191798D03*
Y1195144D03*
Y1198491D03*
Y1201837D03*
Y1205184D03*
Y1208530D03*
Y1211877D03*
Y1215223D03*
Y1218570D03*
Y1221916D03*
Y1225263D03*
Y1228609D03*
Y1231955D03*
Y1235302D03*
Y1238648D03*
Y1241995D03*
Y1245341D03*
Y1248688D03*
Y1252034D03*
Y1255381D03*
Y1258727D03*
Y1262074D03*
Y1265420D03*
X77891Y766798D03*
Y770144D03*
Y773491D03*
Y776837D03*
Y780184D03*
Y783530D03*
Y786877D03*
Y790223D03*
Y793570D03*
Y796916D03*
Y800263D03*
Y803609D03*
Y806955D03*
Y810302D03*
Y813648D03*
Y816995D03*
Y820341D03*
Y823688D03*
Y827034D03*
Y830381D03*
Y833727D03*
Y837074D03*
Y840420D03*
Y843766D03*
Y847113D03*
Y850459D03*
Y853806D03*
Y857152D03*
Y860499D03*
Y863845D03*
Y867192D03*
Y870538D03*
Y873885D03*
Y877231D03*
Y880577D03*
Y883924D03*
Y887270D03*
Y890617D03*
Y893963D03*
Y897310D03*
Y900656D03*
Y904003D03*
Y907349D03*
Y910696D03*
Y914042D03*
Y917389D03*
Y920735D03*
Y924081D03*
Y927428D03*
Y930774D03*
Y934121D03*
Y937467D03*
Y940814D03*
Y944160D03*
Y947507D03*
Y950853D03*
Y954200D03*
Y957546D03*
Y960892D03*
Y964239D03*
Y967585D03*
Y970932D03*
Y974278D03*
Y977625D03*
Y980971D03*
Y984318D03*
Y987664D03*
Y991011D03*
Y994357D03*
Y1017782D03*
Y1021129D03*
Y1024475D03*
Y1027822D03*
Y1031168D03*
Y1034515D03*
Y1037861D03*
Y1041207D03*
Y1044554D03*
Y1047900D03*
Y1051247D03*
Y1054593D03*
Y1057940D03*
Y1061286D03*
Y1064633D03*
Y1067979D03*
Y1071326D03*
Y1074672D03*
Y1078018D03*
Y1081365D03*
Y1084711D03*
Y1088058D03*
Y1091404D03*
Y1094751D03*
Y1098097D03*
Y1101444D03*
Y1104790D03*
Y1108137D03*
Y1111483D03*
Y1114829D03*
Y1118176D03*
Y1121522D03*
Y1124869D03*
Y1128215D03*
Y1131562D03*
Y1134908D03*
Y1138255D03*
Y1141601D03*
Y1144948D03*
Y1148294D03*
Y1151641D03*
Y1154987D03*
Y1158333D03*
Y1161680D03*
Y1165026D03*
Y1168373D03*
Y1171719D03*
Y1175066D03*
Y1178412D03*
Y1181759D03*
Y1185105D03*
Y1188452D03*
Y1191798D03*
Y1195144D03*
Y1198491D03*
Y1201837D03*
Y1205184D03*
Y1208530D03*
Y1211877D03*
Y1215223D03*
Y1218570D03*
Y1221916D03*
Y1225263D03*
Y1228609D03*
Y1231955D03*
Y1235302D03*
Y1238648D03*
Y1241995D03*
Y1245341D03*
Y1248688D03*
Y1252034D03*
Y1255381D03*
Y1258727D03*
Y1262074D03*
Y1265420D03*
X91449Y766798D03*
Y770144D03*
Y773491D03*
Y776837D03*
Y780184D03*
Y783530D03*
Y786877D03*
Y790223D03*
Y793570D03*
Y796916D03*
Y800263D03*
Y803609D03*
Y806955D03*
Y810302D03*
Y813648D03*
Y816995D03*
Y820341D03*
Y823688D03*
Y827034D03*
Y830381D03*
Y833727D03*
Y837074D03*
Y840420D03*
Y843766D03*
Y847113D03*
Y850459D03*
Y853806D03*
Y857152D03*
Y860499D03*
Y863845D03*
Y867192D03*
Y870538D03*
Y873885D03*
Y877231D03*
Y880577D03*
Y883924D03*
Y887270D03*
Y890617D03*
Y893963D03*
Y897310D03*
Y900656D03*
Y904003D03*
Y907349D03*
Y910696D03*
Y914042D03*
Y917389D03*
Y920735D03*
Y924081D03*
Y927428D03*
Y930774D03*
Y934121D03*
Y937467D03*
Y940814D03*
Y944160D03*
Y947507D03*
Y950853D03*
Y954200D03*
Y957546D03*
Y960892D03*
Y964239D03*
Y967585D03*
Y970932D03*
Y974278D03*
Y977625D03*
Y980971D03*
Y984318D03*
Y987664D03*
Y991011D03*
Y994357D03*
Y1017782D03*
Y1021129D03*
Y1024475D03*
Y1027822D03*
Y1031168D03*
Y1034515D03*
Y1037861D03*
Y1041207D03*
Y1044554D03*
Y1047900D03*
Y1051247D03*
Y1054593D03*
Y1057940D03*
Y1061286D03*
Y1064633D03*
Y1067979D03*
Y1071326D03*
Y1074672D03*
Y1078018D03*
Y1081365D03*
Y1084711D03*
Y1088058D03*
Y1091404D03*
Y1094751D03*
Y1098097D03*
Y1101444D03*
Y1104790D03*
Y1108137D03*
Y1111483D03*
Y1114829D03*
Y1118176D03*
Y1121522D03*
Y1124869D03*
Y1128215D03*
Y1131562D03*
Y1134908D03*
Y1138255D03*
Y1141601D03*
Y1144948D03*
Y1148294D03*
Y1151641D03*
Y1154987D03*
Y1158333D03*
Y1161680D03*
Y1165026D03*
Y1168373D03*
Y1171719D03*
Y1175066D03*
Y1178412D03*
Y1181759D03*
Y1185105D03*
Y1188452D03*
Y1191798D03*
Y1195144D03*
Y1198491D03*
Y1201837D03*
Y1205184D03*
Y1208530D03*
Y1211877D03*
Y1215223D03*
Y1218570D03*
Y1221916D03*
Y1225263D03*
Y1228609D03*
Y1231955D03*
Y1235302D03*
Y1238648D03*
Y1241995D03*
Y1245341D03*
Y1248688D03*
Y1252034D03*
Y1255381D03*
Y1258727D03*
Y1262074D03*
Y1265420D03*
X107591Y766798D03*
Y770144D03*
Y773491D03*
Y776837D03*
Y780184D03*
Y783530D03*
Y786877D03*
Y790223D03*
Y793570D03*
Y796916D03*
Y800263D03*
Y803609D03*
Y806955D03*
Y810302D03*
Y813648D03*
Y816995D03*
Y820341D03*
Y823688D03*
Y827034D03*
Y830381D03*
Y833727D03*
Y837074D03*
Y840420D03*
Y843766D03*
Y847113D03*
Y850459D03*
Y853806D03*
Y857152D03*
Y860499D03*
Y863845D03*
Y867192D03*
Y870538D03*
Y873885D03*
Y877231D03*
Y880577D03*
Y883924D03*
Y887270D03*
Y890617D03*
Y893963D03*
Y897310D03*
Y900656D03*
Y904003D03*
Y907349D03*
Y910696D03*
Y914042D03*
Y917389D03*
Y920735D03*
Y924081D03*
Y927428D03*
Y930774D03*
Y934121D03*
Y937467D03*
Y940814D03*
Y944160D03*
Y947507D03*
Y950853D03*
Y954200D03*
Y957546D03*
Y960892D03*
Y964239D03*
Y967585D03*
Y970932D03*
Y974278D03*
Y977625D03*
Y980971D03*
Y984318D03*
Y987664D03*
Y991011D03*
Y994357D03*
Y1017782D03*
Y1021129D03*
Y1024475D03*
Y1027822D03*
Y1031168D03*
Y1034515D03*
Y1037861D03*
Y1041207D03*
Y1044554D03*
Y1047900D03*
Y1051247D03*
Y1054593D03*
Y1057940D03*
Y1061286D03*
Y1064633D03*
Y1067979D03*
Y1071326D03*
Y1074672D03*
Y1078018D03*
Y1081365D03*
Y1084711D03*
Y1088058D03*
Y1091404D03*
Y1094751D03*
Y1098097D03*
Y1101444D03*
Y1104790D03*
Y1108137D03*
Y1111483D03*
Y1114829D03*
Y1118176D03*
Y1121522D03*
Y1124869D03*
Y1128215D03*
Y1131562D03*
Y1134908D03*
Y1138255D03*
Y1141601D03*
Y1144948D03*
Y1148294D03*
Y1151641D03*
Y1154987D03*
Y1158333D03*
Y1161680D03*
Y1165026D03*
Y1168373D03*
Y1171719D03*
Y1175066D03*
Y1178412D03*
Y1181759D03*
Y1185105D03*
Y1188452D03*
Y1191798D03*
Y1195144D03*
Y1198491D03*
Y1201837D03*
Y1205184D03*
Y1208530D03*
Y1211877D03*
Y1215223D03*
Y1218570D03*
Y1221916D03*
Y1225263D03*
Y1228609D03*
Y1231955D03*
Y1235302D03*
Y1238648D03*
Y1241995D03*
Y1245341D03*
Y1248688D03*
Y1252034D03*
Y1255381D03*
Y1258727D03*
Y1262074D03*
Y1265420D03*
X121149Y766798D03*
Y770144D03*
Y773491D03*
Y776837D03*
Y780184D03*
Y783530D03*
Y786877D03*
Y790223D03*
Y793570D03*
Y796916D03*
Y800263D03*
Y803609D03*
Y806955D03*
Y810302D03*
Y813648D03*
Y816995D03*
Y820341D03*
Y823688D03*
Y827034D03*
Y830381D03*
Y833727D03*
Y837074D03*
Y840420D03*
Y843766D03*
Y847113D03*
Y850459D03*
Y853806D03*
Y857152D03*
Y860499D03*
Y863845D03*
Y867192D03*
Y870538D03*
Y873885D03*
Y877231D03*
Y880577D03*
Y883924D03*
Y887270D03*
Y890617D03*
Y893963D03*
Y897310D03*
Y900656D03*
Y904003D03*
Y907349D03*
Y910696D03*
Y914042D03*
Y917389D03*
Y920735D03*
Y924081D03*
Y927428D03*
Y930774D03*
Y934121D03*
Y937467D03*
Y940814D03*
Y944160D03*
Y947507D03*
Y950853D03*
Y954200D03*
Y957546D03*
Y960892D03*
Y964239D03*
Y967585D03*
Y970932D03*
Y974278D03*
Y977625D03*
Y980971D03*
Y984318D03*
Y987664D03*
Y991011D03*
Y994357D03*
Y1017782D03*
Y1021129D03*
Y1024475D03*
Y1027822D03*
Y1031168D03*
Y1034515D03*
Y1037861D03*
Y1041207D03*
Y1044554D03*
Y1047900D03*
Y1051247D03*
Y1054593D03*
Y1057940D03*
Y1061286D03*
Y1064633D03*
Y1067979D03*
Y1071326D03*
Y1074672D03*
Y1078018D03*
Y1081365D03*
Y1084711D03*
Y1088058D03*
Y1091404D03*
Y1094751D03*
Y1098097D03*
Y1101444D03*
Y1104790D03*
Y1108137D03*
Y1111483D03*
Y1114829D03*
Y1118176D03*
Y1121522D03*
Y1124869D03*
Y1128215D03*
Y1131562D03*
Y1134908D03*
Y1138255D03*
Y1141601D03*
Y1144948D03*
Y1148294D03*
Y1151641D03*
Y1154987D03*
Y1158333D03*
Y1161680D03*
Y1165026D03*
Y1168373D03*
Y1171719D03*
Y1175066D03*
Y1178412D03*
Y1181759D03*
Y1185105D03*
Y1188452D03*
Y1191798D03*
Y1195144D03*
Y1198491D03*
Y1201837D03*
Y1205184D03*
Y1208530D03*
Y1211877D03*
Y1215223D03*
Y1218570D03*
Y1221916D03*
Y1225263D03*
Y1228609D03*
Y1231955D03*
Y1235302D03*
Y1238648D03*
Y1241995D03*
Y1245341D03*
Y1248688D03*
Y1252034D03*
Y1255381D03*
Y1258727D03*
Y1262074D03*
Y1265420D03*
X137291Y766798D03*
Y770144D03*
Y773491D03*
Y776837D03*
Y780184D03*
Y783530D03*
Y786877D03*
Y790223D03*
Y793570D03*
Y796916D03*
Y800263D03*
Y803609D03*
Y806955D03*
Y810302D03*
Y813648D03*
Y816995D03*
Y820341D03*
Y823688D03*
Y827034D03*
Y830381D03*
Y833727D03*
Y837074D03*
Y840420D03*
Y843766D03*
Y847113D03*
Y850459D03*
Y853806D03*
Y857152D03*
Y860499D03*
Y863845D03*
Y867192D03*
Y870538D03*
Y873885D03*
Y877231D03*
Y880577D03*
Y883924D03*
Y887270D03*
Y890617D03*
Y893963D03*
Y897310D03*
Y900656D03*
Y904003D03*
Y907349D03*
Y910696D03*
Y914042D03*
Y917389D03*
Y920735D03*
Y924081D03*
Y927428D03*
Y930774D03*
Y934121D03*
Y937467D03*
Y940814D03*
Y944160D03*
Y947507D03*
Y950853D03*
Y954200D03*
Y957546D03*
Y960892D03*
Y964239D03*
Y967585D03*
Y970932D03*
Y974278D03*
Y977625D03*
Y980971D03*
Y984318D03*
Y987664D03*
Y991011D03*
Y994357D03*
Y1017782D03*
Y1021129D03*
Y1024475D03*
Y1027822D03*
Y1031168D03*
Y1034515D03*
Y1037861D03*
Y1041207D03*
Y1044554D03*
Y1047900D03*
Y1051247D03*
Y1054593D03*
Y1057940D03*
Y1061286D03*
Y1064633D03*
Y1067979D03*
Y1071326D03*
Y1074672D03*
Y1078018D03*
Y1081365D03*
Y1084711D03*
Y1088058D03*
Y1091404D03*
Y1094751D03*
Y1098097D03*
Y1101444D03*
Y1104790D03*
Y1108137D03*
Y1111483D03*
Y1114829D03*
Y1118176D03*
Y1121522D03*
Y1124869D03*
Y1128215D03*
Y1131562D03*
Y1134908D03*
Y1138255D03*
Y1141601D03*
Y1144948D03*
Y1148294D03*
Y1151641D03*
Y1154987D03*
Y1158333D03*
Y1161680D03*
Y1165026D03*
Y1168373D03*
Y1171719D03*
Y1175066D03*
Y1178412D03*
Y1181759D03*
Y1185105D03*
Y1188452D03*
Y1191798D03*
Y1195144D03*
Y1198491D03*
Y1201837D03*
Y1205184D03*
Y1208530D03*
Y1211877D03*
Y1215223D03*
Y1218570D03*
Y1221916D03*
Y1225263D03*
Y1228609D03*
Y1231955D03*
Y1235302D03*
Y1238648D03*
Y1241995D03*
Y1245341D03*
Y1248688D03*
Y1252034D03*
Y1255381D03*
Y1258727D03*
Y1262074D03*
Y1265420D03*
X150849Y766798D03*
Y770144D03*
Y773491D03*
Y776837D03*
Y780184D03*
Y783530D03*
Y786877D03*
Y790223D03*
Y793570D03*
Y796916D03*
Y800263D03*
Y803609D03*
Y806955D03*
Y810302D03*
Y813648D03*
Y816995D03*
Y820341D03*
Y823688D03*
Y827034D03*
Y830381D03*
Y833727D03*
Y837074D03*
Y840420D03*
Y843766D03*
Y847113D03*
Y850459D03*
Y853806D03*
Y857152D03*
Y860499D03*
Y863845D03*
Y867192D03*
Y870538D03*
Y873885D03*
Y877231D03*
Y880577D03*
Y883924D03*
Y887270D03*
Y890617D03*
Y893963D03*
Y897310D03*
Y900656D03*
Y904003D03*
Y907349D03*
Y910696D03*
Y914042D03*
Y917389D03*
Y920735D03*
Y924081D03*
Y927428D03*
Y930774D03*
Y934121D03*
Y937467D03*
Y940814D03*
Y944160D03*
Y947507D03*
Y950853D03*
Y954200D03*
Y957546D03*
Y960892D03*
Y964239D03*
Y967585D03*
Y970932D03*
Y974278D03*
Y977625D03*
Y980971D03*
Y984318D03*
Y987664D03*
Y991011D03*
Y994357D03*
Y1017782D03*
Y1021129D03*
Y1024475D03*
Y1027822D03*
Y1031168D03*
Y1034515D03*
Y1037861D03*
Y1041207D03*
Y1044554D03*
Y1047900D03*
Y1051247D03*
Y1054593D03*
Y1057940D03*
Y1061286D03*
Y1064633D03*
Y1067979D03*
Y1071326D03*
Y1074672D03*
Y1078018D03*
Y1081365D03*
Y1084711D03*
Y1088058D03*
Y1091404D03*
Y1094751D03*
Y1098097D03*
Y1101444D03*
Y1104790D03*
Y1108137D03*
Y1111483D03*
Y1114829D03*
Y1118176D03*
Y1121522D03*
Y1124869D03*
Y1128215D03*
Y1131562D03*
Y1134908D03*
Y1138255D03*
Y1141601D03*
Y1144948D03*
Y1148294D03*
Y1151641D03*
Y1154987D03*
Y1158333D03*
Y1161680D03*
Y1165026D03*
Y1168373D03*
Y1171719D03*
Y1175066D03*
Y1178412D03*
Y1181759D03*
Y1185105D03*
Y1188452D03*
Y1191798D03*
Y1195144D03*
Y1198491D03*
Y1201837D03*
Y1205184D03*
Y1208530D03*
Y1211877D03*
Y1215223D03*
Y1218570D03*
Y1221916D03*
Y1225263D03*
Y1228609D03*
Y1231955D03*
Y1235302D03*
Y1238648D03*
Y1241995D03*
Y1245341D03*
Y1248688D03*
Y1252034D03*
Y1255381D03*
Y1258727D03*
Y1262074D03*
Y1265420D03*
X166991Y766798D03*
Y770144D03*
Y773491D03*
Y776837D03*
Y780184D03*
Y783530D03*
Y786877D03*
Y790223D03*
Y793570D03*
Y796916D03*
Y800263D03*
Y803609D03*
Y806955D03*
Y810302D03*
Y813648D03*
Y816995D03*
Y820341D03*
Y823688D03*
Y827034D03*
Y830381D03*
Y833727D03*
Y837074D03*
Y840420D03*
Y843766D03*
Y847113D03*
Y850459D03*
Y853806D03*
Y857152D03*
Y860499D03*
Y863845D03*
Y867192D03*
Y870538D03*
Y873885D03*
Y877231D03*
Y880577D03*
Y883924D03*
Y887270D03*
Y890617D03*
Y893963D03*
Y897310D03*
Y900656D03*
Y904003D03*
Y907349D03*
Y910696D03*
Y914042D03*
Y917389D03*
Y920735D03*
Y924081D03*
Y927428D03*
Y930774D03*
Y934121D03*
Y937467D03*
Y940814D03*
Y944160D03*
Y947507D03*
Y950853D03*
Y954200D03*
Y957546D03*
Y960892D03*
Y964239D03*
Y967585D03*
Y970932D03*
Y974278D03*
Y977625D03*
Y980971D03*
Y984318D03*
Y987664D03*
Y991011D03*
Y994357D03*
Y1017782D03*
Y1021129D03*
Y1024475D03*
Y1027822D03*
Y1031168D03*
Y1034515D03*
Y1037861D03*
Y1041207D03*
Y1044554D03*
Y1047900D03*
Y1051247D03*
Y1054593D03*
Y1057940D03*
Y1061286D03*
Y1064633D03*
Y1067979D03*
Y1071326D03*
Y1074672D03*
Y1078018D03*
Y1081365D03*
Y1084711D03*
Y1088058D03*
Y1091404D03*
Y1094751D03*
Y1098097D03*
Y1101444D03*
Y1104790D03*
Y1108137D03*
Y1111483D03*
Y1114829D03*
Y1118176D03*
Y1121522D03*
Y1124869D03*
Y1128215D03*
Y1131562D03*
Y1134908D03*
Y1138255D03*
Y1141601D03*
Y1144948D03*
Y1148294D03*
Y1151641D03*
Y1154987D03*
Y1158333D03*
Y1161680D03*
Y1165026D03*
Y1168373D03*
Y1171719D03*
Y1175066D03*
Y1178412D03*
Y1181759D03*
Y1185105D03*
Y1188452D03*
Y1191798D03*
Y1195144D03*
Y1198491D03*
Y1201837D03*
Y1205184D03*
Y1208530D03*
Y1211877D03*
Y1215223D03*
Y1218570D03*
Y1221916D03*
Y1225263D03*
Y1228609D03*
Y1231955D03*
Y1235302D03*
Y1238648D03*
Y1241995D03*
Y1245341D03*
Y1248688D03*
Y1252034D03*
Y1255381D03*
Y1258727D03*
Y1262074D03*
Y1265420D03*
X180549Y766798D03*
Y770144D03*
Y773491D03*
Y776837D03*
Y780184D03*
Y783530D03*
Y786877D03*
Y790223D03*
Y793570D03*
Y796916D03*
Y800263D03*
Y803609D03*
Y806955D03*
Y810302D03*
Y813648D03*
Y816995D03*
Y820341D03*
Y823688D03*
Y827034D03*
Y830381D03*
Y833727D03*
Y837074D03*
Y840420D03*
Y843766D03*
Y847113D03*
Y850459D03*
Y853806D03*
Y857152D03*
Y860499D03*
Y863845D03*
Y867192D03*
Y870538D03*
Y873885D03*
Y877231D03*
Y880577D03*
Y883924D03*
Y887270D03*
Y890617D03*
Y893963D03*
Y897310D03*
Y900656D03*
Y904003D03*
Y907349D03*
Y910696D03*
Y914042D03*
Y917389D03*
Y920735D03*
Y924081D03*
Y927428D03*
Y930774D03*
Y934121D03*
Y937467D03*
Y940814D03*
Y944160D03*
Y947507D03*
Y950853D03*
Y954200D03*
Y957546D03*
Y960892D03*
Y964239D03*
Y967585D03*
Y970932D03*
Y974278D03*
Y977625D03*
Y980971D03*
Y984318D03*
Y987664D03*
Y991011D03*
Y994357D03*
Y1017782D03*
Y1021129D03*
Y1024475D03*
Y1027822D03*
Y1031168D03*
Y1034515D03*
Y1037861D03*
Y1041207D03*
Y1044554D03*
Y1047900D03*
Y1051247D03*
Y1054593D03*
Y1057940D03*
Y1061286D03*
Y1064633D03*
Y1067979D03*
Y1071326D03*
Y1074672D03*
Y1078018D03*
Y1081365D03*
Y1084711D03*
Y1088058D03*
Y1091404D03*
Y1094751D03*
Y1098097D03*
Y1101444D03*
Y1104790D03*
Y1108137D03*
Y1111483D03*
Y1114829D03*
Y1118176D03*
Y1121522D03*
Y1124869D03*
Y1128215D03*
Y1131562D03*
Y1134908D03*
Y1138255D03*
Y1141601D03*
Y1144948D03*
Y1148294D03*
Y1151641D03*
Y1154987D03*
Y1158333D03*
Y1161680D03*
Y1165026D03*
Y1168373D03*
Y1171719D03*
Y1175066D03*
Y1178412D03*
Y1181759D03*
Y1185105D03*
Y1188452D03*
Y1191798D03*
Y1195144D03*
Y1198491D03*
Y1201837D03*
Y1205184D03*
Y1208530D03*
Y1211877D03*
Y1215223D03*
Y1218570D03*
Y1221916D03*
Y1225263D03*
Y1228609D03*
Y1231955D03*
Y1235302D03*
Y1238648D03*
Y1241995D03*
Y1245341D03*
Y1248688D03*
Y1252034D03*
Y1255381D03*
Y1258727D03*
Y1262074D03*
Y1265420D03*
X210249Y766798D03*
Y770144D03*
X196691Y766798D03*
Y770144D03*
X210249Y773491D03*
Y776837D03*
Y780184D03*
Y783530D03*
Y786877D03*
X196691Y773491D03*
Y776837D03*
Y780184D03*
Y783530D03*
Y786877D03*
X210249Y790223D03*
Y793570D03*
Y796916D03*
Y800263D03*
Y803609D03*
X196691Y790223D03*
Y793570D03*
Y796916D03*
Y800263D03*
Y803609D03*
X210249Y806955D03*
Y810302D03*
Y813648D03*
Y816995D03*
Y820341D03*
X196691Y806955D03*
Y810302D03*
Y813648D03*
Y816995D03*
Y820341D03*
X210249Y823688D03*
Y827034D03*
Y830381D03*
Y833727D03*
X196691Y823688D03*
Y827034D03*
Y830381D03*
Y833727D03*
X210249Y837074D03*
Y840420D03*
Y843766D03*
Y847113D03*
Y850459D03*
X196691Y837074D03*
Y840420D03*
Y843766D03*
Y847113D03*
Y850459D03*
X210249Y853806D03*
Y857152D03*
Y860499D03*
Y863845D03*
Y867192D03*
X196691Y853806D03*
Y857152D03*
Y860499D03*
Y863845D03*
Y867192D03*
X210249Y870538D03*
Y873885D03*
Y877231D03*
Y880577D03*
Y883924D03*
X196691Y870538D03*
Y873885D03*
Y877231D03*
Y880577D03*
Y883924D03*
X210249Y887270D03*
Y890617D03*
Y893963D03*
Y897310D03*
Y900656D03*
X196691Y887270D03*
Y890617D03*
Y893963D03*
Y897310D03*
Y900656D03*
X210249Y904003D03*
Y907349D03*
Y910696D03*
Y914042D03*
Y917389D03*
X196691Y904003D03*
Y907349D03*
Y910696D03*
Y914042D03*
Y917389D03*
X210249Y920735D03*
Y924081D03*
Y927428D03*
Y930774D03*
Y934121D03*
X196691Y920735D03*
Y924081D03*
Y927428D03*
Y930774D03*
Y934121D03*
X210249Y937467D03*
Y940814D03*
Y944160D03*
Y947507D03*
X196691Y937467D03*
Y940814D03*
Y944160D03*
Y947507D03*
X210249Y950853D03*
Y954200D03*
Y957546D03*
Y960892D03*
Y964239D03*
X196691Y950853D03*
Y954200D03*
Y957546D03*
Y960892D03*
Y964239D03*
X210249Y967585D03*
Y970932D03*
Y974278D03*
Y977625D03*
Y980971D03*
X196691Y967585D03*
Y970932D03*
Y974278D03*
Y977625D03*
Y980971D03*
X210249Y984318D03*
Y987664D03*
Y991011D03*
Y994357D03*
X196691Y984318D03*
Y987664D03*
Y991011D03*
Y994357D03*
X210249Y1017782D03*
Y1021129D03*
Y1024475D03*
Y1027822D03*
Y1031168D03*
X196691Y1017782D03*
Y1021129D03*
Y1024475D03*
Y1027822D03*
Y1031168D03*
X210249Y1034515D03*
Y1037861D03*
Y1041207D03*
Y1044554D03*
Y1047900D03*
X196691Y1034515D03*
Y1037861D03*
Y1041207D03*
Y1044554D03*
Y1047900D03*
X210249Y1051247D03*
Y1054593D03*
Y1057940D03*
Y1061286D03*
X196691Y1051247D03*
Y1054593D03*
Y1057940D03*
Y1061286D03*
X210249Y1064633D03*
Y1067979D03*
Y1071326D03*
Y1074672D03*
Y1078018D03*
X196691Y1064633D03*
Y1067979D03*
Y1071326D03*
Y1074672D03*
Y1078018D03*
X210249Y1081365D03*
Y1084711D03*
Y1088058D03*
Y1091404D03*
Y1094751D03*
X196691Y1081365D03*
Y1084711D03*
Y1088058D03*
Y1091404D03*
Y1094751D03*
X210249Y1098097D03*
Y1101444D03*
Y1104790D03*
Y1108137D03*
Y1111483D03*
X196691Y1098097D03*
Y1101444D03*
Y1104790D03*
Y1108137D03*
Y1111483D03*
X210249Y1114829D03*
Y1118176D03*
Y1121522D03*
Y1124869D03*
Y1128215D03*
X196691Y1114829D03*
Y1118176D03*
Y1121522D03*
Y1124869D03*
Y1128215D03*
X210249Y1131562D03*
Y1134908D03*
Y1138255D03*
Y1141601D03*
Y1144948D03*
X196691Y1131562D03*
Y1134908D03*
Y1138255D03*
Y1141601D03*
Y1144948D03*
X210249Y1148294D03*
Y1151641D03*
Y1154987D03*
Y1158333D03*
Y1161680D03*
X196691Y1148294D03*
Y1151641D03*
Y1154987D03*
Y1158333D03*
Y1161680D03*
X210249Y1165026D03*
Y1168373D03*
Y1171719D03*
Y1175066D03*
X196691Y1165026D03*
Y1168373D03*
Y1171719D03*
Y1175066D03*
X210249Y1178412D03*
Y1181759D03*
Y1185105D03*
Y1188452D03*
Y1191798D03*
X196691Y1178412D03*
Y1181759D03*
Y1185105D03*
Y1188452D03*
Y1191798D03*
X210249Y1195144D03*
Y1198491D03*
Y1201837D03*
Y1205184D03*
Y1208530D03*
X196691Y1195144D03*
Y1198491D03*
Y1201837D03*
Y1205184D03*
Y1208530D03*
X210249Y1211877D03*
Y1215223D03*
Y1218570D03*
Y1221916D03*
Y1225263D03*
X196691Y1211877D03*
Y1215223D03*
Y1218570D03*
Y1221916D03*
Y1225263D03*
X210249Y1228609D03*
Y1231955D03*
Y1235302D03*
Y1238648D03*
Y1241995D03*
X196691Y1228609D03*
Y1231955D03*
Y1235302D03*
Y1238648D03*
Y1241995D03*
X210249Y1245341D03*
Y1248688D03*
Y1252034D03*
Y1255381D03*
Y1258727D03*
X196691Y1245341D03*
Y1248688D03*
Y1252034D03*
Y1255381D03*
Y1258727D03*
X210249Y1262074D03*
Y1265420D03*
X196691Y1262074D03*
Y1265420D03*
X226391Y766798D03*
Y770144D03*
Y773491D03*
Y776837D03*
Y780184D03*
Y783530D03*
Y786877D03*
Y790223D03*
Y793570D03*
Y796916D03*
Y800263D03*
Y803609D03*
Y806955D03*
Y810302D03*
Y813648D03*
Y816995D03*
Y820341D03*
Y823688D03*
Y827034D03*
Y830381D03*
Y833727D03*
Y837074D03*
Y840420D03*
Y843766D03*
Y847113D03*
Y850459D03*
Y853806D03*
Y857152D03*
Y860499D03*
Y863845D03*
Y867192D03*
Y870538D03*
Y873885D03*
Y877231D03*
Y880577D03*
Y883924D03*
Y887270D03*
Y890617D03*
Y893963D03*
Y897310D03*
Y900656D03*
Y904003D03*
Y907349D03*
Y910696D03*
Y914042D03*
Y917389D03*
Y920735D03*
Y924081D03*
Y927428D03*
Y930774D03*
Y934121D03*
Y937467D03*
Y940814D03*
Y944160D03*
Y947507D03*
Y950853D03*
Y954200D03*
Y957546D03*
Y960892D03*
Y964239D03*
Y967585D03*
Y970932D03*
Y974278D03*
Y977625D03*
Y980971D03*
Y984318D03*
Y987664D03*
Y991011D03*
Y994357D03*
Y1017782D03*
Y1021129D03*
Y1024475D03*
Y1027822D03*
Y1031168D03*
Y1034515D03*
Y1037861D03*
Y1041207D03*
Y1044554D03*
Y1047900D03*
Y1051247D03*
Y1054593D03*
Y1057940D03*
Y1061286D03*
Y1064633D03*
Y1067979D03*
Y1071326D03*
Y1074672D03*
Y1078018D03*
Y1081365D03*
Y1084711D03*
Y1088058D03*
Y1091404D03*
Y1094751D03*
Y1098097D03*
Y1101444D03*
Y1104790D03*
Y1108137D03*
Y1111483D03*
Y1114829D03*
Y1118176D03*
Y1121522D03*
Y1124869D03*
Y1128215D03*
Y1131562D03*
Y1134908D03*
Y1138255D03*
Y1141601D03*
Y1144948D03*
Y1148294D03*
Y1151641D03*
Y1154987D03*
Y1158333D03*
Y1161680D03*
Y1165026D03*
Y1168373D03*
Y1171719D03*
Y1175066D03*
Y1178412D03*
Y1181759D03*
Y1185105D03*
Y1188452D03*
Y1191798D03*
Y1195144D03*
Y1198491D03*
Y1201837D03*
Y1205184D03*
Y1208530D03*
Y1211877D03*
Y1215223D03*
Y1218570D03*
Y1221916D03*
Y1225263D03*
Y1228609D03*
Y1231955D03*
Y1235302D03*
Y1238648D03*
Y1241995D03*
Y1245341D03*
Y1248688D03*
Y1252034D03*
Y1255381D03*
Y1258727D03*
Y1262074D03*
Y1265420D03*
X239949Y766798D03*
Y770144D03*
Y773491D03*
Y776837D03*
Y780184D03*
Y783530D03*
Y786877D03*
Y790223D03*
Y793570D03*
Y796916D03*
Y800263D03*
Y803609D03*
Y806955D03*
Y810302D03*
Y813648D03*
Y816995D03*
Y820341D03*
Y823688D03*
Y827034D03*
Y830381D03*
Y833727D03*
Y837074D03*
Y840420D03*
Y843766D03*
Y847113D03*
Y850459D03*
Y853806D03*
Y857152D03*
Y860499D03*
Y863845D03*
Y867192D03*
Y870538D03*
Y873885D03*
Y877231D03*
Y880577D03*
Y883924D03*
Y887270D03*
Y890617D03*
Y893963D03*
Y897310D03*
Y900656D03*
Y904003D03*
Y907349D03*
Y910696D03*
Y914042D03*
Y917389D03*
Y920735D03*
Y924081D03*
Y927428D03*
Y930774D03*
Y934121D03*
Y937467D03*
Y940814D03*
Y944160D03*
Y947507D03*
Y950853D03*
Y954200D03*
Y957546D03*
Y960892D03*
Y964239D03*
Y967585D03*
Y970932D03*
Y974278D03*
Y977625D03*
Y980971D03*
Y984318D03*
Y987664D03*
Y991011D03*
Y994357D03*
Y1017782D03*
Y1021129D03*
Y1024475D03*
Y1027822D03*
Y1031168D03*
Y1034515D03*
Y1037861D03*
Y1041207D03*
Y1044554D03*
Y1047900D03*
Y1051247D03*
Y1054593D03*
Y1057940D03*
Y1061286D03*
Y1064633D03*
Y1067979D03*
Y1071326D03*
Y1074672D03*
Y1078018D03*
Y1081365D03*
Y1084711D03*
Y1088058D03*
Y1091404D03*
Y1094751D03*
Y1098097D03*
Y1101444D03*
Y1104790D03*
Y1108137D03*
Y1111483D03*
Y1114829D03*
Y1118176D03*
Y1121522D03*
Y1124869D03*
Y1128215D03*
Y1131562D03*
Y1134908D03*
Y1138255D03*
Y1141601D03*
Y1144948D03*
Y1148294D03*
Y1151641D03*
Y1154987D03*
Y1158333D03*
Y1161680D03*
Y1165026D03*
Y1168373D03*
Y1171719D03*
Y1175066D03*
Y1178412D03*
Y1181759D03*
Y1185105D03*
Y1188452D03*
Y1191798D03*
Y1195144D03*
Y1198491D03*
Y1201837D03*
Y1205184D03*
Y1208530D03*
Y1211877D03*
Y1215223D03*
Y1218570D03*
Y1221916D03*
Y1225263D03*
Y1228609D03*
Y1231955D03*
Y1235302D03*
Y1238648D03*
Y1241995D03*
Y1245341D03*
Y1248688D03*
Y1252034D03*
Y1255381D03*
Y1258727D03*
Y1262074D03*
Y1265420D03*
X256091Y766798D03*
Y770144D03*
Y773491D03*
Y776837D03*
Y780184D03*
Y783530D03*
Y786877D03*
Y790223D03*
Y793570D03*
Y796916D03*
Y800263D03*
Y803609D03*
Y806955D03*
Y810302D03*
Y813648D03*
Y816995D03*
Y820341D03*
Y823688D03*
Y827034D03*
Y830381D03*
Y833727D03*
Y837074D03*
Y840420D03*
Y843766D03*
Y847113D03*
Y850459D03*
Y853806D03*
Y857152D03*
Y860499D03*
Y863845D03*
Y867192D03*
Y870538D03*
Y873885D03*
Y877231D03*
Y880577D03*
Y883924D03*
Y887270D03*
Y890617D03*
Y893963D03*
Y897310D03*
Y900656D03*
Y904003D03*
Y907349D03*
Y910696D03*
Y914042D03*
Y917389D03*
Y920735D03*
Y924081D03*
Y927428D03*
Y930774D03*
Y934121D03*
Y937467D03*
Y940814D03*
Y944160D03*
Y947507D03*
Y950853D03*
Y954200D03*
Y957546D03*
Y960892D03*
Y964239D03*
Y967585D03*
Y970932D03*
Y974278D03*
Y977625D03*
Y980971D03*
Y984318D03*
Y987664D03*
Y991011D03*
Y994357D03*
Y1017782D03*
Y1021129D03*
Y1024475D03*
Y1027822D03*
Y1031168D03*
Y1034515D03*
Y1037861D03*
Y1041207D03*
Y1044554D03*
Y1047900D03*
Y1051247D03*
Y1054593D03*
Y1057940D03*
Y1061286D03*
Y1064633D03*
Y1067979D03*
Y1071326D03*
Y1074672D03*
Y1078018D03*
Y1081365D03*
Y1084711D03*
Y1088058D03*
Y1091404D03*
Y1094751D03*
Y1098097D03*
Y1101444D03*
Y1104790D03*
Y1108137D03*
Y1111483D03*
Y1114829D03*
Y1118176D03*
Y1121522D03*
Y1124869D03*
Y1128215D03*
Y1131562D03*
Y1134908D03*
Y1138255D03*
Y1141601D03*
Y1144948D03*
Y1148294D03*
Y1151641D03*
Y1154987D03*
Y1158333D03*
Y1161680D03*
Y1165026D03*
Y1168373D03*
Y1171719D03*
Y1175066D03*
Y1178412D03*
Y1181759D03*
Y1185105D03*
Y1188452D03*
Y1191798D03*
Y1195144D03*
Y1198491D03*
Y1201837D03*
Y1205184D03*
Y1208530D03*
Y1211877D03*
Y1215223D03*
Y1218570D03*
Y1221916D03*
Y1225263D03*
Y1228609D03*
Y1231955D03*
Y1235302D03*
Y1238648D03*
Y1241995D03*
Y1245341D03*
Y1248688D03*
Y1252034D03*
Y1255381D03*
Y1258727D03*
Y1262074D03*
Y1265420D03*
X625249Y766798D03*
Y770144D03*
Y773491D03*
Y776837D03*
Y780184D03*
Y783530D03*
Y786877D03*
Y790223D03*
Y793570D03*
Y796916D03*
Y800263D03*
Y803609D03*
Y806955D03*
Y810302D03*
Y813648D03*
Y816995D03*
Y820341D03*
Y823688D03*
Y827034D03*
Y830381D03*
Y833727D03*
Y837074D03*
Y840420D03*
Y843766D03*
Y847113D03*
Y850459D03*
Y853806D03*
Y857152D03*
Y860499D03*
Y863845D03*
Y867192D03*
Y870538D03*
Y873885D03*
Y877231D03*
Y880577D03*
Y883924D03*
Y887270D03*
Y890617D03*
Y893963D03*
Y897310D03*
Y900656D03*
Y904003D03*
Y907349D03*
Y910696D03*
Y914042D03*
Y917389D03*
Y920735D03*
Y924081D03*
Y927428D03*
Y930774D03*
Y934121D03*
Y937467D03*
Y940814D03*
Y944160D03*
Y947507D03*
Y950853D03*
Y954200D03*
Y957546D03*
Y960892D03*
Y964239D03*
Y967585D03*
Y970932D03*
Y974278D03*
Y977625D03*
Y980971D03*
Y984318D03*
Y987664D03*
Y991011D03*
Y994357D03*
Y1017782D03*
Y1021129D03*
Y1024475D03*
Y1027822D03*
Y1031168D03*
Y1034515D03*
Y1037861D03*
Y1041207D03*
Y1044554D03*
Y1047900D03*
Y1051247D03*
Y1054593D03*
Y1057940D03*
Y1061286D03*
Y1064633D03*
Y1067979D03*
Y1071326D03*
Y1074672D03*
Y1078018D03*
Y1081365D03*
Y1084711D03*
Y1088058D03*
Y1091404D03*
Y1094751D03*
Y1098097D03*
Y1101444D03*
Y1104790D03*
Y1108137D03*
Y1111483D03*
Y1114829D03*
Y1118176D03*
Y1121522D03*
Y1124869D03*
Y1128215D03*
Y1131562D03*
Y1134908D03*
Y1138255D03*
Y1141601D03*
Y1144948D03*
Y1148294D03*
Y1151641D03*
Y1154987D03*
Y1158333D03*
Y1161680D03*
Y1165026D03*
Y1168373D03*
Y1171719D03*
Y1175066D03*
Y1178412D03*
Y1181759D03*
Y1185105D03*
Y1188452D03*
Y1191798D03*
Y1195144D03*
Y1198491D03*
Y1201837D03*
Y1205184D03*
Y1208530D03*
Y1211877D03*
Y1215223D03*
Y1218570D03*
Y1221916D03*
Y1225263D03*
Y1228609D03*
Y1231955D03*
Y1235302D03*
Y1238648D03*
Y1241995D03*
Y1245341D03*
Y1248688D03*
Y1252034D03*
Y1255381D03*
Y1258727D03*
Y1262074D03*
Y1265420D03*
X641391Y766798D03*
Y770144D03*
Y773491D03*
Y776837D03*
Y780184D03*
Y783530D03*
Y786877D03*
Y790223D03*
Y793570D03*
Y796916D03*
Y800263D03*
Y803609D03*
Y806955D03*
Y810302D03*
Y813648D03*
Y816995D03*
Y820341D03*
Y823688D03*
Y827034D03*
Y830381D03*
Y833727D03*
Y837074D03*
Y840420D03*
Y843766D03*
Y847113D03*
Y850459D03*
Y853806D03*
Y857152D03*
Y860499D03*
Y863845D03*
Y867192D03*
Y870538D03*
Y873885D03*
Y877231D03*
Y880577D03*
Y883924D03*
Y887270D03*
Y890617D03*
Y893963D03*
Y897310D03*
Y900656D03*
Y904003D03*
Y907349D03*
Y910696D03*
Y914042D03*
Y917389D03*
Y920735D03*
Y924081D03*
Y927428D03*
Y930774D03*
Y934121D03*
Y937467D03*
Y940814D03*
Y944160D03*
Y947507D03*
Y950853D03*
Y954200D03*
Y957546D03*
Y960892D03*
Y964239D03*
Y967585D03*
Y970932D03*
Y974278D03*
Y977625D03*
Y980971D03*
Y984318D03*
Y987664D03*
Y991011D03*
Y994357D03*
Y1017782D03*
Y1021129D03*
Y1024475D03*
Y1027822D03*
Y1031168D03*
Y1034515D03*
Y1037861D03*
Y1041207D03*
Y1044554D03*
Y1047900D03*
Y1051247D03*
Y1054593D03*
Y1057940D03*
Y1061286D03*
Y1064633D03*
Y1067979D03*
Y1071326D03*
Y1074672D03*
Y1078018D03*
Y1081365D03*
Y1084711D03*
Y1088058D03*
Y1091404D03*
Y1094751D03*
Y1098097D03*
Y1101444D03*
Y1104790D03*
Y1108137D03*
Y1111483D03*
Y1114829D03*
Y1118176D03*
Y1121522D03*
Y1124869D03*
Y1128215D03*
Y1131562D03*
Y1134908D03*
Y1138255D03*
Y1141601D03*
Y1144948D03*
Y1148294D03*
Y1151641D03*
Y1154987D03*
Y1158333D03*
Y1161680D03*
Y1165026D03*
Y1168373D03*
Y1171719D03*
Y1175066D03*
Y1178412D03*
Y1181759D03*
Y1185105D03*
Y1188452D03*
Y1191798D03*
Y1195144D03*
Y1198491D03*
Y1201837D03*
Y1205184D03*
Y1208530D03*
Y1211877D03*
Y1215223D03*
Y1218570D03*
Y1221916D03*
Y1225263D03*
Y1228609D03*
Y1231955D03*
Y1235302D03*
Y1238648D03*
Y1241995D03*
Y1245341D03*
Y1248688D03*
Y1252034D03*
Y1255381D03*
Y1258727D03*
Y1262074D03*
Y1265420D03*
X654949Y766798D03*
Y770144D03*
Y773491D03*
Y776837D03*
Y780184D03*
Y783530D03*
Y786877D03*
Y790223D03*
Y793570D03*
Y796916D03*
Y800263D03*
Y803609D03*
Y806955D03*
Y810302D03*
Y813648D03*
Y816995D03*
Y820341D03*
Y823688D03*
Y827034D03*
Y830381D03*
Y833727D03*
Y837074D03*
Y840420D03*
Y843766D03*
Y847113D03*
Y850459D03*
Y853806D03*
Y857152D03*
Y860499D03*
Y863845D03*
Y867192D03*
Y870538D03*
Y873885D03*
Y877231D03*
Y880577D03*
Y883924D03*
Y887270D03*
Y890617D03*
Y893963D03*
Y897310D03*
Y900656D03*
Y904003D03*
Y907349D03*
Y910696D03*
Y914042D03*
Y917389D03*
Y920735D03*
Y924081D03*
Y927428D03*
Y930774D03*
Y934121D03*
Y937467D03*
Y940814D03*
Y944160D03*
Y947507D03*
Y950853D03*
Y954200D03*
Y957546D03*
Y960892D03*
Y964239D03*
Y967585D03*
Y970932D03*
Y974278D03*
Y977625D03*
Y980971D03*
Y984318D03*
Y987664D03*
Y991011D03*
Y994357D03*
Y1017782D03*
Y1021129D03*
Y1024475D03*
Y1027822D03*
Y1031168D03*
Y1034515D03*
Y1037861D03*
Y1041207D03*
Y1044554D03*
Y1047900D03*
Y1051247D03*
Y1054593D03*
Y1057940D03*
Y1061286D03*
Y1064633D03*
Y1067979D03*
Y1071326D03*
Y1074672D03*
Y1078018D03*
Y1081365D03*
Y1084711D03*
Y1088058D03*
Y1091404D03*
Y1094751D03*
Y1098097D03*
Y1101444D03*
Y1104790D03*
Y1108137D03*
Y1111483D03*
Y1114829D03*
Y1118176D03*
Y1121522D03*
Y1124869D03*
Y1128215D03*
Y1131562D03*
Y1134908D03*
Y1138255D03*
Y1141601D03*
Y1144948D03*
Y1148294D03*
Y1151641D03*
Y1154987D03*
Y1158333D03*
Y1161680D03*
Y1165026D03*
Y1168373D03*
Y1171719D03*
Y1175066D03*
Y1178412D03*
Y1181759D03*
Y1185105D03*
Y1188452D03*
Y1191798D03*
Y1195144D03*
Y1198491D03*
Y1201837D03*
Y1205184D03*
Y1208530D03*
Y1211877D03*
Y1215223D03*
Y1218570D03*
Y1221916D03*
Y1225263D03*
Y1228609D03*
Y1231955D03*
Y1235302D03*
Y1238648D03*
Y1241995D03*
Y1245341D03*
Y1248688D03*
Y1252034D03*
Y1255381D03*
Y1258727D03*
Y1262074D03*
Y1265420D03*
X671091Y766798D03*
Y770144D03*
Y773491D03*
Y776837D03*
Y780184D03*
Y783530D03*
Y786877D03*
Y790223D03*
Y793570D03*
Y796916D03*
Y800263D03*
Y803609D03*
Y806955D03*
Y810302D03*
Y813648D03*
Y816995D03*
Y820341D03*
Y823688D03*
Y827034D03*
Y830381D03*
Y833727D03*
Y837074D03*
Y840420D03*
Y843766D03*
Y847113D03*
Y850459D03*
Y853806D03*
Y857152D03*
Y860499D03*
Y863845D03*
Y867192D03*
Y870538D03*
Y873885D03*
Y877231D03*
Y880577D03*
Y883924D03*
Y887270D03*
Y890617D03*
Y893963D03*
Y897310D03*
Y900656D03*
Y904003D03*
Y907349D03*
Y910696D03*
Y914042D03*
Y917389D03*
Y920735D03*
Y924081D03*
Y927428D03*
Y930774D03*
Y934121D03*
Y937467D03*
Y940814D03*
Y944160D03*
Y947507D03*
Y950853D03*
Y954200D03*
Y957546D03*
Y960892D03*
Y964239D03*
Y967585D03*
Y970932D03*
Y974278D03*
Y977625D03*
Y980971D03*
Y984318D03*
Y987664D03*
Y991011D03*
Y994357D03*
Y1017782D03*
Y1021129D03*
Y1024475D03*
Y1027822D03*
Y1031168D03*
Y1034515D03*
Y1037861D03*
Y1041207D03*
Y1044554D03*
Y1047900D03*
Y1051247D03*
Y1054593D03*
Y1057940D03*
Y1061286D03*
Y1064633D03*
Y1067979D03*
Y1071326D03*
Y1074672D03*
Y1078018D03*
Y1081365D03*
Y1084711D03*
Y1088058D03*
Y1091404D03*
Y1094751D03*
Y1098097D03*
Y1101444D03*
Y1104790D03*
Y1108137D03*
Y1111483D03*
Y1114829D03*
Y1118176D03*
Y1121522D03*
Y1124869D03*
Y1128215D03*
Y1131562D03*
Y1134908D03*
Y1138255D03*
Y1141601D03*
Y1144948D03*
Y1148294D03*
Y1151641D03*
Y1154987D03*
Y1158333D03*
Y1161680D03*
Y1165026D03*
Y1168373D03*
Y1171719D03*
Y1175066D03*
Y1178412D03*
Y1181759D03*
Y1185105D03*
Y1188452D03*
Y1191798D03*
Y1195144D03*
Y1198491D03*
Y1201837D03*
Y1205184D03*
Y1208530D03*
Y1211877D03*
Y1215223D03*
Y1218570D03*
Y1221916D03*
Y1225263D03*
Y1228609D03*
Y1231955D03*
Y1235302D03*
Y1238648D03*
Y1241995D03*
Y1245341D03*
Y1248688D03*
Y1252034D03*
Y1255381D03*
Y1258727D03*
Y1262074D03*
Y1265420D03*
X684649Y766798D03*
Y770144D03*
Y773491D03*
Y776837D03*
Y780184D03*
Y783530D03*
Y786877D03*
Y790223D03*
Y793570D03*
Y796916D03*
Y800263D03*
Y803609D03*
Y806955D03*
Y810302D03*
Y813648D03*
Y816995D03*
Y820341D03*
Y823688D03*
Y827034D03*
Y830381D03*
Y833727D03*
Y837074D03*
Y840420D03*
Y843766D03*
Y847113D03*
Y850459D03*
Y853806D03*
Y857152D03*
Y860499D03*
Y863845D03*
Y867192D03*
Y870538D03*
Y873885D03*
Y877231D03*
Y880577D03*
Y883924D03*
Y887270D03*
Y890617D03*
Y893963D03*
Y897310D03*
Y900656D03*
Y904003D03*
Y907349D03*
Y910696D03*
Y914042D03*
Y917389D03*
Y920735D03*
Y924081D03*
Y927428D03*
Y930774D03*
Y934121D03*
Y937467D03*
Y940814D03*
Y944160D03*
Y947507D03*
Y950853D03*
Y954200D03*
Y957546D03*
Y960892D03*
Y964239D03*
Y967585D03*
Y970932D03*
Y974278D03*
Y977625D03*
Y980971D03*
Y984318D03*
Y987664D03*
Y991011D03*
Y994357D03*
Y1017782D03*
Y1021129D03*
Y1024475D03*
Y1027822D03*
Y1031168D03*
Y1034515D03*
Y1037861D03*
Y1041207D03*
Y1044554D03*
Y1047900D03*
Y1051247D03*
Y1054593D03*
Y1057940D03*
Y1061286D03*
Y1064633D03*
Y1067979D03*
Y1071326D03*
Y1074672D03*
Y1078018D03*
Y1081365D03*
Y1084711D03*
Y1088058D03*
Y1091404D03*
Y1094751D03*
Y1098097D03*
Y1101444D03*
Y1104790D03*
Y1108137D03*
Y1111483D03*
Y1114829D03*
Y1118176D03*
Y1121522D03*
Y1124869D03*
Y1128215D03*
Y1131562D03*
Y1134908D03*
Y1138255D03*
Y1141601D03*
Y1144948D03*
Y1148294D03*
Y1151641D03*
Y1154987D03*
Y1158333D03*
Y1161680D03*
Y1165026D03*
Y1168373D03*
Y1171719D03*
Y1175066D03*
Y1178412D03*
Y1181759D03*
Y1185105D03*
Y1188452D03*
Y1191798D03*
Y1195144D03*
Y1198491D03*
Y1201837D03*
Y1205184D03*
Y1208530D03*
Y1211877D03*
Y1215223D03*
Y1218570D03*
Y1221916D03*
Y1225263D03*
Y1228609D03*
Y1231955D03*
Y1235302D03*
Y1238648D03*
Y1241995D03*
Y1245341D03*
Y1248688D03*
Y1252034D03*
Y1255381D03*
Y1258727D03*
Y1262074D03*
Y1265420D03*
X714349Y766798D03*
Y770144D03*
X700791Y766798D03*
Y770144D03*
X714349Y773491D03*
Y776837D03*
Y780184D03*
Y783530D03*
Y786877D03*
X700791Y773491D03*
Y776837D03*
Y780184D03*
Y783530D03*
Y786877D03*
X714349Y790223D03*
Y793570D03*
Y796916D03*
Y800263D03*
Y803609D03*
X700791Y790223D03*
Y793570D03*
Y796916D03*
Y800263D03*
Y803609D03*
X714349Y806955D03*
Y810302D03*
Y813648D03*
Y816995D03*
Y820341D03*
X700791Y806955D03*
Y810302D03*
Y813648D03*
Y816995D03*
Y820341D03*
X714349Y823688D03*
Y827034D03*
Y830381D03*
Y833727D03*
X700791Y823688D03*
Y827034D03*
Y830381D03*
Y833727D03*
X714349Y837074D03*
Y840420D03*
Y843766D03*
Y847113D03*
Y850459D03*
X700791Y837074D03*
Y840420D03*
Y843766D03*
Y847113D03*
Y850459D03*
X714349Y853806D03*
Y857152D03*
Y860499D03*
Y863845D03*
Y867192D03*
X700791Y853806D03*
Y857152D03*
Y860499D03*
Y863845D03*
Y867192D03*
X714349Y870538D03*
Y873885D03*
Y877231D03*
Y880577D03*
Y883924D03*
X700791Y870538D03*
Y873885D03*
Y877231D03*
Y880577D03*
Y883924D03*
X714349Y887270D03*
Y890617D03*
Y893963D03*
Y897310D03*
Y900656D03*
X700791Y887270D03*
Y890617D03*
Y893963D03*
Y897310D03*
Y900656D03*
X714349Y904003D03*
Y907349D03*
Y910696D03*
Y914042D03*
Y917389D03*
X700791Y904003D03*
Y907349D03*
Y910696D03*
Y914042D03*
Y917389D03*
X714349Y920735D03*
Y924081D03*
Y927428D03*
Y930774D03*
Y934121D03*
X700791Y920735D03*
Y924081D03*
Y927428D03*
Y930774D03*
Y934121D03*
X714349Y937467D03*
Y940814D03*
Y944160D03*
Y947507D03*
X700791Y937467D03*
Y940814D03*
Y944160D03*
Y947507D03*
X714349Y950853D03*
Y954200D03*
Y957546D03*
Y960892D03*
Y964239D03*
X700791Y950853D03*
Y954200D03*
Y957546D03*
Y960892D03*
Y964239D03*
X714349Y967585D03*
Y970932D03*
Y974278D03*
Y977625D03*
Y980971D03*
X700791Y967585D03*
Y970932D03*
Y974278D03*
Y977625D03*
Y980971D03*
X714349Y984318D03*
Y987664D03*
Y991011D03*
Y994357D03*
X700791Y984318D03*
Y987664D03*
Y991011D03*
Y994357D03*
X714349Y1017782D03*
Y1021129D03*
Y1024475D03*
Y1027822D03*
Y1031168D03*
X700791Y1017782D03*
Y1021129D03*
Y1024475D03*
Y1027822D03*
Y1031168D03*
X714349Y1034515D03*
Y1037861D03*
Y1041207D03*
Y1044554D03*
Y1047900D03*
X700791Y1034515D03*
Y1037861D03*
Y1041207D03*
Y1044554D03*
Y1047900D03*
X714349Y1051247D03*
Y1054593D03*
Y1057940D03*
Y1061286D03*
X700791Y1051247D03*
Y1054593D03*
Y1057940D03*
Y1061286D03*
X714349Y1064633D03*
Y1067979D03*
Y1071326D03*
Y1074672D03*
Y1078018D03*
X700791Y1064633D03*
Y1067979D03*
Y1071326D03*
Y1074672D03*
Y1078018D03*
X714349Y1081365D03*
Y1084711D03*
Y1088058D03*
Y1091404D03*
Y1094751D03*
X700791Y1081365D03*
Y1084711D03*
Y1088058D03*
Y1091404D03*
Y1094751D03*
X714349Y1098097D03*
Y1101444D03*
Y1104790D03*
Y1108137D03*
Y1111483D03*
X700791Y1098097D03*
Y1101444D03*
Y1104790D03*
Y1108137D03*
Y1111483D03*
X714349Y1114829D03*
Y1118176D03*
Y1121522D03*
Y1124869D03*
Y1128215D03*
X700791Y1114829D03*
Y1118176D03*
Y1121522D03*
Y1124869D03*
Y1128215D03*
X714349Y1131562D03*
Y1134908D03*
Y1138255D03*
Y1141601D03*
Y1144948D03*
X700791Y1131562D03*
Y1134908D03*
Y1138255D03*
Y1141601D03*
Y1144948D03*
X714349Y1148294D03*
Y1151641D03*
Y1154987D03*
Y1158333D03*
Y1161680D03*
X700791Y1148294D03*
Y1151641D03*
Y1154987D03*
Y1158333D03*
Y1161680D03*
X714349Y1165026D03*
Y1168373D03*
Y1171719D03*
Y1175066D03*
X700791Y1165026D03*
Y1168373D03*
Y1171719D03*
Y1175066D03*
X714349Y1178412D03*
Y1181759D03*
Y1185105D03*
Y1188452D03*
Y1191798D03*
X700791Y1178412D03*
Y1181759D03*
Y1185105D03*
Y1188452D03*
Y1191798D03*
X714349Y1195144D03*
Y1198491D03*
Y1201837D03*
Y1205184D03*
Y1208530D03*
X700791Y1195144D03*
Y1198491D03*
Y1201837D03*
Y1205184D03*
Y1208530D03*
X714349Y1211877D03*
Y1215223D03*
Y1218570D03*
Y1221916D03*
Y1225263D03*
X700791Y1211877D03*
Y1215223D03*
Y1218570D03*
Y1221916D03*
Y1225263D03*
X714349Y1228609D03*
Y1231955D03*
Y1235302D03*
Y1238648D03*
Y1241995D03*
X700791Y1228609D03*
Y1231955D03*
Y1235302D03*
Y1238648D03*
Y1241995D03*
X714349Y1245341D03*
Y1248688D03*
Y1252034D03*
Y1255381D03*
Y1258727D03*
X700791Y1245341D03*
Y1248688D03*
Y1252034D03*
Y1255381D03*
Y1258727D03*
X714349Y1262074D03*
Y1265420D03*
X700791Y1262074D03*
Y1265420D03*
X730491Y766798D03*
Y770144D03*
Y773491D03*
Y776837D03*
Y780184D03*
Y783530D03*
Y786877D03*
Y790223D03*
Y793570D03*
Y796916D03*
Y800263D03*
Y803609D03*
Y806955D03*
Y810302D03*
Y813648D03*
Y816995D03*
Y820341D03*
Y823688D03*
Y827034D03*
Y830381D03*
Y833727D03*
Y837074D03*
Y840420D03*
Y843766D03*
Y847113D03*
Y850459D03*
Y853806D03*
Y857152D03*
Y860499D03*
Y863845D03*
Y867192D03*
Y870538D03*
Y873885D03*
Y877231D03*
Y880577D03*
Y883924D03*
Y887270D03*
Y890617D03*
Y893963D03*
Y897310D03*
Y900656D03*
Y904003D03*
Y907349D03*
Y910696D03*
Y914042D03*
Y917389D03*
Y920735D03*
Y924081D03*
Y927428D03*
Y930774D03*
Y934121D03*
Y937467D03*
Y940814D03*
Y944160D03*
Y947507D03*
Y950853D03*
Y954200D03*
Y957546D03*
Y960892D03*
Y964239D03*
Y967585D03*
Y970932D03*
Y974278D03*
Y977625D03*
Y980971D03*
Y984318D03*
Y987664D03*
Y991011D03*
Y994357D03*
Y1017782D03*
Y1021129D03*
Y1024475D03*
Y1027822D03*
Y1031168D03*
Y1034515D03*
Y1037861D03*
Y1041207D03*
Y1044554D03*
Y1047900D03*
Y1051247D03*
Y1054593D03*
Y1057940D03*
Y1061286D03*
Y1064633D03*
Y1067979D03*
Y1071326D03*
Y1074672D03*
Y1078018D03*
Y1081365D03*
Y1084711D03*
Y1088058D03*
Y1091404D03*
Y1094751D03*
Y1098097D03*
Y1101444D03*
Y1104790D03*
Y1108137D03*
Y1111483D03*
Y1114829D03*
Y1118176D03*
Y1121522D03*
Y1124869D03*
Y1128215D03*
Y1131562D03*
Y1134908D03*
Y1138255D03*
Y1141601D03*
Y1144948D03*
Y1148294D03*
Y1151641D03*
Y1154987D03*
Y1158333D03*
Y1161680D03*
Y1165026D03*
Y1168373D03*
Y1171719D03*
Y1175066D03*
Y1178412D03*
Y1181759D03*
Y1185105D03*
Y1188452D03*
Y1191798D03*
Y1195144D03*
Y1198491D03*
Y1201837D03*
Y1205184D03*
Y1208530D03*
Y1211877D03*
Y1215223D03*
Y1218570D03*
Y1221916D03*
Y1225263D03*
Y1228609D03*
Y1231955D03*
Y1235302D03*
Y1238648D03*
Y1241995D03*
Y1245341D03*
Y1248688D03*
Y1252034D03*
Y1255381D03*
Y1258727D03*
Y1262074D03*
Y1265420D03*
X744049Y766798D03*
Y770144D03*
Y773491D03*
Y776837D03*
Y780184D03*
Y783530D03*
Y786877D03*
Y790223D03*
Y793570D03*
Y796916D03*
Y800263D03*
Y803609D03*
Y806955D03*
Y810302D03*
Y813648D03*
Y816995D03*
Y820341D03*
Y823688D03*
Y827034D03*
Y830381D03*
Y833727D03*
Y837074D03*
Y840420D03*
Y843766D03*
Y847113D03*
Y850459D03*
Y853806D03*
Y857152D03*
Y860499D03*
Y863845D03*
Y867192D03*
Y870538D03*
Y873885D03*
Y877231D03*
Y880577D03*
Y883924D03*
Y887270D03*
Y890617D03*
Y893963D03*
Y897310D03*
Y900656D03*
Y904003D03*
Y907349D03*
Y910696D03*
Y914042D03*
Y917389D03*
Y920735D03*
Y924081D03*
Y927428D03*
Y930774D03*
Y934121D03*
Y937467D03*
Y940814D03*
Y944160D03*
Y947507D03*
Y950853D03*
Y954200D03*
Y957546D03*
Y960892D03*
Y964239D03*
Y967585D03*
Y970932D03*
Y974278D03*
Y977625D03*
Y980971D03*
Y984318D03*
Y987664D03*
Y991011D03*
Y994357D03*
Y1017782D03*
Y1021129D03*
Y1024475D03*
Y1027822D03*
Y1031168D03*
Y1034515D03*
Y1037861D03*
Y1041207D03*
Y1044554D03*
Y1047900D03*
Y1051247D03*
Y1054593D03*
Y1057940D03*
Y1061286D03*
Y1064633D03*
Y1067979D03*
Y1071326D03*
Y1074672D03*
Y1078018D03*
Y1081365D03*
Y1084711D03*
Y1088058D03*
Y1091404D03*
Y1094751D03*
Y1098097D03*
Y1101444D03*
Y1104790D03*
Y1108137D03*
Y1111483D03*
Y1114829D03*
Y1118176D03*
Y1121522D03*
Y1124869D03*
Y1128215D03*
Y1131562D03*
Y1134908D03*
Y1138255D03*
Y1141601D03*
Y1144948D03*
Y1148294D03*
Y1151641D03*
Y1154987D03*
Y1158333D03*
Y1161680D03*
Y1165026D03*
Y1168373D03*
Y1171719D03*
Y1175066D03*
Y1178412D03*
Y1181759D03*
Y1185105D03*
Y1188452D03*
Y1191798D03*
Y1195144D03*
Y1198491D03*
Y1201837D03*
Y1205184D03*
Y1208530D03*
Y1211877D03*
Y1215223D03*
Y1218570D03*
Y1221916D03*
Y1225263D03*
Y1228609D03*
Y1231955D03*
Y1235302D03*
Y1238648D03*
Y1241995D03*
Y1245341D03*
Y1248688D03*
Y1252034D03*
Y1255381D03*
Y1258727D03*
Y1262074D03*
Y1265420D03*
X760191Y766798D03*
Y770144D03*
Y773491D03*
Y776837D03*
Y780184D03*
Y783530D03*
Y786877D03*
Y790223D03*
Y793570D03*
Y796916D03*
Y800263D03*
Y803609D03*
Y806955D03*
Y810302D03*
Y813648D03*
Y816995D03*
Y820341D03*
Y823688D03*
Y827034D03*
Y830381D03*
Y833727D03*
Y837074D03*
Y840420D03*
Y843766D03*
Y847113D03*
Y850459D03*
Y853806D03*
Y857152D03*
Y860499D03*
Y863845D03*
Y867192D03*
Y870538D03*
Y873885D03*
Y877231D03*
Y880577D03*
Y883924D03*
Y887270D03*
Y890617D03*
Y893963D03*
Y897310D03*
Y900656D03*
Y904003D03*
Y907349D03*
Y910696D03*
Y914042D03*
Y917389D03*
Y920735D03*
Y924081D03*
Y927428D03*
Y930774D03*
Y934121D03*
Y937467D03*
Y940814D03*
Y944160D03*
Y947507D03*
Y950853D03*
Y954200D03*
Y957546D03*
Y960892D03*
Y964239D03*
Y967585D03*
Y970932D03*
Y974278D03*
Y977625D03*
Y980971D03*
Y984318D03*
Y987664D03*
Y991011D03*
Y994357D03*
Y1017782D03*
Y1021129D03*
Y1024475D03*
Y1027822D03*
Y1031168D03*
Y1034515D03*
Y1037861D03*
Y1041207D03*
Y1044554D03*
Y1047900D03*
Y1051247D03*
Y1054593D03*
Y1057940D03*
Y1061286D03*
Y1064633D03*
Y1067979D03*
Y1071326D03*
Y1074672D03*
Y1078018D03*
Y1081365D03*
Y1084711D03*
Y1088058D03*
Y1091404D03*
Y1094751D03*
Y1098097D03*
Y1101444D03*
Y1104790D03*
Y1108137D03*
Y1111483D03*
Y1114829D03*
Y1118176D03*
Y1121522D03*
Y1124869D03*
Y1128215D03*
Y1131562D03*
Y1134908D03*
Y1138255D03*
Y1141601D03*
Y1144948D03*
Y1148294D03*
Y1151641D03*
Y1154987D03*
Y1158333D03*
Y1161680D03*
Y1165026D03*
Y1168373D03*
Y1171719D03*
Y1175066D03*
Y1178412D03*
Y1181759D03*
Y1185105D03*
Y1188452D03*
Y1191798D03*
Y1195144D03*
Y1198491D03*
Y1201837D03*
Y1205184D03*
Y1208530D03*
Y1211877D03*
Y1215223D03*
Y1218570D03*
Y1221916D03*
Y1225263D03*
Y1228609D03*
Y1231955D03*
Y1235302D03*
Y1238648D03*
Y1241995D03*
Y1245341D03*
Y1248688D03*
Y1252034D03*
Y1255381D03*
Y1258727D03*
Y1262074D03*
Y1265420D03*
X773749Y766798D03*
Y770144D03*
Y773491D03*
Y776837D03*
Y780184D03*
Y783530D03*
Y786877D03*
Y790223D03*
Y793570D03*
Y796916D03*
Y800263D03*
Y803609D03*
Y806955D03*
Y810302D03*
Y813648D03*
Y816995D03*
Y820341D03*
Y823688D03*
Y827034D03*
Y830381D03*
Y833727D03*
Y837074D03*
Y840420D03*
Y843766D03*
Y847113D03*
Y850459D03*
Y853806D03*
Y857152D03*
Y860499D03*
Y863845D03*
Y867192D03*
Y870538D03*
Y873885D03*
Y877231D03*
Y880577D03*
Y883924D03*
Y887270D03*
Y890617D03*
Y893963D03*
Y897310D03*
Y900656D03*
Y904003D03*
Y907349D03*
Y910696D03*
Y914042D03*
Y917389D03*
Y920735D03*
Y924081D03*
Y927428D03*
Y930774D03*
Y934121D03*
Y937467D03*
Y940814D03*
Y944160D03*
Y947507D03*
Y950853D03*
Y954200D03*
Y957546D03*
Y960892D03*
Y964239D03*
Y967585D03*
Y970932D03*
Y974278D03*
Y977625D03*
Y980971D03*
Y984318D03*
Y987664D03*
Y991011D03*
Y994357D03*
Y1017782D03*
Y1021129D03*
Y1024475D03*
Y1027822D03*
Y1031168D03*
Y1034515D03*
Y1037861D03*
Y1041207D03*
Y1044554D03*
Y1047900D03*
Y1051247D03*
Y1054593D03*
Y1057940D03*
Y1061286D03*
Y1064633D03*
Y1067979D03*
Y1071326D03*
Y1074672D03*
Y1078018D03*
Y1081365D03*
Y1084711D03*
Y1088058D03*
Y1091404D03*
Y1094751D03*
Y1098097D03*
Y1101444D03*
Y1104790D03*
Y1108137D03*
Y1111483D03*
Y1114829D03*
Y1118176D03*
Y1121522D03*
Y1124869D03*
Y1128215D03*
Y1131562D03*
Y1134908D03*
Y1138255D03*
Y1141601D03*
Y1144948D03*
Y1148294D03*
Y1151641D03*
Y1154987D03*
Y1158333D03*
Y1161680D03*
Y1165026D03*
Y1168373D03*
Y1171719D03*
Y1175066D03*
Y1178412D03*
Y1181759D03*
Y1185105D03*
Y1188452D03*
Y1191798D03*
Y1195144D03*
Y1198491D03*
Y1201837D03*
Y1205184D03*
Y1208530D03*
Y1211877D03*
Y1215223D03*
Y1218570D03*
Y1221916D03*
Y1225263D03*
Y1228609D03*
Y1231955D03*
Y1235302D03*
Y1238648D03*
Y1241995D03*
Y1245341D03*
Y1248688D03*
Y1252034D03*
Y1255381D03*
Y1258727D03*
Y1262074D03*
Y1265420D03*
X789891Y766798D03*
Y770144D03*
Y773491D03*
Y776837D03*
Y780184D03*
Y783530D03*
Y786877D03*
Y790223D03*
Y793570D03*
Y796916D03*
Y800263D03*
Y803609D03*
Y806955D03*
Y810302D03*
Y813648D03*
Y816995D03*
Y820341D03*
Y823688D03*
Y827034D03*
Y830381D03*
Y833727D03*
Y837074D03*
Y840420D03*
Y843766D03*
Y847113D03*
Y850459D03*
Y853806D03*
Y857152D03*
Y860499D03*
Y863845D03*
Y867192D03*
Y870538D03*
Y873885D03*
Y877231D03*
Y880577D03*
Y883924D03*
Y887270D03*
Y890617D03*
Y893963D03*
Y897310D03*
Y900656D03*
Y904003D03*
Y907349D03*
Y910696D03*
Y914042D03*
Y917389D03*
Y920735D03*
Y924081D03*
Y927428D03*
Y930774D03*
Y934121D03*
Y937467D03*
Y940814D03*
Y944160D03*
Y947507D03*
Y950853D03*
Y954200D03*
Y957546D03*
Y960892D03*
Y964239D03*
Y967585D03*
Y970932D03*
Y974278D03*
Y977625D03*
Y980971D03*
Y984318D03*
Y987664D03*
Y991011D03*
Y994357D03*
Y1017782D03*
Y1021129D03*
Y1024475D03*
Y1027822D03*
Y1031168D03*
Y1034515D03*
Y1037861D03*
Y1041207D03*
Y1044554D03*
Y1047900D03*
Y1051247D03*
Y1054593D03*
Y1057940D03*
Y1061286D03*
Y1064633D03*
Y1067979D03*
Y1071326D03*
Y1074672D03*
Y1078018D03*
Y1081365D03*
Y1084711D03*
Y1088058D03*
Y1091404D03*
Y1094751D03*
Y1098097D03*
Y1101444D03*
Y1104790D03*
Y1108137D03*
Y1111483D03*
Y1114829D03*
Y1118176D03*
Y1121522D03*
Y1124869D03*
Y1128215D03*
Y1131562D03*
Y1134908D03*
Y1138255D03*
Y1141601D03*
Y1144948D03*
Y1148294D03*
Y1151641D03*
Y1154987D03*
Y1158333D03*
Y1161680D03*
Y1165026D03*
Y1168373D03*
Y1171719D03*
Y1175066D03*
Y1178412D03*
Y1181759D03*
Y1185105D03*
Y1188452D03*
Y1191798D03*
Y1195144D03*
Y1198491D03*
Y1201837D03*
Y1205184D03*
Y1208530D03*
Y1211877D03*
Y1215223D03*
Y1218570D03*
Y1221916D03*
Y1225263D03*
Y1228609D03*
Y1231955D03*
Y1235302D03*
Y1238648D03*
Y1241995D03*
Y1245341D03*
Y1248688D03*
Y1252034D03*
Y1255381D03*
Y1258727D03*
Y1262074D03*
Y1265420D03*
X803449Y766798D03*
Y770144D03*
Y773491D03*
Y776837D03*
Y780184D03*
Y783530D03*
Y786877D03*
Y790223D03*
Y793570D03*
Y796916D03*
Y800263D03*
Y803609D03*
Y806955D03*
Y810302D03*
Y813648D03*
Y816995D03*
Y820341D03*
Y823688D03*
Y827034D03*
Y830381D03*
Y833727D03*
Y837074D03*
Y840420D03*
Y843766D03*
Y847113D03*
Y850459D03*
Y853806D03*
Y857152D03*
Y860499D03*
Y863845D03*
Y867192D03*
Y870538D03*
Y873885D03*
Y877231D03*
Y880577D03*
Y883924D03*
Y887270D03*
Y890617D03*
Y893963D03*
Y897310D03*
Y900656D03*
Y904003D03*
Y907349D03*
Y910696D03*
Y914042D03*
Y917389D03*
Y920735D03*
Y924081D03*
Y927428D03*
Y930774D03*
Y934121D03*
Y937467D03*
Y940814D03*
Y944160D03*
Y947507D03*
Y950853D03*
Y954200D03*
Y957546D03*
Y960892D03*
Y964239D03*
Y967585D03*
Y970932D03*
Y974278D03*
Y977625D03*
Y980971D03*
Y984318D03*
Y987664D03*
Y991011D03*
Y994357D03*
Y1017782D03*
Y1021129D03*
Y1024475D03*
Y1027822D03*
Y1031168D03*
Y1034515D03*
Y1037861D03*
Y1041207D03*
Y1044554D03*
Y1047900D03*
Y1051247D03*
Y1054593D03*
Y1057940D03*
Y1061286D03*
Y1064633D03*
Y1067979D03*
Y1071326D03*
Y1074672D03*
Y1078018D03*
Y1081365D03*
Y1084711D03*
Y1088058D03*
Y1091404D03*
Y1094751D03*
Y1098097D03*
Y1101444D03*
Y1104790D03*
Y1108137D03*
Y1111483D03*
Y1114829D03*
Y1118176D03*
Y1121522D03*
Y1124869D03*
Y1128215D03*
Y1131562D03*
Y1134908D03*
Y1138255D03*
Y1141601D03*
Y1144948D03*
Y1148294D03*
Y1151641D03*
Y1154987D03*
Y1158333D03*
Y1161680D03*
Y1165026D03*
Y1168373D03*
Y1171719D03*
Y1175066D03*
Y1178412D03*
Y1181759D03*
Y1185105D03*
Y1188452D03*
Y1191798D03*
Y1195144D03*
Y1198491D03*
Y1201837D03*
Y1205184D03*
Y1208530D03*
Y1211877D03*
Y1215223D03*
Y1218570D03*
Y1221916D03*
Y1225263D03*
Y1228609D03*
Y1231955D03*
Y1235302D03*
Y1238648D03*
Y1241995D03*
Y1245341D03*
Y1248688D03*
Y1252034D03*
Y1255381D03*
Y1258727D03*
Y1262074D03*
Y1265420D03*
X819591Y766798D03*
Y770144D03*
Y773491D03*
Y776837D03*
Y780184D03*
Y783530D03*
Y786877D03*
Y790223D03*
Y793570D03*
Y796916D03*
Y800263D03*
Y803609D03*
Y806955D03*
Y810302D03*
Y813648D03*
Y816995D03*
Y820341D03*
Y823688D03*
Y827034D03*
Y830381D03*
Y833727D03*
Y837074D03*
Y840420D03*
Y843766D03*
Y847113D03*
Y850459D03*
Y853806D03*
Y857152D03*
Y860499D03*
Y863845D03*
Y867192D03*
Y870538D03*
Y873885D03*
Y877231D03*
Y880577D03*
Y883924D03*
Y887270D03*
Y890617D03*
Y893963D03*
Y897310D03*
Y900656D03*
Y904003D03*
Y907349D03*
Y910696D03*
Y914042D03*
Y917389D03*
Y920735D03*
Y924081D03*
Y927428D03*
Y930774D03*
Y934121D03*
Y937467D03*
Y940814D03*
Y944160D03*
Y947507D03*
Y950853D03*
Y954200D03*
Y957546D03*
Y960892D03*
Y964239D03*
Y967585D03*
Y970932D03*
Y974278D03*
Y977625D03*
Y980971D03*
Y984318D03*
Y987664D03*
Y991011D03*
Y994357D03*
Y1017782D03*
Y1021129D03*
Y1024475D03*
Y1027822D03*
Y1031168D03*
Y1034515D03*
Y1037861D03*
Y1041207D03*
Y1044554D03*
Y1047900D03*
Y1051247D03*
Y1054593D03*
Y1057940D03*
Y1061286D03*
Y1064633D03*
Y1067979D03*
Y1071326D03*
Y1074672D03*
Y1078018D03*
Y1081365D03*
Y1084711D03*
Y1088058D03*
Y1091404D03*
Y1094751D03*
Y1098097D03*
Y1101444D03*
Y1104790D03*
Y1108137D03*
Y1111483D03*
Y1114829D03*
Y1118176D03*
Y1121522D03*
Y1124869D03*
Y1128215D03*
Y1131562D03*
Y1134908D03*
Y1138255D03*
Y1141601D03*
Y1144948D03*
Y1148294D03*
Y1151641D03*
Y1154987D03*
Y1158333D03*
Y1161680D03*
Y1165026D03*
Y1168373D03*
Y1171719D03*
Y1175066D03*
Y1178412D03*
Y1181759D03*
Y1185105D03*
Y1188452D03*
Y1191798D03*
Y1195144D03*
Y1198491D03*
Y1201837D03*
Y1205184D03*
Y1208530D03*
Y1211877D03*
Y1215223D03*
Y1218570D03*
Y1221916D03*
Y1225263D03*
Y1228609D03*
Y1231955D03*
Y1235302D03*
Y1238648D03*
Y1241995D03*
Y1245341D03*
Y1248688D03*
Y1252034D03*
Y1255381D03*
Y1258727D03*
Y1262074D03*
Y1265420D03*
X833149Y766798D03*
Y770144D03*
Y773491D03*
Y776837D03*
Y780184D03*
Y783530D03*
Y786877D03*
Y790223D03*
Y793570D03*
Y796916D03*
Y800263D03*
Y803609D03*
Y806955D03*
Y810302D03*
Y813648D03*
Y816995D03*
Y820341D03*
Y823688D03*
Y827034D03*
Y830381D03*
Y833727D03*
Y837074D03*
Y840420D03*
Y843766D03*
Y847113D03*
Y850459D03*
Y853806D03*
Y857152D03*
Y860499D03*
Y863845D03*
Y867192D03*
Y870538D03*
Y873885D03*
Y877231D03*
Y880577D03*
Y883924D03*
Y887270D03*
Y890617D03*
Y893963D03*
Y897310D03*
Y900656D03*
Y904003D03*
Y907349D03*
Y910696D03*
Y914042D03*
Y917389D03*
Y920735D03*
Y924081D03*
Y927428D03*
Y930774D03*
Y934121D03*
Y937467D03*
Y940814D03*
Y944160D03*
Y947507D03*
Y950853D03*
Y954200D03*
Y957546D03*
Y960892D03*
Y964239D03*
Y967585D03*
Y970932D03*
Y974278D03*
Y977625D03*
Y980971D03*
Y984318D03*
Y987664D03*
Y991011D03*
Y994357D03*
Y1017782D03*
Y1021129D03*
Y1024475D03*
Y1027822D03*
Y1031168D03*
Y1034515D03*
Y1037861D03*
Y1041207D03*
Y1044554D03*
Y1047900D03*
Y1051247D03*
Y1054593D03*
Y1057940D03*
Y1061286D03*
Y1064633D03*
Y1067979D03*
Y1071326D03*
Y1074672D03*
Y1078018D03*
Y1081365D03*
Y1084711D03*
Y1088058D03*
Y1091404D03*
Y1094751D03*
Y1098097D03*
Y1101444D03*
Y1104790D03*
Y1108137D03*
Y1111483D03*
Y1114829D03*
Y1118176D03*
Y1121522D03*
Y1124869D03*
Y1128215D03*
Y1131562D03*
Y1134908D03*
Y1138255D03*
Y1141601D03*
Y1144948D03*
Y1148294D03*
Y1151641D03*
Y1154987D03*
Y1158333D03*
Y1161680D03*
Y1165026D03*
Y1168373D03*
Y1171719D03*
Y1175066D03*
Y1178412D03*
Y1181759D03*
Y1185105D03*
Y1188452D03*
Y1191798D03*
Y1195144D03*
Y1198491D03*
Y1201837D03*
Y1205184D03*
Y1208530D03*
Y1211877D03*
Y1215223D03*
Y1218570D03*
Y1221916D03*
Y1225263D03*
Y1228609D03*
Y1231955D03*
Y1235302D03*
Y1238648D03*
Y1241995D03*
Y1245341D03*
Y1248688D03*
Y1252034D03*
Y1255381D03*
Y1258727D03*
Y1262074D03*
Y1265420D03*
X849291Y766798D03*
Y770144D03*
Y773491D03*
Y776837D03*
Y780184D03*
Y783530D03*
Y786877D03*
Y790223D03*
Y793570D03*
Y796916D03*
Y800263D03*
Y803609D03*
Y806955D03*
Y810302D03*
Y813648D03*
Y816995D03*
Y820341D03*
Y823688D03*
Y827034D03*
Y830381D03*
Y833727D03*
Y837074D03*
Y840420D03*
Y843766D03*
Y847113D03*
Y850459D03*
Y853806D03*
Y857152D03*
Y860499D03*
Y863845D03*
Y867192D03*
Y870538D03*
Y873885D03*
Y877231D03*
Y880577D03*
Y883924D03*
Y887270D03*
Y890617D03*
Y893963D03*
Y897310D03*
Y900656D03*
Y904003D03*
Y907349D03*
Y910696D03*
Y914042D03*
Y917389D03*
Y920735D03*
Y924081D03*
Y927428D03*
Y930774D03*
Y934121D03*
Y937467D03*
Y940814D03*
Y944160D03*
Y947507D03*
Y950853D03*
Y954200D03*
Y957546D03*
Y960892D03*
Y964239D03*
Y967585D03*
Y970932D03*
Y974278D03*
Y977625D03*
Y980971D03*
Y984318D03*
Y987664D03*
Y991011D03*
Y994357D03*
Y1017782D03*
Y1021129D03*
Y1024475D03*
Y1027822D03*
Y1031168D03*
Y1034515D03*
Y1037861D03*
Y1041207D03*
Y1044554D03*
Y1047900D03*
Y1051247D03*
Y1054593D03*
Y1057940D03*
Y1061286D03*
Y1064633D03*
Y1067979D03*
Y1071326D03*
Y1074672D03*
Y1078018D03*
Y1081365D03*
Y1084711D03*
Y1088058D03*
Y1091404D03*
Y1094751D03*
Y1098097D03*
Y1101444D03*
Y1104790D03*
Y1108137D03*
Y1111483D03*
Y1114829D03*
Y1118176D03*
Y1121522D03*
Y1124869D03*
Y1128215D03*
Y1131562D03*
Y1134908D03*
Y1138255D03*
Y1141601D03*
Y1144948D03*
Y1148294D03*
Y1151641D03*
Y1154987D03*
Y1158333D03*
Y1161680D03*
Y1165026D03*
Y1168373D03*
Y1171719D03*
Y1175066D03*
Y1178412D03*
Y1181759D03*
Y1185105D03*
Y1188452D03*
Y1191798D03*
Y1195144D03*
Y1198491D03*
Y1201837D03*
Y1205184D03*
Y1208530D03*
Y1211877D03*
Y1215223D03*
Y1218570D03*
Y1221916D03*
Y1225263D03*
Y1228609D03*
Y1231955D03*
Y1235302D03*
Y1238648D03*
Y1241995D03*
Y1245341D03*
Y1248688D03*
Y1252034D03*
Y1255381D03*
Y1258727D03*
Y1262074D03*
Y1265420D03*
X1008191Y766798D03*
Y770144D03*
Y773491D03*
Y776837D03*
Y780184D03*
Y783530D03*
Y786877D03*
Y790223D03*
Y793570D03*
Y796916D03*
Y800263D03*
Y803609D03*
Y806955D03*
Y810302D03*
Y813648D03*
Y816995D03*
Y820341D03*
Y823688D03*
Y827034D03*
Y830381D03*
Y833727D03*
Y837074D03*
Y840420D03*
Y843766D03*
Y847113D03*
Y850459D03*
Y853806D03*
Y857152D03*
Y860499D03*
Y863845D03*
Y867192D03*
Y870538D03*
Y873885D03*
Y877231D03*
Y880577D03*
Y883924D03*
Y887270D03*
Y890617D03*
Y893963D03*
Y897310D03*
Y900656D03*
Y904003D03*
Y907349D03*
Y910696D03*
Y914042D03*
Y917389D03*
Y920735D03*
Y924081D03*
Y927428D03*
Y930774D03*
Y934121D03*
Y937467D03*
Y940814D03*
Y944160D03*
Y947507D03*
Y950853D03*
Y954200D03*
Y957546D03*
Y960892D03*
Y964239D03*
Y967585D03*
Y970932D03*
Y974278D03*
Y977625D03*
Y980971D03*
Y984318D03*
Y987664D03*
Y991011D03*
Y994357D03*
Y1017782D03*
Y1021129D03*
Y1024475D03*
Y1027822D03*
Y1031168D03*
Y1034515D03*
Y1037861D03*
Y1041207D03*
Y1044554D03*
Y1047900D03*
Y1051247D03*
Y1054593D03*
Y1057940D03*
Y1061286D03*
Y1064633D03*
Y1067979D03*
Y1071326D03*
Y1074672D03*
Y1078018D03*
Y1081365D03*
Y1084711D03*
Y1088058D03*
Y1091404D03*
Y1094751D03*
Y1098097D03*
Y1101444D03*
Y1104790D03*
Y1108137D03*
Y1111483D03*
Y1114829D03*
Y1118176D03*
Y1121522D03*
Y1124869D03*
Y1128215D03*
Y1131562D03*
Y1134908D03*
Y1138255D03*
Y1141601D03*
Y1144948D03*
Y1148294D03*
Y1151641D03*
Y1154987D03*
Y1158333D03*
Y1161680D03*
Y1165026D03*
Y1168373D03*
Y1171719D03*
Y1175066D03*
Y1178412D03*
Y1181759D03*
Y1185105D03*
Y1188452D03*
Y1191798D03*
Y1195144D03*
Y1198491D03*
Y1201837D03*
Y1205184D03*
Y1208530D03*
Y1211877D03*
Y1215223D03*
Y1218570D03*
Y1221916D03*
Y1225263D03*
Y1228609D03*
Y1231955D03*
Y1235302D03*
Y1238648D03*
Y1241995D03*
Y1245341D03*
Y1248688D03*
Y1252034D03*
Y1255381D03*
Y1258727D03*
Y1262074D03*
Y1265420D03*
X1037891Y766798D03*
Y770144D03*
X1024333Y766798D03*
Y770144D03*
X1037891Y773491D03*
Y776837D03*
Y780184D03*
Y783530D03*
Y786877D03*
X1024333Y773491D03*
Y776837D03*
Y780184D03*
Y783530D03*
Y786877D03*
X1037891Y790223D03*
Y793570D03*
Y796916D03*
Y800263D03*
Y803609D03*
X1024333Y790223D03*
Y793570D03*
Y796916D03*
Y800263D03*
Y803609D03*
X1037891Y806955D03*
Y810302D03*
Y813648D03*
Y816995D03*
Y820341D03*
X1024333Y806955D03*
Y810302D03*
Y813648D03*
Y816995D03*
Y820341D03*
X1037891Y823688D03*
Y827034D03*
Y830381D03*
Y833727D03*
X1024333Y823688D03*
Y827034D03*
Y830381D03*
Y833727D03*
X1037891Y837074D03*
Y840420D03*
Y843766D03*
Y847113D03*
Y850459D03*
X1024333Y837074D03*
Y840420D03*
Y843766D03*
Y847113D03*
Y850459D03*
X1037891Y853806D03*
Y857152D03*
Y860499D03*
Y863845D03*
Y867192D03*
X1024333Y853806D03*
Y857152D03*
Y860499D03*
Y863845D03*
Y867192D03*
X1037891Y870538D03*
Y873885D03*
Y877231D03*
Y880577D03*
Y883924D03*
X1024333Y870538D03*
Y873885D03*
Y877231D03*
Y880577D03*
Y883924D03*
X1037891Y887270D03*
Y890617D03*
Y893963D03*
Y897310D03*
Y900656D03*
X1024333Y887270D03*
Y890617D03*
Y893963D03*
Y897310D03*
Y900656D03*
X1037891Y904003D03*
Y907349D03*
Y910696D03*
Y914042D03*
Y917389D03*
X1024333Y904003D03*
Y907349D03*
Y910696D03*
Y914042D03*
Y917389D03*
X1037891Y920735D03*
Y924081D03*
Y927428D03*
Y930774D03*
Y934121D03*
X1024333Y920735D03*
Y924081D03*
Y927428D03*
Y930774D03*
Y934121D03*
X1037891Y937467D03*
Y940814D03*
Y944160D03*
Y947507D03*
X1024333Y937467D03*
Y940814D03*
Y944160D03*
Y947507D03*
X1037891Y950853D03*
Y954200D03*
Y957546D03*
Y960892D03*
Y964239D03*
X1024333Y950853D03*
Y954200D03*
Y957546D03*
Y960892D03*
Y964239D03*
X1037891Y967585D03*
Y970932D03*
Y974278D03*
Y977625D03*
Y980971D03*
X1024333Y967585D03*
Y970932D03*
Y974278D03*
Y977625D03*
Y980971D03*
X1037891Y984318D03*
Y987664D03*
Y991011D03*
Y994357D03*
X1024333Y984318D03*
Y987664D03*
Y991011D03*
Y994357D03*
X1037891Y1017782D03*
Y1021129D03*
Y1024475D03*
Y1027822D03*
Y1031168D03*
X1024333Y1017782D03*
Y1021129D03*
Y1024475D03*
Y1027822D03*
Y1031168D03*
X1037891Y1034515D03*
Y1037861D03*
Y1041207D03*
Y1044554D03*
Y1047900D03*
X1024333Y1034515D03*
Y1037861D03*
Y1041207D03*
Y1044554D03*
Y1047900D03*
X1037891Y1051247D03*
Y1054593D03*
Y1057940D03*
Y1061286D03*
X1024333Y1051247D03*
Y1054593D03*
Y1057940D03*
Y1061286D03*
X1037891Y1064633D03*
Y1067979D03*
Y1071326D03*
Y1074672D03*
Y1078018D03*
X1024333Y1064633D03*
Y1067979D03*
Y1071326D03*
Y1074672D03*
Y1078018D03*
X1037891Y1081365D03*
Y1084711D03*
Y1088058D03*
Y1091404D03*
Y1094751D03*
X1024333Y1081365D03*
Y1084711D03*
Y1088058D03*
Y1091404D03*
Y1094751D03*
X1037891Y1098097D03*
Y1101444D03*
Y1104790D03*
Y1108137D03*
Y1111483D03*
X1024333Y1098097D03*
Y1101444D03*
Y1104790D03*
Y1108137D03*
Y1111483D03*
X1037891Y1114829D03*
Y1118176D03*
Y1121522D03*
Y1124869D03*
Y1128215D03*
X1024333Y1114829D03*
Y1118176D03*
Y1121522D03*
Y1124869D03*
Y1128215D03*
X1037891Y1131562D03*
Y1134908D03*
Y1138255D03*
Y1141601D03*
Y1144948D03*
X1024333Y1131562D03*
Y1134908D03*
Y1138255D03*
Y1141601D03*
Y1144948D03*
X1037891Y1148294D03*
Y1151641D03*
Y1154987D03*
Y1158333D03*
Y1161680D03*
X1024333Y1148294D03*
Y1151641D03*
Y1154987D03*
Y1158333D03*
Y1161680D03*
X1037891Y1165026D03*
Y1168373D03*
Y1171719D03*
Y1175066D03*
X1024333Y1165026D03*
Y1168373D03*
Y1171719D03*
Y1175066D03*
X1037891Y1178412D03*
Y1181759D03*
Y1185105D03*
Y1188452D03*
Y1191798D03*
X1024333Y1178412D03*
Y1181759D03*
Y1185105D03*
Y1188452D03*
Y1191798D03*
X1037891Y1195144D03*
Y1198491D03*
Y1201837D03*
Y1205184D03*
Y1208530D03*
X1024333Y1195144D03*
Y1198491D03*
Y1201837D03*
Y1205184D03*
Y1208530D03*
X1037891Y1211877D03*
Y1215223D03*
Y1218570D03*
Y1221916D03*
Y1225263D03*
X1024333Y1211877D03*
Y1215223D03*
Y1218570D03*
Y1221916D03*
Y1225263D03*
X1037891Y1228609D03*
Y1231955D03*
Y1235302D03*
Y1238648D03*
Y1241995D03*
X1024333Y1228609D03*
Y1231955D03*
Y1235302D03*
Y1238648D03*
Y1241995D03*
X1037891Y1245341D03*
Y1248688D03*
Y1252034D03*
Y1255381D03*
Y1258727D03*
X1024333Y1245341D03*
Y1248688D03*
Y1252034D03*
Y1255381D03*
Y1258727D03*
X1037891Y1262074D03*
Y1265420D03*
X1024333Y1262074D03*
Y1265420D03*
X1054033Y766798D03*
Y770144D03*
Y773491D03*
Y776837D03*
Y780184D03*
Y783530D03*
Y786877D03*
Y790223D03*
Y793570D03*
Y796916D03*
Y800263D03*
Y803609D03*
Y806955D03*
Y810302D03*
Y813648D03*
Y816995D03*
Y820341D03*
Y823688D03*
Y827034D03*
Y830381D03*
Y833727D03*
Y837074D03*
Y840420D03*
Y843766D03*
Y847113D03*
Y850459D03*
Y853806D03*
Y857152D03*
Y860499D03*
Y863845D03*
Y867192D03*
Y870538D03*
Y873885D03*
Y877231D03*
Y880577D03*
Y883924D03*
Y887270D03*
Y890617D03*
Y893963D03*
Y897310D03*
Y900656D03*
Y904003D03*
Y907349D03*
Y910696D03*
Y914042D03*
Y917389D03*
Y920735D03*
Y924081D03*
Y927428D03*
Y930774D03*
Y934121D03*
Y937467D03*
Y940814D03*
Y944160D03*
Y947507D03*
Y950853D03*
Y954200D03*
Y957546D03*
Y960892D03*
Y964239D03*
Y967585D03*
Y970932D03*
Y974278D03*
Y977625D03*
Y980971D03*
Y984318D03*
Y987664D03*
Y991011D03*
Y994357D03*
Y1017782D03*
Y1021129D03*
Y1024475D03*
Y1027822D03*
Y1031168D03*
Y1034515D03*
Y1037861D03*
Y1041207D03*
Y1044554D03*
Y1047900D03*
Y1051247D03*
Y1054593D03*
Y1057940D03*
Y1061286D03*
Y1064633D03*
Y1067979D03*
Y1071326D03*
Y1074672D03*
Y1078018D03*
Y1081365D03*
Y1084711D03*
Y1088058D03*
Y1091404D03*
Y1094751D03*
Y1098097D03*
Y1101444D03*
Y1104790D03*
Y1108137D03*
Y1111483D03*
Y1114829D03*
Y1118176D03*
Y1121522D03*
Y1124869D03*
Y1128215D03*
Y1131562D03*
Y1134908D03*
Y1138255D03*
Y1141601D03*
Y1144948D03*
Y1148294D03*
Y1151641D03*
Y1154987D03*
Y1158333D03*
Y1161680D03*
Y1165026D03*
Y1168373D03*
Y1171719D03*
Y1175066D03*
Y1178412D03*
Y1181759D03*
Y1185105D03*
Y1188452D03*
Y1191798D03*
Y1195144D03*
Y1198491D03*
Y1201837D03*
Y1205184D03*
Y1208530D03*
Y1211877D03*
Y1215223D03*
Y1218570D03*
Y1221916D03*
Y1225263D03*
Y1228609D03*
Y1231955D03*
Y1235302D03*
Y1238648D03*
Y1241995D03*
Y1245341D03*
Y1248688D03*
Y1252034D03*
Y1255381D03*
Y1258727D03*
Y1262074D03*
Y1265420D03*
X1067591Y766798D03*
Y770144D03*
Y773491D03*
Y776837D03*
Y780184D03*
Y783530D03*
Y786877D03*
Y790223D03*
Y793570D03*
Y796916D03*
Y800263D03*
Y803609D03*
Y806955D03*
Y810302D03*
Y813648D03*
Y816995D03*
Y820341D03*
Y823688D03*
Y827034D03*
Y830381D03*
Y833727D03*
Y837074D03*
Y840420D03*
Y843766D03*
Y847113D03*
Y850459D03*
Y853806D03*
Y857152D03*
Y860499D03*
Y863845D03*
Y867192D03*
Y870538D03*
Y873885D03*
Y877231D03*
Y880577D03*
Y883924D03*
Y887270D03*
Y890617D03*
Y893963D03*
Y897310D03*
Y900656D03*
Y904003D03*
Y907349D03*
Y910696D03*
Y914042D03*
Y917389D03*
Y920735D03*
Y924081D03*
Y927428D03*
Y930774D03*
Y934121D03*
Y937467D03*
Y940814D03*
Y944160D03*
Y947507D03*
Y950853D03*
Y954200D03*
Y957546D03*
Y960892D03*
Y964239D03*
Y967585D03*
Y970932D03*
Y974278D03*
Y977625D03*
Y980971D03*
Y984318D03*
Y987664D03*
Y991011D03*
Y994357D03*
Y1017782D03*
Y1021129D03*
Y1024475D03*
Y1027822D03*
Y1031168D03*
Y1034515D03*
Y1037861D03*
Y1041207D03*
Y1044554D03*
Y1047900D03*
Y1051247D03*
Y1054593D03*
Y1057940D03*
Y1061286D03*
Y1064633D03*
Y1067979D03*
Y1071326D03*
Y1074672D03*
Y1078018D03*
Y1081365D03*
Y1084711D03*
Y1088058D03*
Y1091404D03*
Y1094751D03*
Y1098097D03*
Y1101444D03*
Y1104790D03*
Y1108137D03*
Y1111483D03*
Y1114829D03*
Y1118176D03*
Y1121522D03*
Y1124869D03*
Y1128215D03*
Y1131562D03*
Y1134908D03*
Y1138255D03*
Y1141601D03*
Y1144948D03*
Y1148294D03*
Y1151641D03*
Y1154987D03*
Y1158333D03*
Y1161680D03*
Y1165026D03*
Y1168373D03*
Y1171719D03*
Y1175066D03*
Y1178412D03*
Y1181759D03*
Y1185105D03*
Y1188452D03*
Y1191798D03*
Y1195144D03*
Y1198491D03*
Y1201837D03*
Y1205184D03*
Y1208530D03*
Y1211877D03*
Y1215223D03*
Y1218570D03*
Y1221916D03*
Y1225263D03*
Y1228609D03*
Y1231955D03*
Y1235302D03*
Y1238648D03*
Y1241995D03*
Y1245341D03*
Y1248688D03*
Y1252034D03*
Y1255381D03*
Y1258727D03*
Y1262074D03*
Y1265420D03*
X1083733Y766798D03*
Y770144D03*
Y773491D03*
Y776837D03*
Y780184D03*
Y783530D03*
Y786877D03*
Y790223D03*
Y793570D03*
Y796916D03*
Y800263D03*
Y803609D03*
Y806955D03*
Y810302D03*
Y813648D03*
Y816995D03*
Y820341D03*
Y823688D03*
Y827034D03*
Y830381D03*
Y833727D03*
Y837074D03*
Y840420D03*
Y843766D03*
Y847113D03*
Y850459D03*
Y853806D03*
Y857152D03*
Y860499D03*
Y863845D03*
Y867192D03*
Y870538D03*
Y873885D03*
Y877231D03*
Y880577D03*
Y883924D03*
Y887270D03*
Y890617D03*
Y893963D03*
Y897310D03*
Y900656D03*
Y904003D03*
Y907349D03*
Y910696D03*
Y914042D03*
Y917389D03*
Y920735D03*
Y924081D03*
Y927428D03*
Y930774D03*
Y934121D03*
Y937467D03*
Y940814D03*
Y944160D03*
Y947507D03*
Y950853D03*
Y954200D03*
Y957546D03*
Y960892D03*
Y964239D03*
Y967585D03*
Y970932D03*
Y974278D03*
Y977625D03*
Y980971D03*
Y984318D03*
Y987664D03*
Y991011D03*
Y994357D03*
Y1017782D03*
Y1021129D03*
Y1024475D03*
Y1027822D03*
Y1031168D03*
Y1034515D03*
Y1037861D03*
Y1041207D03*
Y1044554D03*
Y1047900D03*
Y1051247D03*
Y1054593D03*
Y1057940D03*
Y1061286D03*
Y1064633D03*
Y1067979D03*
Y1071326D03*
Y1074672D03*
Y1078018D03*
Y1081365D03*
Y1084711D03*
Y1088058D03*
Y1091404D03*
Y1094751D03*
Y1098097D03*
Y1101444D03*
Y1104790D03*
Y1108137D03*
Y1111483D03*
Y1114829D03*
Y1118176D03*
Y1121522D03*
Y1124869D03*
Y1128215D03*
Y1131562D03*
Y1134908D03*
Y1138255D03*
Y1141601D03*
Y1144948D03*
Y1148294D03*
Y1151641D03*
Y1154987D03*
Y1158333D03*
Y1161680D03*
Y1165026D03*
Y1168373D03*
Y1171719D03*
Y1175066D03*
Y1178412D03*
Y1181759D03*
Y1185105D03*
Y1188452D03*
Y1191798D03*
Y1195144D03*
Y1198491D03*
Y1201837D03*
Y1205184D03*
Y1208530D03*
Y1211877D03*
Y1215223D03*
Y1218570D03*
Y1221916D03*
Y1225263D03*
Y1228609D03*
Y1231955D03*
Y1235302D03*
Y1238648D03*
Y1241995D03*
Y1245341D03*
Y1248688D03*
Y1252034D03*
Y1255381D03*
Y1258727D03*
Y1262074D03*
Y1265420D03*
X1097291Y766798D03*
Y770144D03*
Y773491D03*
Y776837D03*
Y780184D03*
Y783530D03*
Y786877D03*
Y790223D03*
Y793570D03*
Y796916D03*
Y800263D03*
Y803609D03*
Y806955D03*
Y810302D03*
Y813648D03*
Y816995D03*
Y820341D03*
Y823688D03*
Y827034D03*
Y830381D03*
Y833727D03*
Y837074D03*
Y840420D03*
Y843766D03*
Y847113D03*
Y850459D03*
Y853806D03*
Y857152D03*
Y860499D03*
Y863845D03*
Y867192D03*
Y870538D03*
Y873885D03*
Y877231D03*
Y880577D03*
Y883924D03*
Y887270D03*
Y890617D03*
Y893963D03*
Y897310D03*
Y900656D03*
Y904003D03*
Y907349D03*
Y910696D03*
Y914042D03*
Y917389D03*
Y920735D03*
Y924081D03*
Y927428D03*
Y930774D03*
Y934121D03*
Y937467D03*
Y940814D03*
Y944160D03*
Y947507D03*
Y950853D03*
Y954200D03*
Y957546D03*
Y960892D03*
Y964239D03*
Y967585D03*
Y970932D03*
Y974278D03*
Y977625D03*
Y980971D03*
Y984318D03*
Y987664D03*
Y991011D03*
Y994357D03*
Y1017782D03*
Y1021129D03*
Y1024475D03*
Y1027822D03*
Y1031168D03*
Y1034515D03*
Y1037861D03*
Y1041207D03*
Y1044554D03*
Y1047900D03*
Y1051247D03*
Y1054593D03*
Y1057940D03*
Y1061286D03*
Y1064633D03*
Y1067979D03*
Y1071326D03*
Y1074672D03*
Y1078018D03*
Y1081365D03*
Y1084711D03*
Y1088058D03*
Y1091404D03*
Y1094751D03*
Y1098097D03*
Y1101444D03*
Y1104790D03*
Y1108137D03*
Y1111483D03*
Y1114829D03*
Y1118176D03*
Y1121522D03*
Y1124869D03*
Y1128215D03*
Y1131562D03*
Y1134908D03*
Y1138255D03*
Y1141601D03*
Y1144948D03*
Y1148294D03*
Y1151641D03*
Y1154987D03*
Y1158333D03*
Y1161680D03*
Y1165026D03*
Y1168373D03*
Y1171719D03*
Y1175066D03*
Y1178412D03*
Y1181759D03*
Y1185105D03*
Y1188452D03*
Y1191798D03*
Y1195144D03*
Y1198491D03*
Y1201837D03*
Y1205184D03*
Y1208530D03*
Y1211877D03*
Y1215223D03*
Y1218570D03*
Y1221916D03*
Y1225263D03*
Y1228609D03*
Y1231955D03*
Y1235302D03*
Y1238648D03*
Y1241995D03*
Y1245341D03*
Y1248688D03*
Y1252034D03*
Y1255381D03*
Y1258727D03*
Y1262074D03*
Y1265420D03*
X1113433Y766798D03*
Y770144D03*
Y773491D03*
Y776837D03*
Y780184D03*
Y783530D03*
Y786877D03*
Y790223D03*
Y793570D03*
Y796916D03*
Y800263D03*
Y803609D03*
Y806955D03*
Y810302D03*
Y813648D03*
Y816995D03*
Y820341D03*
Y823688D03*
Y827034D03*
Y830381D03*
Y833727D03*
Y837074D03*
Y840420D03*
Y843766D03*
Y847113D03*
Y850459D03*
Y853806D03*
Y857152D03*
Y860499D03*
Y863845D03*
Y867192D03*
Y870538D03*
Y873885D03*
Y877231D03*
Y880577D03*
Y883924D03*
Y887270D03*
Y890617D03*
Y893963D03*
Y897310D03*
Y900656D03*
Y904003D03*
Y907349D03*
Y910696D03*
Y914042D03*
Y917389D03*
Y920735D03*
Y924081D03*
Y927428D03*
Y930774D03*
Y934121D03*
Y937467D03*
Y940814D03*
Y944160D03*
Y947507D03*
Y950853D03*
Y954200D03*
Y957546D03*
Y960892D03*
Y964239D03*
Y967585D03*
Y970932D03*
Y974278D03*
Y977625D03*
Y980971D03*
Y984318D03*
Y987664D03*
Y991011D03*
Y994357D03*
Y1017782D03*
Y1021129D03*
Y1024475D03*
Y1027822D03*
Y1031168D03*
Y1034515D03*
Y1037861D03*
Y1041207D03*
Y1044554D03*
Y1047900D03*
Y1051247D03*
Y1054593D03*
Y1057940D03*
Y1061286D03*
Y1064633D03*
Y1067979D03*
Y1071326D03*
Y1074672D03*
Y1078018D03*
Y1081365D03*
Y1084711D03*
Y1088058D03*
Y1091404D03*
Y1094751D03*
Y1098097D03*
Y1101444D03*
Y1104790D03*
Y1108137D03*
Y1111483D03*
Y1114829D03*
Y1118176D03*
Y1121522D03*
Y1124869D03*
Y1128215D03*
Y1131562D03*
Y1134908D03*
Y1138255D03*
Y1141601D03*
Y1144948D03*
Y1148294D03*
Y1151641D03*
Y1154987D03*
Y1158333D03*
Y1161680D03*
Y1165026D03*
Y1168373D03*
Y1171719D03*
Y1175066D03*
Y1178412D03*
Y1181759D03*
Y1185105D03*
Y1188452D03*
Y1191798D03*
Y1195144D03*
Y1198491D03*
Y1201837D03*
Y1205184D03*
Y1208530D03*
Y1211877D03*
Y1215223D03*
Y1218570D03*
Y1221916D03*
Y1225263D03*
Y1228609D03*
Y1231955D03*
Y1235302D03*
Y1238648D03*
Y1241995D03*
Y1245341D03*
Y1248688D03*
Y1252034D03*
Y1255381D03*
Y1258727D03*
Y1262074D03*
Y1265420D03*
X1126991Y766798D03*
Y770144D03*
Y773491D03*
Y776837D03*
Y780184D03*
Y783530D03*
Y786877D03*
Y790223D03*
Y793570D03*
Y796916D03*
Y800263D03*
Y803609D03*
Y806955D03*
Y810302D03*
Y813648D03*
Y816995D03*
Y820341D03*
Y823688D03*
Y827034D03*
Y830381D03*
Y833727D03*
Y837074D03*
Y840420D03*
Y843766D03*
Y847113D03*
Y850459D03*
Y853806D03*
Y857152D03*
Y860499D03*
Y863845D03*
Y867192D03*
Y870538D03*
Y873885D03*
Y877231D03*
Y880577D03*
Y883924D03*
Y887270D03*
Y890617D03*
Y893963D03*
Y897310D03*
Y900656D03*
Y904003D03*
Y907349D03*
Y910696D03*
Y914042D03*
Y917389D03*
Y920735D03*
Y924081D03*
Y927428D03*
Y930774D03*
Y934121D03*
Y937467D03*
Y940814D03*
Y944160D03*
Y947507D03*
Y950853D03*
Y954200D03*
Y957546D03*
Y960892D03*
Y964239D03*
Y967585D03*
Y970932D03*
Y974278D03*
Y977625D03*
Y980971D03*
Y984318D03*
Y987664D03*
Y991011D03*
Y994357D03*
Y1017782D03*
Y1021129D03*
Y1024475D03*
Y1027822D03*
Y1031168D03*
Y1034515D03*
Y1037861D03*
Y1041207D03*
Y1044554D03*
Y1047900D03*
Y1051247D03*
Y1054593D03*
Y1057940D03*
Y1061286D03*
Y1064633D03*
Y1067979D03*
Y1071326D03*
Y1074672D03*
Y1078018D03*
Y1081365D03*
Y1084711D03*
Y1088058D03*
Y1091404D03*
Y1094751D03*
Y1098097D03*
Y1101444D03*
Y1104790D03*
Y1108137D03*
Y1111483D03*
Y1114829D03*
Y1118176D03*
Y1121522D03*
Y1124869D03*
Y1128215D03*
Y1131562D03*
Y1134908D03*
Y1138255D03*
Y1141601D03*
Y1144948D03*
Y1148294D03*
Y1151641D03*
Y1154987D03*
Y1158333D03*
Y1161680D03*
Y1165026D03*
Y1168373D03*
Y1171719D03*
Y1175066D03*
Y1178412D03*
Y1181759D03*
Y1185105D03*
Y1188452D03*
Y1191798D03*
Y1195144D03*
Y1198491D03*
Y1201837D03*
Y1205184D03*
Y1208530D03*
Y1211877D03*
Y1215223D03*
Y1218570D03*
Y1221916D03*
Y1225263D03*
Y1228609D03*
Y1231955D03*
Y1235302D03*
Y1238648D03*
Y1241995D03*
Y1245341D03*
Y1248688D03*
Y1252034D03*
Y1255381D03*
Y1258727D03*
Y1262074D03*
Y1265420D03*
X1143133Y766798D03*
Y770144D03*
Y773491D03*
Y776837D03*
Y780184D03*
Y783530D03*
Y786877D03*
Y790223D03*
Y793570D03*
Y796916D03*
Y800263D03*
Y803609D03*
Y806955D03*
Y810302D03*
Y813648D03*
Y816995D03*
Y820341D03*
Y823688D03*
Y827034D03*
Y830381D03*
Y833727D03*
Y837074D03*
Y840420D03*
Y843766D03*
Y847113D03*
Y850459D03*
Y853806D03*
Y857152D03*
Y860499D03*
Y863845D03*
Y867192D03*
Y870538D03*
Y873885D03*
Y877231D03*
Y880577D03*
Y883924D03*
Y887270D03*
Y890617D03*
Y893963D03*
Y897310D03*
Y900656D03*
Y904003D03*
Y907349D03*
Y910696D03*
Y914042D03*
Y917389D03*
Y920735D03*
Y924081D03*
Y927428D03*
Y930774D03*
Y934121D03*
Y937467D03*
Y940814D03*
Y944160D03*
Y947507D03*
Y950853D03*
Y954200D03*
Y957546D03*
Y960892D03*
Y964239D03*
Y967585D03*
Y970932D03*
Y974278D03*
Y977625D03*
Y980971D03*
Y984318D03*
Y987664D03*
Y991011D03*
Y994357D03*
Y1017782D03*
Y1021129D03*
Y1024475D03*
Y1027822D03*
Y1031168D03*
Y1034515D03*
Y1037861D03*
Y1041207D03*
Y1044554D03*
Y1047900D03*
Y1051247D03*
Y1054593D03*
Y1057940D03*
Y1061286D03*
Y1064633D03*
Y1067979D03*
Y1071326D03*
Y1074672D03*
Y1078018D03*
Y1081365D03*
Y1084711D03*
Y1088058D03*
Y1091404D03*
Y1094751D03*
Y1098097D03*
Y1101444D03*
Y1104790D03*
Y1108137D03*
Y1111483D03*
Y1114829D03*
Y1118176D03*
Y1121522D03*
Y1124869D03*
Y1128215D03*
Y1131562D03*
Y1134908D03*
Y1138255D03*
Y1141601D03*
Y1144948D03*
Y1148294D03*
Y1151641D03*
Y1154987D03*
Y1158333D03*
Y1161680D03*
Y1165026D03*
Y1168373D03*
Y1171719D03*
Y1175066D03*
Y1178412D03*
Y1181759D03*
Y1185105D03*
Y1188452D03*
Y1191798D03*
Y1195144D03*
Y1198491D03*
Y1201837D03*
Y1205184D03*
Y1208530D03*
Y1211877D03*
Y1215223D03*
Y1218570D03*
Y1221916D03*
Y1225263D03*
Y1228609D03*
Y1231955D03*
Y1235302D03*
Y1238648D03*
Y1241995D03*
Y1245341D03*
Y1248688D03*
Y1252034D03*
Y1255381D03*
Y1258727D03*
Y1262074D03*
Y1265420D03*
X1156691Y766798D03*
Y770144D03*
Y773491D03*
Y776837D03*
Y780184D03*
Y783530D03*
Y786877D03*
Y790223D03*
Y793570D03*
Y796916D03*
Y800263D03*
Y803609D03*
Y806955D03*
Y810302D03*
Y813648D03*
Y816995D03*
Y820341D03*
Y823688D03*
Y827034D03*
Y830381D03*
Y833727D03*
Y837074D03*
Y840420D03*
Y843766D03*
Y847113D03*
Y850459D03*
Y853806D03*
Y857152D03*
Y860499D03*
Y863845D03*
Y867192D03*
Y870538D03*
Y873885D03*
Y877231D03*
Y880577D03*
Y883924D03*
Y887270D03*
Y890617D03*
Y893963D03*
Y897310D03*
Y900656D03*
Y904003D03*
Y907349D03*
Y910696D03*
Y914042D03*
Y917389D03*
Y920735D03*
Y924081D03*
Y927428D03*
Y930774D03*
Y934121D03*
Y937467D03*
Y940814D03*
Y944160D03*
Y947507D03*
Y950853D03*
Y954200D03*
Y957546D03*
Y960892D03*
Y964239D03*
Y967585D03*
Y970932D03*
Y974278D03*
Y977625D03*
Y980971D03*
Y984318D03*
Y987664D03*
Y991011D03*
Y994357D03*
Y1017782D03*
Y1021129D03*
Y1024475D03*
Y1027822D03*
Y1031168D03*
Y1034515D03*
Y1037861D03*
Y1041207D03*
Y1044554D03*
Y1047900D03*
Y1051247D03*
Y1054593D03*
Y1057940D03*
Y1061286D03*
Y1064633D03*
Y1067979D03*
Y1071326D03*
Y1074672D03*
Y1078018D03*
Y1081365D03*
Y1084711D03*
Y1088058D03*
Y1091404D03*
Y1094751D03*
Y1098097D03*
Y1101444D03*
Y1104790D03*
Y1108137D03*
Y1111483D03*
Y1114829D03*
Y1118176D03*
Y1121522D03*
Y1124869D03*
Y1128215D03*
Y1131562D03*
Y1134908D03*
Y1138255D03*
Y1141601D03*
Y1144948D03*
Y1148294D03*
Y1151641D03*
Y1154987D03*
Y1158333D03*
Y1161680D03*
Y1165026D03*
Y1168373D03*
Y1171719D03*
Y1175066D03*
Y1178412D03*
Y1181759D03*
Y1185105D03*
Y1188452D03*
Y1191798D03*
Y1195144D03*
Y1198491D03*
Y1201837D03*
Y1205184D03*
Y1208530D03*
Y1211877D03*
Y1215223D03*
Y1218570D03*
Y1221916D03*
Y1225263D03*
Y1228609D03*
Y1231955D03*
Y1235302D03*
Y1238648D03*
Y1241995D03*
Y1245341D03*
Y1248688D03*
Y1252034D03*
Y1255381D03*
Y1258727D03*
Y1262074D03*
Y1265420D03*
X1186391Y766798D03*
Y770144D03*
X1172833Y766798D03*
Y770144D03*
X1186391Y773491D03*
Y776837D03*
Y780184D03*
Y783530D03*
Y786877D03*
X1172833Y773491D03*
Y776837D03*
Y780184D03*
Y783530D03*
Y786877D03*
X1186391Y790223D03*
Y793570D03*
Y796916D03*
Y800263D03*
Y803609D03*
X1172833Y790223D03*
Y793570D03*
Y796916D03*
Y800263D03*
Y803609D03*
X1186391Y806955D03*
Y810302D03*
Y813648D03*
Y816995D03*
Y820341D03*
X1172833Y806955D03*
Y810302D03*
Y813648D03*
Y816995D03*
Y820341D03*
X1186391Y823688D03*
Y827034D03*
Y830381D03*
Y833727D03*
X1172833Y823688D03*
Y827034D03*
Y830381D03*
Y833727D03*
X1186391Y837074D03*
Y840420D03*
Y843766D03*
Y847113D03*
Y850459D03*
X1172833Y837074D03*
Y840420D03*
Y843766D03*
Y847113D03*
Y850459D03*
X1186391Y853806D03*
Y857152D03*
Y860499D03*
Y863845D03*
Y867192D03*
X1172833Y853806D03*
Y857152D03*
Y860499D03*
Y863845D03*
Y867192D03*
X1186391Y870538D03*
Y873885D03*
Y877231D03*
Y880577D03*
Y883924D03*
X1172833Y870538D03*
Y873885D03*
Y877231D03*
Y880577D03*
Y883924D03*
X1186391Y887270D03*
Y890617D03*
Y893963D03*
Y897310D03*
Y900656D03*
X1172833Y887270D03*
Y890617D03*
Y893963D03*
Y897310D03*
Y900656D03*
X1186391Y904003D03*
Y907349D03*
Y910696D03*
Y914042D03*
Y917389D03*
X1172833Y904003D03*
Y907349D03*
Y910696D03*
Y914042D03*
Y917389D03*
X1186391Y920735D03*
Y924081D03*
Y927428D03*
Y930774D03*
Y934121D03*
X1172833Y920735D03*
Y924081D03*
Y927428D03*
Y930774D03*
Y934121D03*
X1186391Y937467D03*
Y940814D03*
Y944160D03*
Y947507D03*
X1172833Y937467D03*
Y940814D03*
Y944160D03*
Y947507D03*
X1186391Y950853D03*
Y954200D03*
Y957546D03*
Y960892D03*
Y964239D03*
X1172833Y950853D03*
Y954200D03*
Y957546D03*
Y960892D03*
Y964239D03*
X1186391Y967585D03*
Y970932D03*
Y974278D03*
Y977625D03*
Y980971D03*
X1172833Y967585D03*
Y970932D03*
Y974278D03*
Y977625D03*
Y980971D03*
X1186391Y984318D03*
Y987664D03*
Y991011D03*
Y994357D03*
X1172833Y984318D03*
Y987664D03*
Y991011D03*
Y994357D03*
X1186391Y1017782D03*
Y1021129D03*
Y1024475D03*
Y1027822D03*
Y1031168D03*
X1172833Y1017782D03*
Y1021129D03*
Y1024475D03*
Y1027822D03*
Y1031168D03*
X1186391Y1034515D03*
Y1037861D03*
Y1041207D03*
Y1044554D03*
Y1047900D03*
X1172833Y1034515D03*
Y1037861D03*
Y1041207D03*
Y1044554D03*
Y1047900D03*
X1186391Y1051247D03*
Y1054593D03*
Y1057940D03*
Y1061286D03*
X1172833Y1051247D03*
Y1054593D03*
Y1057940D03*
Y1061286D03*
X1186391Y1064633D03*
Y1067979D03*
Y1071326D03*
Y1074672D03*
Y1078018D03*
X1172833Y1064633D03*
Y1067979D03*
Y1071326D03*
Y1074672D03*
Y1078018D03*
X1186391Y1081365D03*
Y1084711D03*
Y1088058D03*
Y1091404D03*
Y1094751D03*
X1172833Y1081365D03*
Y1084711D03*
Y1088058D03*
Y1091404D03*
Y1094751D03*
X1186391Y1098097D03*
Y1101444D03*
Y1104790D03*
Y1108137D03*
Y1111483D03*
X1172833Y1098097D03*
Y1101444D03*
Y1104790D03*
Y1108137D03*
Y1111483D03*
X1186391Y1114829D03*
Y1118176D03*
Y1121522D03*
Y1124869D03*
Y1128215D03*
X1172833Y1114829D03*
Y1118176D03*
Y1121522D03*
Y1124869D03*
Y1128215D03*
X1186391Y1131562D03*
Y1134908D03*
Y1138255D03*
Y1141601D03*
Y1144948D03*
X1172833Y1131562D03*
Y1134908D03*
Y1138255D03*
Y1141601D03*
Y1144948D03*
X1186391Y1148294D03*
Y1151641D03*
Y1154987D03*
Y1158333D03*
Y1161680D03*
X1172833Y1148294D03*
Y1151641D03*
Y1154987D03*
Y1158333D03*
Y1161680D03*
X1186391Y1165026D03*
Y1168373D03*
Y1171719D03*
Y1175066D03*
X1172833Y1165026D03*
Y1168373D03*
Y1171719D03*
Y1175066D03*
X1186391Y1178412D03*
Y1181759D03*
Y1185105D03*
Y1188452D03*
Y1191798D03*
X1172833Y1178412D03*
Y1181759D03*
Y1185105D03*
Y1188452D03*
Y1191798D03*
X1186391Y1195144D03*
Y1198491D03*
Y1201837D03*
Y1205184D03*
Y1208530D03*
X1172833Y1195144D03*
Y1198491D03*
Y1201837D03*
Y1205184D03*
Y1208530D03*
X1186391Y1211877D03*
Y1215223D03*
Y1218570D03*
Y1221916D03*
Y1225263D03*
X1172833Y1211877D03*
Y1215223D03*
Y1218570D03*
Y1221916D03*
Y1225263D03*
X1186391Y1228609D03*
Y1231955D03*
Y1235302D03*
Y1238648D03*
Y1241995D03*
X1172833Y1228609D03*
Y1231955D03*
Y1235302D03*
Y1238648D03*
Y1241995D03*
X1186391Y1245341D03*
Y1248688D03*
Y1252034D03*
Y1255381D03*
Y1258727D03*
X1172833Y1245341D03*
Y1248688D03*
Y1252034D03*
Y1255381D03*
Y1258727D03*
X1186391Y1262074D03*
Y1265420D03*
X1172833Y1262074D03*
Y1265420D03*
X1202533Y766798D03*
Y770144D03*
Y773491D03*
Y776837D03*
Y780184D03*
Y783530D03*
Y786877D03*
Y790223D03*
Y793570D03*
Y796916D03*
Y800263D03*
Y803609D03*
Y806955D03*
Y810302D03*
Y813648D03*
Y816995D03*
Y820341D03*
Y823688D03*
Y827034D03*
Y830381D03*
Y833727D03*
Y837074D03*
Y840420D03*
Y843766D03*
Y847113D03*
Y850459D03*
Y853806D03*
Y857152D03*
Y860499D03*
Y863845D03*
Y867192D03*
Y870538D03*
Y873885D03*
Y877231D03*
Y880577D03*
Y883924D03*
Y887270D03*
Y890617D03*
Y893963D03*
Y897310D03*
Y900656D03*
Y904003D03*
Y907349D03*
Y910696D03*
Y914042D03*
Y917389D03*
Y920735D03*
Y924081D03*
Y927428D03*
Y930774D03*
Y934121D03*
Y937467D03*
Y940814D03*
Y944160D03*
Y947507D03*
Y950853D03*
Y954200D03*
Y957546D03*
Y960892D03*
Y964239D03*
Y967585D03*
Y970932D03*
Y974278D03*
Y977625D03*
Y980971D03*
Y984318D03*
Y987664D03*
Y991011D03*
Y994357D03*
Y1017782D03*
Y1021129D03*
Y1024475D03*
Y1027822D03*
Y1031168D03*
Y1034515D03*
Y1037861D03*
Y1041207D03*
Y1044554D03*
Y1047900D03*
Y1051247D03*
Y1054593D03*
Y1057940D03*
Y1061286D03*
Y1064633D03*
Y1067979D03*
Y1071326D03*
Y1074672D03*
Y1078018D03*
Y1081365D03*
Y1084711D03*
Y1088058D03*
Y1091404D03*
Y1094751D03*
Y1098097D03*
Y1101444D03*
Y1104790D03*
Y1108137D03*
Y1111483D03*
Y1114829D03*
Y1118176D03*
Y1121522D03*
Y1124869D03*
Y1128215D03*
Y1131562D03*
Y1134908D03*
Y1138255D03*
Y1141601D03*
Y1144948D03*
Y1148294D03*
Y1151641D03*
Y1154987D03*
Y1158333D03*
Y1161680D03*
Y1165026D03*
Y1168373D03*
Y1171719D03*
Y1175066D03*
Y1178412D03*
Y1181759D03*
Y1185105D03*
Y1188452D03*
Y1191798D03*
Y1195144D03*
Y1198491D03*
Y1201837D03*
Y1205184D03*
Y1208530D03*
Y1211877D03*
Y1215223D03*
Y1218570D03*
Y1221916D03*
Y1225263D03*
Y1228609D03*
Y1231955D03*
Y1235302D03*
Y1238648D03*
Y1241995D03*
Y1245341D03*
Y1248688D03*
Y1252034D03*
Y1255381D03*
Y1258727D03*
Y1262074D03*
Y1265420D03*
X1216091Y766798D03*
Y770144D03*
Y773491D03*
Y776837D03*
Y780184D03*
Y783530D03*
Y786877D03*
Y790223D03*
Y793570D03*
Y796916D03*
Y800263D03*
Y803609D03*
Y806955D03*
Y810302D03*
Y813648D03*
Y816995D03*
Y820341D03*
Y823688D03*
Y827034D03*
Y830381D03*
Y833727D03*
Y837074D03*
Y840420D03*
Y843766D03*
Y847113D03*
Y850459D03*
Y853806D03*
Y857152D03*
Y860499D03*
Y863845D03*
Y867192D03*
Y870538D03*
Y873885D03*
Y877231D03*
Y880577D03*
Y883924D03*
Y887270D03*
Y890617D03*
Y893963D03*
Y897310D03*
Y900656D03*
Y904003D03*
Y907349D03*
Y910696D03*
Y914042D03*
Y917389D03*
Y920735D03*
Y924081D03*
Y927428D03*
Y930774D03*
Y934121D03*
Y937467D03*
Y940814D03*
Y944160D03*
Y947507D03*
Y950853D03*
Y954200D03*
Y957546D03*
Y960892D03*
Y964239D03*
Y967585D03*
Y970932D03*
Y974278D03*
Y977625D03*
Y980971D03*
Y984318D03*
Y987664D03*
Y991011D03*
Y994357D03*
Y1017782D03*
Y1021129D03*
Y1024475D03*
Y1027822D03*
Y1031168D03*
Y1034515D03*
Y1037861D03*
Y1041207D03*
Y1044554D03*
Y1047900D03*
Y1051247D03*
Y1054593D03*
Y1057940D03*
Y1061286D03*
Y1064633D03*
Y1067979D03*
Y1071326D03*
Y1074672D03*
Y1078018D03*
Y1081365D03*
Y1084711D03*
Y1088058D03*
Y1091404D03*
Y1094751D03*
Y1098097D03*
Y1101444D03*
Y1104790D03*
Y1108137D03*
Y1111483D03*
Y1114829D03*
Y1118176D03*
Y1121522D03*
Y1124869D03*
Y1128215D03*
Y1131562D03*
Y1134908D03*
Y1138255D03*
Y1141601D03*
Y1144948D03*
Y1148294D03*
Y1151641D03*
Y1154987D03*
Y1158333D03*
Y1161680D03*
Y1165026D03*
Y1168373D03*
Y1171719D03*
Y1175066D03*
Y1178412D03*
Y1181759D03*
Y1185105D03*
Y1188452D03*
Y1191798D03*
Y1195144D03*
Y1198491D03*
Y1201837D03*
Y1205184D03*
Y1208530D03*
Y1211877D03*
Y1215223D03*
Y1218570D03*
Y1221916D03*
Y1225263D03*
Y1228609D03*
Y1231955D03*
Y1235302D03*
Y1238648D03*
Y1241995D03*
Y1245341D03*
Y1248688D03*
Y1252034D03*
Y1255381D03*
Y1258727D03*
Y1262074D03*
Y1265420D03*
X1232233Y766798D03*
Y770144D03*
Y773491D03*
Y776837D03*
Y780184D03*
Y783530D03*
Y786877D03*
Y790223D03*
Y793570D03*
Y796916D03*
Y800263D03*
Y803609D03*
Y806955D03*
Y810302D03*
Y813648D03*
Y816995D03*
Y820341D03*
Y823688D03*
Y827034D03*
Y830381D03*
Y833727D03*
Y837074D03*
Y840420D03*
Y843766D03*
Y847113D03*
Y850459D03*
Y853806D03*
Y857152D03*
Y860499D03*
Y863845D03*
Y867192D03*
Y870538D03*
Y873885D03*
Y877231D03*
Y880577D03*
Y883924D03*
Y887270D03*
Y890617D03*
Y893963D03*
Y897310D03*
Y900656D03*
Y904003D03*
Y907349D03*
Y910696D03*
Y914042D03*
Y917389D03*
Y920735D03*
Y924081D03*
Y927428D03*
Y930774D03*
Y934121D03*
Y937467D03*
Y940814D03*
Y944160D03*
Y947507D03*
Y950853D03*
Y954200D03*
Y957546D03*
Y960892D03*
Y964239D03*
Y967585D03*
Y970932D03*
Y974278D03*
Y977625D03*
Y980971D03*
Y984318D03*
Y987664D03*
Y991011D03*
Y994357D03*
Y1017782D03*
Y1021129D03*
Y1024475D03*
Y1027822D03*
Y1031168D03*
Y1034515D03*
Y1037861D03*
Y1041207D03*
Y1044554D03*
Y1047900D03*
Y1051247D03*
Y1054593D03*
Y1057940D03*
Y1061286D03*
Y1064633D03*
Y1067979D03*
Y1071326D03*
Y1074672D03*
Y1078018D03*
Y1081365D03*
Y1084711D03*
Y1088058D03*
Y1091404D03*
Y1094751D03*
Y1098097D03*
Y1101444D03*
Y1104790D03*
Y1108137D03*
Y1111483D03*
Y1114829D03*
Y1118176D03*
Y1121522D03*
Y1124869D03*
Y1128215D03*
Y1131562D03*
Y1134908D03*
Y1138255D03*
Y1141601D03*
Y1144948D03*
Y1148294D03*
Y1151641D03*
Y1154987D03*
Y1158333D03*
Y1161680D03*
Y1165026D03*
Y1168373D03*
Y1171719D03*
Y1175066D03*
Y1178412D03*
Y1181759D03*
Y1185105D03*
Y1188452D03*
Y1191798D03*
Y1195144D03*
Y1198491D03*
Y1201837D03*
Y1205184D03*
Y1208530D03*
Y1211877D03*
Y1215223D03*
Y1218570D03*
Y1221916D03*
Y1225263D03*
Y1228609D03*
Y1231955D03*
Y1235302D03*
Y1238648D03*
Y1241995D03*
Y1245341D03*
Y1248688D03*
Y1252034D03*
Y1255381D03*
Y1258727D03*
Y1262074D03*
Y1265420D03*
X1601391Y766798D03*
Y770144D03*
Y773491D03*
Y776837D03*
Y780184D03*
Y783530D03*
Y786877D03*
Y790223D03*
Y793570D03*
Y796916D03*
Y800263D03*
Y803609D03*
Y806955D03*
Y810302D03*
Y813648D03*
Y816995D03*
Y820341D03*
Y823688D03*
Y827034D03*
Y830381D03*
Y833727D03*
Y837074D03*
Y840420D03*
Y843766D03*
Y847113D03*
Y850459D03*
Y853806D03*
Y857152D03*
Y860499D03*
Y863845D03*
Y867192D03*
Y870538D03*
Y873885D03*
Y877231D03*
Y880577D03*
Y883924D03*
Y887270D03*
Y890617D03*
Y893963D03*
Y897310D03*
Y900656D03*
Y904003D03*
Y907349D03*
Y910696D03*
Y914042D03*
Y917389D03*
Y920735D03*
Y924081D03*
Y927428D03*
Y930774D03*
Y934121D03*
Y937467D03*
Y940814D03*
Y944160D03*
Y947507D03*
Y950853D03*
Y954200D03*
Y957546D03*
Y960892D03*
Y964239D03*
Y967585D03*
Y970932D03*
Y974278D03*
Y977625D03*
Y980971D03*
Y984318D03*
Y987664D03*
Y991011D03*
Y994357D03*
Y1017782D03*
Y1021129D03*
Y1024475D03*
Y1027822D03*
Y1031168D03*
Y1034515D03*
Y1037861D03*
Y1041207D03*
Y1044554D03*
Y1047900D03*
Y1051247D03*
Y1054593D03*
Y1057940D03*
Y1061286D03*
Y1064633D03*
Y1067979D03*
Y1071326D03*
Y1074672D03*
Y1078018D03*
Y1081365D03*
Y1084711D03*
Y1088058D03*
Y1091404D03*
Y1094751D03*
Y1098097D03*
Y1101444D03*
Y1104790D03*
Y1108137D03*
Y1111483D03*
Y1114829D03*
Y1118176D03*
Y1121522D03*
Y1124869D03*
Y1128215D03*
Y1131562D03*
Y1134908D03*
Y1138255D03*
Y1141601D03*
Y1144948D03*
Y1148294D03*
Y1151641D03*
Y1154987D03*
Y1158333D03*
Y1161680D03*
Y1165026D03*
Y1168373D03*
Y1171719D03*
Y1175066D03*
Y1178412D03*
Y1181759D03*
Y1185105D03*
Y1188452D03*
Y1191798D03*
Y1195144D03*
Y1198491D03*
Y1201837D03*
Y1205184D03*
Y1208530D03*
Y1211877D03*
Y1215223D03*
Y1218570D03*
Y1221916D03*
Y1225263D03*
Y1228609D03*
Y1231955D03*
Y1235302D03*
Y1238648D03*
Y1241995D03*
Y1245341D03*
Y1248688D03*
Y1252034D03*
Y1255381D03*
Y1258727D03*
Y1262074D03*
Y1265420D03*
X1617533Y766798D03*
Y770144D03*
Y773491D03*
Y776837D03*
Y780184D03*
Y783530D03*
Y786877D03*
Y790223D03*
Y793570D03*
Y796916D03*
Y800263D03*
Y803609D03*
Y806955D03*
Y810302D03*
Y813648D03*
Y816995D03*
Y820341D03*
Y823688D03*
Y827034D03*
Y830381D03*
Y833727D03*
Y837074D03*
Y840420D03*
Y843766D03*
Y847113D03*
Y850459D03*
Y853806D03*
Y857152D03*
Y860499D03*
Y863845D03*
Y867192D03*
Y870538D03*
Y873885D03*
Y877231D03*
Y880577D03*
Y883924D03*
Y887270D03*
Y890617D03*
Y893963D03*
Y897310D03*
Y900656D03*
Y904003D03*
Y907349D03*
Y910696D03*
Y914042D03*
Y917389D03*
Y920735D03*
Y924081D03*
Y927428D03*
Y930774D03*
Y934121D03*
Y937467D03*
Y940814D03*
Y944160D03*
Y947507D03*
Y950853D03*
Y954200D03*
Y957546D03*
Y960892D03*
Y964239D03*
Y967585D03*
Y970932D03*
Y974278D03*
Y977625D03*
Y980971D03*
Y984318D03*
Y987664D03*
Y991011D03*
Y994357D03*
Y1017782D03*
Y1021129D03*
Y1024475D03*
Y1027822D03*
Y1031168D03*
Y1034515D03*
Y1037861D03*
Y1041207D03*
Y1044554D03*
Y1047900D03*
Y1051247D03*
Y1054593D03*
Y1057940D03*
Y1061286D03*
Y1064633D03*
Y1067979D03*
Y1071326D03*
Y1074672D03*
Y1078018D03*
Y1081365D03*
Y1084711D03*
Y1088058D03*
Y1091404D03*
Y1094751D03*
Y1098097D03*
Y1101444D03*
Y1104790D03*
Y1108137D03*
Y1111483D03*
Y1114829D03*
Y1118176D03*
Y1121522D03*
Y1124869D03*
Y1128215D03*
Y1131562D03*
Y1134908D03*
Y1138255D03*
Y1141601D03*
Y1144948D03*
Y1148294D03*
Y1151641D03*
Y1154987D03*
Y1158333D03*
Y1161680D03*
Y1165026D03*
Y1168373D03*
Y1171719D03*
Y1175066D03*
Y1178412D03*
Y1181759D03*
Y1185105D03*
Y1188452D03*
Y1191798D03*
Y1195144D03*
Y1198491D03*
Y1201837D03*
Y1205184D03*
Y1208530D03*
Y1211877D03*
Y1215223D03*
Y1218570D03*
Y1221916D03*
Y1225263D03*
Y1228609D03*
Y1231955D03*
Y1235302D03*
Y1238648D03*
Y1241995D03*
Y1245341D03*
Y1248688D03*
Y1252034D03*
Y1255381D03*
Y1258727D03*
Y1262074D03*
Y1265420D03*
X1631091Y766798D03*
Y770144D03*
Y773491D03*
Y776837D03*
Y780184D03*
Y783530D03*
Y786877D03*
Y790223D03*
Y793570D03*
Y796916D03*
Y800263D03*
Y803609D03*
Y806955D03*
Y810302D03*
Y813648D03*
Y816995D03*
Y820341D03*
Y823688D03*
Y827034D03*
Y830381D03*
Y833727D03*
Y837074D03*
Y840420D03*
Y843766D03*
Y847113D03*
Y850459D03*
Y853806D03*
Y857152D03*
Y860499D03*
Y863845D03*
Y867192D03*
Y870538D03*
Y873885D03*
Y877231D03*
Y880577D03*
Y883924D03*
Y887270D03*
Y890617D03*
Y893963D03*
Y897310D03*
Y900656D03*
Y904003D03*
Y907349D03*
Y910696D03*
Y914042D03*
Y917389D03*
Y920735D03*
Y924081D03*
Y927428D03*
Y930774D03*
Y934121D03*
Y937467D03*
Y940814D03*
Y944160D03*
Y947507D03*
Y950853D03*
Y954200D03*
Y957546D03*
Y960892D03*
Y964239D03*
Y967585D03*
Y970932D03*
Y974278D03*
Y977625D03*
Y980971D03*
Y984318D03*
Y987664D03*
Y991011D03*
Y994357D03*
Y1017782D03*
Y1021129D03*
Y1024475D03*
Y1027822D03*
Y1031168D03*
Y1034515D03*
Y1037861D03*
Y1041207D03*
Y1044554D03*
Y1047900D03*
Y1051247D03*
Y1054593D03*
Y1057940D03*
Y1061286D03*
Y1064633D03*
Y1067979D03*
Y1071326D03*
Y1074672D03*
Y1078018D03*
Y1081365D03*
Y1084711D03*
Y1088058D03*
Y1091404D03*
Y1094751D03*
Y1098097D03*
Y1101444D03*
Y1104790D03*
Y1108137D03*
Y1111483D03*
Y1114829D03*
Y1118176D03*
Y1121522D03*
Y1124869D03*
Y1128215D03*
Y1131562D03*
Y1134908D03*
Y1138255D03*
Y1141601D03*
Y1144948D03*
Y1148294D03*
Y1151641D03*
Y1154987D03*
Y1158333D03*
Y1161680D03*
Y1165026D03*
Y1168373D03*
Y1171719D03*
Y1175066D03*
Y1178412D03*
Y1181759D03*
Y1185105D03*
Y1188452D03*
Y1191798D03*
Y1195144D03*
Y1198491D03*
Y1201837D03*
Y1205184D03*
Y1208530D03*
Y1211877D03*
Y1215223D03*
Y1218570D03*
Y1221916D03*
Y1225263D03*
Y1228609D03*
Y1231955D03*
Y1235302D03*
Y1238648D03*
Y1241995D03*
Y1245341D03*
Y1248688D03*
Y1252034D03*
Y1255381D03*
Y1258727D03*
Y1262074D03*
Y1265420D03*
X1647233Y766798D03*
Y770144D03*
Y773491D03*
Y776837D03*
Y780184D03*
Y783530D03*
Y786877D03*
Y790223D03*
Y793570D03*
Y796916D03*
Y800263D03*
Y803609D03*
Y806955D03*
Y810302D03*
Y813648D03*
Y816995D03*
Y820341D03*
Y823688D03*
Y827034D03*
Y830381D03*
Y833727D03*
Y837074D03*
Y840420D03*
Y843766D03*
Y847113D03*
Y850459D03*
Y853806D03*
Y857152D03*
Y860499D03*
Y863845D03*
Y867192D03*
Y870538D03*
Y873885D03*
Y877231D03*
Y880577D03*
Y883924D03*
Y887270D03*
Y890617D03*
Y893963D03*
Y897310D03*
Y900656D03*
Y904003D03*
Y907349D03*
Y910696D03*
Y914042D03*
Y917389D03*
Y920735D03*
Y924081D03*
Y927428D03*
Y930774D03*
Y934121D03*
Y937467D03*
Y940814D03*
Y944160D03*
Y947507D03*
Y950853D03*
Y954200D03*
Y957546D03*
Y960892D03*
Y964239D03*
Y967585D03*
Y970932D03*
Y974278D03*
Y977625D03*
Y980971D03*
Y984318D03*
Y987664D03*
Y991011D03*
Y994357D03*
Y1017782D03*
Y1021129D03*
Y1024475D03*
Y1027822D03*
Y1031168D03*
Y1034515D03*
Y1037861D03*
Y1041207D03*
Y1044554D03*
Y1047900D03*
Y1051247D03*
Y1054593D03*
Y1057940D03*
Y1061286D03*
Y1064633D03*
Y1067979D03*
Y1071326D03*
Y1074672D03*
Y1078018D03*
Y1081365D03*
Y1084711D03*
Y1088058D03*
Y1091404D03*
Y1094751D03*
Y1098097D03*
Y1101444D03*
Y1104790D03*
Y1108137D03*
Y1111483D03*
Y1114829D03*
Y1118176D03*
Y1121522D03*
Y1124869D03*
Y1128215D03*
Y1131562D03*
Y1134908D03*
Y1138255D03*
Y1141601D03*
Y1144948D03*
Y1148294D03*
Y1151641D03*
Y1154987D03*
Y1158333D03*
Y1161680D03*
Y1165026D03*
Y1168373D03*
Y1171719D03*
Y1175066D03*
Y1178412D03*
Y1181759D03*
Y1185105D03*
Y1188452D03*
Y1191798D03*
Y1195144D03*
Y1198491D03*
Y1201837D03*
Y1205184D03*
Y1208530D03*
Y1211877D03*
Y1215223D03*
Y1218570D03*
Y1221916D03*
Y1225263D03*
Y1228609D03*
Y1231955D03*
Y1235302D03*
Y1238648D03*
Y1241995D03*
Y1245341D03*
Y1248688D03*
Y1252034D03*
Y1255381D03*
Y1258727D03*
Y1262074D03*
Y1265420D03*
X1660791Y766798D03*
Y770144D03*
Y773491D03*
Y776837D03*
Y780184D03*
Y783530D03*
Y786877D03*
Y790223D03*
Y793570D03*
Y796916D03*
Y800263D03*
Y803609D03*
Y806955D03*
Y810302D03*
Y813648D03*
Y816995D03*
Y820341D03*
Y823688D03*
Y827034D03*
Y830381D03*
Y833727D03*
Y837074D03*
Y840420D03*
Y843766D03*
Y847113D03*
Y850459D03*
Y853806D03*
Y857152D03*
Y860499D03*
Y863845D03*
Y867192D03*
Y870538D03*
Y873885D03*
Y877231D03*
Y880577D03*
Y883924D03*
Y887270D03*
Y890617D03*
Y893963D03*
Y897310D03*
Y900656D03*
Y904003D03*
Y907349D03*
Y910696D03*
Y914042D03*
Y917389D03*
Y920735D03*
Y924081D03*
Y927428D03*
Y930774D03*
Y934121D03*
Y937467D03*
Y940814D03*
Y944160D03*
Y947507D03*
Y950853D03*
Y954200D03*
Y957546D03*
Y960892D03*
Y964239D03*
Y967585D03*
Y970932D03*
Y974278D03*
Y977625D03*
Y980971D03*
Y984318D03*
Y987664D03*
Y991011D03*
Y994357D03*
Y1017782D03*
Y1021129D03*
Y1024475D03*
Y1027822D03*
Y1031168D03*
Y1034515D03*
Y1037861D03*
Y1041207D03*
Y1044554D03*
Y1047900D03*
Y1051247D03*
Y1054593D03*
Y1057940D03*
Y1061286D03*
Y1064633D03*
Y1067979D03*
Y1071326D03*
Y1074672D03*
Y1078018D03*
Y1081365D03*
Y1084711D03*
Y1088058D03*
Y1091404D03*
Y1094751D03*
Y1098097D03*
Y1101444D03*
Y1104790D03*
Y1108137D03*
Y1111483D03*
Y1114829D03*
Y1118176D03*
Y1121522D03*
Y1124869D03*
Y1128215D03*
Y1131562D03*
Y1134908D03*
Y1138255D03*
Y1141601D03*
Y1144948D03*
Y1148294D03*
Y1151641D03*
Y1154987D03*
Y1158333D03*
Y1161680D03*
Y1165026D03*
Y1168373D03*
Y1171719D03*
Y1175066D03*
Y1178412D03*
Y1181759D03*
Y1185105D03*
Y1188452D03*
Y1191798D03*
Y1195144D03*
Y1198491D03*
Y1201837D03*
Y1205184D03*
Y1208530D03*
Y1211877D03*
Y1215223D03*
Y1218570D03*
Y1221916D03*
Y1225263D03*
Y1228609D03*
Y1231955D03*
Y1235302D03*
Y1238648D03*
Y1241995D03*
Y1245341D03*
Y1248688D03*
Y1252034D03*
Y1255381D03*
Y1258727D03*
Y1262074D03*
Y1265420D03*
X1690491Y766798D03*
Y770144D03*
X1676933Y766798D03*
Y770144D03*
X1690491Y773491D03*
Y776837D03*
Y780184D03*
Y783530D03*
Y786877D03*
X1676933Y773491D03*
Y776837D03*
Y780184D03*
Y783530D03*
Y786877D03*
X1690491Y790223D03*
Y793570D03*
Y796916D03*
Y800263D03*
Y803609D03*
X1676933Y790223D03*
Y793570D03*
Y796916D03*
Y800263D03*
Y803609D03*
X1690491Y806955D03*
Y810302D03*
Y813648D03*
Y816995D03*
Y820341D03*
X1676933Y806955D03*
Y810302D03*
Y813648D03*
Y816995D03*
Y820341D03*
X1690491Y823688D03*
Y827034D03*
Y830381D03*
Y833727D03*
X1676933Y823688D03*
Y827034D03*
Y830381D03*
Y833727D03*
X1690491Y837074D03*
Y840420D03*
Y843766D03*
Y847113D03*
Y850459D03*
X1676933Y837074D03*
Y840420D03*
Y843766D03*
Y847113D03*
Y850459D03*
X1690491Y853806D03*
Y857152D03*
Y860499D03*
Y863845D03*
Y867192D03*
X1676933Y853806D03*
Y857152D03*
Y860499D03*
Y863845D03*
Y867192D03*
X1690491Y870538D03*
Y873885D03*
Y877231D03*
Y880577D03*
Y883924D03*
X1676933Y870538D03*
Y873885D03*
Y877231D03*
Y880577D03*
Y883924D03*
X1690491Y887270D03*
Y890617D03*
Y893963D03*
Y897310D03*
Y900656D03*
X1676933Y887270D03*
Y890617D03*
Y893963D03*
Y897310D03*
Y900656D03*
X1690491Y904003D03*
Y907349D03*
Y910696D03*
Y914042D03*
Y917389D03*
X1676933Y904003D03*
Y907349D03*
Y910696D03*
Y914042D03*
Y917389D03*
X1690491Y920735D03*
Y924081D03*
Y927428D03*
Y930774D03*
Y934121D03*
X1676933Y920735D03*
Y924081D03*
Y927428D03*
Y930774D03*
Y934121D03*
X1690491Y937467D03*
Y940814D03*
Y944160D03*
Y947507D03*
X1676933Y937467D03*
Y940814D03*
Y944160D03*
Y947507D03*
X1690491Y950853D03*
Y954200D03*
Y957546D03*
Y960892D03*
Y964239D03*
X1676933Y950853D03*
Y954200D03*
Y957546D03*
Y960892D03*
Y964239D03*
X1690491Y967585D03*
Y970932D03*
Y974278D03*
Y977625D03*
Y980971D03*
X1676933Y967585D03*
Y970932D03*
Y974278D03*
Y977625D03*
Y980971D03*
X1690491Y984318D03*
Y987664D03*
Y991011D03*
Y994357D03*
X1676933Y984318D03*
Y987664D03*
Y991011D03*
Y994357D03*
X1690491Y1017782D03*
Y1021129D03*
Y1024475D03*
Y1027822D03*
Y1031168D03*
X1676933Y1017782D03*
Y1021129D03*
Y1024475D03*
Y1027822D03*
Y1031168D03*
X1690491Y1034515D03*
Y1037861D03*
Y1041207D03*
Y1044554D03*
Y1047900D03*
X1676933Y1034515D03*
Y1037861D03*
Y1041207D03*
Y1044554D03*
Y1047900D03*
X1690491Y1051247D03*
Y1054593D03*
Y1057940D03*
Y1061286D03*
X1676933Y1051247D03*
Y1054593D03*
Y1057940D03*
Y1061286D03*
X1690491Y1064633D03*
Y1067979D03*
Y1071326D03*
Y1074672D03*
Y1078018D03*
X1676933Y1064633D03*
Y1067979D03*
Y1071326D03*
Y1074672D03*
Y1078018D03*
X1690491Y1081365D03*
Y1084711D03*
Y1088058D03*
Y1091404D03*
Y1094751D03*
X1676933Y1081365D03*
Y1084711D03*
Y1088058D03*
Y1091404D03*
Y1094751D03*
X1690491Y1098097D03*
Y1101444D03*
Y1104790D03*
Y1108137D03*
Y1111483D03*
X1676933Y1098097D03*
Y1101444D03*
Y1104790D03*
Y1108137D03*
Y1111483D03*
X1690491Y1114829D03*
Y1118176D03*
Y1121522D03*
Y1124869D03*
Y1128215D03*
X1676933Y1114829D03*
Y1118176D03*
Y1121522D03*
Y1124869D03*
Y1128215D03*
X1690491Y1131562D03*
Y1134908D03*
Y1138255D03*
Y1141601D03*
Y1144948D03*
X1676933Y1131562D03*
Y1134908D03*
Y1138255D03*
Y1141601D03*
Y1144948D03*
X1690491Y1148294D03*
Y1151641D03*
Y1154987D03*
Y1158333D03*
Y1161680D03*
X1676933Y1148294D03*
Y1151641D03*
Y1154987D03*
Y1158333D03*
Y1161680D03*
X1690491Y1165026D03*
Y1168373D03*
Y1171719D03*
Y1175066D03*
X1676933Y1165026D03*
Y1168373D03*
Y1171719D03*
Y1175066D03*
X1690491Y1178412D03*
Y1181759D03*
Y1185105D03*
Y1188452D03*
Y1191798D03*
X1676933Y1178412D03*
Y1181759D03*
Y1185105D03*
Y1188452D03*
Y1191798D03*
X1690491Y1195144D03*
Y1198491D03*
Y1201837D03*
Y1205184D03*
Y1208530D03*
X1676933Y1195144D03*
Y1198491D03*
Y1201837D03*
Y1205184D03*
Y1208530D03*
X1690491Y1211877D03*
Y1215223D03*
Y1218570D03*
Y1221916D03*
Y1225263D03*
X1676933Y1211877D03*
Y1215223D03*
Y1218570D03*
Y1221916D03*
Y1225263D03*
X1690491Y1228609D03*
Y1231955D03*
Y1235302D03*
Y1238648D03*
Y1241995D03*
X1676933Y1228609D03*
Y1231955D03*
Y1235302D03*
Y1238648D03*
Y1241995D03*
X1690491Y1245341D03*
Y1248688D03*
Y1252034D03*
Y1255381D03*
Y1258727D03*
X1676933Y1245341D03*
Y1248688D03*
Y1252034D03*
Y1255381D03*
Y1258727D03*
X1690491Y1262074D03*
Y1265420D03*
X1676933Y1262074D03*
Y1265420D03*
X1706633Y766798D03*
Y770144D03*
Y773491D03*
Y776837D03*
Y780184D03*
Y783530D03*
Y786877D03*
Y790223D03*
Y793570D03*
Y796916D03*
Y800263D03*
Y803609D03*
Y806955D03*
Y810302D03*
Y813648D03*
Y816995D03*
Y820341D03*
Y823688D03*
Y827034D03*
Y830381D03*
Y833727D03*
Y837074D03*
Y840420D03*
Y843766D03*
Y847113D03*
Y850459D03*
Y853806D03*
Y857152D03*
Y860499D03*
Y863845D03*
Y867192D03*
Y870538D03*
Y873885D03*
Y877231D03*
Y880577D03*
Y883924D03*
Y887270D03*
Y890617D03*
Y893963D03*
Y897310D03*
Y900656D03*
Y904003D03*
Y907349D03*
Y910696D03*
Y914042D03*
Y917389D03*
Y920735D03*
Y924081D03*
Y927428D03*
Y930774D03*
Y934121D03*
Y937467D03*
Y940814D03*
Y944160D03*
Y947507D03*
Y950853D03*
Y954200D03*
Y957546D03*
Y960892D03*
Y964239D03*
Y967585D03*
Y970932D03*
Y974278D03*
Y977625D03*
Y980971D03*
Y984318D03*
Y987664D03*
Y991011D03*
Y994357D03*
Y1017782D03*
Y1021129D03*
Y1024475D03*
Y1027822D03*
Y1031168D03*
Y1034515D03*
Y1037861D03*
Y1041207D03*
Y1044554D03*
Y1047900D03*
Y1051247D03*
Y1054593D03*
Y1057940D03*
Y1061286D03*
Y1064633D03*
Y1067979D03*
Y1071326D03*
Y1074672D03*
Y1078018D03*
Y1081365D03*
Y1084711D03*
Y1088058D03*
Y1091404D03*
Y1094751D03*
Y1098097D03*
Y1101444D03*
Y1104790D03*
Y1108137D03*
Y1111483D03*
Y1114829D03*
Y1118176D03*
Y1121522D03*
Y1124869D03*
Y1128215D03*
Y1131562D03*
Y1134908D03*
Y1138255D03*
Y1141601D03*
Y1144948D03*
Y1148294D03*
Y1151641D03*
Y1154987D03*
Y1158333D03*
Y1161680D03*
Y1165026D03*
Y1168373D03*
Y1171719D03*
Y1175066D03*
Y1178412D03*
Y1181759D03*
Y1185105D03*
Y1188452D03*
Y1191798D03*
Y1195144D03*
Y1198491D03*
Y1201837D03*
Y1205184D03*
Y1208530D03*
Y1211877D03*
Y1215223D03*
Y1218570D03*
Y1221916D03*
Y1225263D03*
Y1228609D03*
Y1231955D03*
Y1235302D03*
Y1238648D03*
Y1241995D03*
Y1245341D03*
Y1248688D03*
Y1252034D03*
Y1255381D03*
Y1258727D03*
Y1262074D03*
Y1265420D03*
X1720191Y766798D03*
Y770144D03*
Y773491D03*
Y776837D03*
Y780184D03*
Y783530D03*
Y786877D03*
Y790223D03*
Y793570D03*
Y796916D03*
Y800263D03*
Y803609D03*
Y806955D03*
Y810302D03*
Y813648D03*
Y816995D03*
Y820341D03*
Y823688D03*
Y827034D03*
Y830381D03*
Y833727D03*
Y837074D03*
Y840420D03*
Y843766D03*
Y847113D03*
Y850459D03*
Y853806D03*
Y857152D03*
Y860499D03*
Y863845D03*
Y867192D03*
Y870538D03*
Y873885D03*
Y877231D03*
Y880577D03*
Y883924D03*
Y887270D03*
Y890617D03*
Y893963D03*
Y897310D03*
Y900656D03*
Y904003D03*
Y907349D03*
Y910696D03*
Y914042D03*
Y917389D03*
Y920735D03*
Y924081D03*
Y927428D03*
Y930774D03*
Y934121D03*
Y937467D03*
Y940814D03*
Y944160D03*
Y947507D03*
Y950853D03*
Y954200D03*
Y957546D03*
Y960892D03*
Y964239D03*
Y967585D03*
Y970932D03*
Y974278D03*
Y977625D03*
Y980971D03*
Y984318D03*
Y987664D03*
Y991011D03*
Y994357D03*
Y1017782D03*
Y1021129D03*
Y1024475D03*
Y1027822D03*
Y1031168D03*
Y1034515D03*
Y1037861D03*
Y1041207D03*
Y1044554D03*
Y1047900D03*
Y1051247D03*
Y1054593D03*
Y1057940D03*
Y1061286D03*
Y1064633D03*
Y1067979D03*
Y1071326D03*
Y1074672D03*
Y1078018D03*
Y1081365D03*
Y1084711D03*
Y1088058D03*
Y1091404D03*
Y1094751D03*
Y1098097D03*
Y1101444D03*
Y1104790D03*
Y1108137D03*
Y1111483D03*
Y1114829D03*
Y1118176D03*
Y1121522D03*
Y1124869D03*
Y1128215D03*
Y1131562D03*
Y1134908D03*
Y1138255D03*
Y1141601D03*
Y1144948D03*
Y1148294D03*
Y1151641D03*
Y1154987D03*
Y1158333D03*
Y1161680D03*
Y1165026D03*
Y1168373D03*
Y1171719D03*
Y1175066D03*
Y1178412D03*
Y1181759D03*
Y1185105D03*
Y1188452D03*
Y1191798D03*
Y1195144D03*
Y1198491D03*
Y1201837D03*
Y1205184D03*
Y1208530D03*
Y1211877D03*
Y1215223D03*
Y1218570D03*
Y1221916D03*
Y1225263D03*
Y1228609D03*
Y1231955D03*
Y1235302D03*
Y1238648D03*
Y1241995D03*
Y1245341D03*
Y1248688D03*
Y1252034D03*
Y1255381D03*
Y1258727D03*
Y1262074D03*
Y1265420D03*
X1736333Y766798D03*
Y770144D03*
Y773491D03*
Y776837D03*
Y780184D03*
Y783530D03*
Y786877D03*
Y790223D03*
Y793570D03*
Y796916D03*
Y800263D03*
Y803609D03*
Y806955D03*
Y810302D03*
Y813648D03*
Y816995D03*
Y820341D03*
Y823688D03*
Y827034D03*
Y830381D03*
Y833727D03*
Y837074D03*
Y840420D03*
Y843766D03*
Y847113D03*
Y850459D03*
Y853806D03*
Y857152D03*
Y860499D03*
Y863845D03*
Y867192D03*
Y870538D03*
Y873885D03*
Y877231D03*
Y880577D03*
Y883924D03*
Y887270D03*
Y890617D03*
Y893963D03*
Y897310D03*
Y900656D03*
Y904003D03*
Y907349D03*
Y910696D03*
Y914042D03*
Y917389D03*
Y920735D03*
Y924081D03*
Y927428D03*
Y930774D03*
Y934121D03*
Y937467D03*
Y940814D03*
Y944160D03*
Y947507D03*
Y950853D03*
Y954200D03*
Y957546D03*
Y960892D03*
Y964239D03*
Y967585D03*
Y970932D03*
Y974278D03*
Y977625D03*
Y980971D03*
Y984318D03*
Y987664D03*
Y991011D03*
Y994357D03*
Y1017782D03*
Y1021129D03*
Y1024475D03*
Y1027822D03*
Y1031168D03*
Y1034515D03*
Y1037861D03*
Y1041207D03*
Y1044554D03*
Y1047900D03*
Y1051247D03*
Y1054593D03*
Y1057940D03*
Y1061286D03*
Y1064633D03*
Y1067979D03*
Y1071326D03*
Y1074672D03*
Y1078018D03*
Y1081365D03*
Y1084711D03*
Y1088058D03*
Y1091404D03*
Y1094751D03*
Y1098097D03*
Y1101444D03*
Y1104790D03*
Y1108137D03*
Y1111483D03*
Y1114829D03*
Y1118176D03*
Y1121522D03*
Y1124869D03*
Y1128215D03*
Y1131562D03*
Y1134908D03*
Y1138255D03*
Y1141601D03*
Y1144948D03*
Y1148294D03*
Y1151641D03*
Y1154987D03*
Y1158333D03*
Y1161680D03*
Y1165026D03*
Y1168373D03*
Y1171719D03*
Y1175066D03*
Y1178412D03*
Y1181759D03*
Y1185105D03*
Y1188452D03*
Y1191798D03*
Y1195144D03*
Y1198491D03*
Y1201837D03*
Y1205184D03*
Y1208530D03*
Y1211877D03*
Y1215223D03*
Y1218570D03*
Y1221916D03*
Y1225263D03*
Y1228609D03*
Y1231955D03*
Y1235302D03*
Y1238648D03*
Y1241995D03*
Y1245341D03*
Y1248688D03*
Y1252034D03*
Y1255381D03*
Y1258727D03*
Y1262074D03*
Y1265420D03*
X1749891Y766798D03*
Y770144D03*
Y773491D03*
Y776837D03*
Y780184D03*
Y783530D03*
Y786877D03*
Y790223D03*
Y793570D03*
Y796916D03*
Y800263D03*
Y803609D03*
Y806955D03*
Y810302D03*
Y813648D03*
Y816995D03*
Y820341D03*
Y823688D03*
Y827034D03*
Y830381D03*
Y833727D03*
Y837074D03*
Y840420D03*
Y843766D03*
Y847113D03*
Y850459D03*
Y853806D03*
Y857152D03*
Y860499D03*
Y863845D03*
Y867192D03*
Y870538D03*
Y873885D03*
Y877231D03*
Y880577D03*
Y883924D03*
Y887270D03*
Y890617D03*
Y893963D03*
Y897310D03*
Y900656D03*
Y904003D03*
Y907349D03*
Y910696D03*
Y914042D03*
Y917389D03*
Y920735D03*
Y924081D03*
Y927428D03*
Y930774D03*
Y934121D03*
Y937467D03*
Y940814D03*
Y944160D03*
Y947507D03*
Y950853D03*
Y954200D03*
Y957546D03*
Y960892D03*
Y964239D03*
Y967585D03*
Y970932D03*
Y974278D03*
Y977625D03*
Y980971D03*
Y984318D03*
Y987664D03*
Y991011D03*
Y994357D03*
Y1017782D03*
Y1021129D03*
Y1024475D03*
Y1027822D03*
Y1031168D03*
Y1034515D03*
Y1037861D03*
Y1041207D03*
Y1044554D03*
Y1047900D03*
Y1051247D03*
Y1054593D03*
Y1057940D03*
Y1061286D03*
Y1064633D03*
Y1067979D03*
Y1071326D03*
Y1074672D03*
Y1078018D03*
Y1081365D03*
Y1084711D03*
Y1088058D03*
Y1091404D03*
Y1094751D03*
Y1098097D03*
Y1101444D03*
Y1104790D03*
Y1108137D03*
Y1111483D03*
Y1114829D03*
Y1118176D03*
Y1121522D03*
Y1124869D03*
Y1128215D03*
Y1131562D03*
Y1134908D03*
Y1138255D03*
Y1141601D03*
Y1144948D03*
Y1148294D03*
Y1151641D03*
Y1154987D03*
Y1158333D03*
Y1161680D03*
Y1165026D03*
Y1168373D03*
Y1171719D03*
Y1175066D03*
Y1178412D03*
Y1181759D03*
Y1185105D03*
Y1188452D03*
Y1191798D03*
Y1195144D03*
Y1198491D03*
Y1201837D03*
Y1205184D03*
Y1208530D03*
Y1211877D03*
Y1215223D03*
Y1218570D03*
Y1221916D03*
Y1225263D03*
Y1228609D03*
Y1231955D03*
Y1235302D03*
Y1238648D03*
Y1241995D03*
Y1245341D03*
Y1248688D03*
Y1252034D03*
Y1255381D03*
Y1258727D03*
Y1262074D03*
Y1265420D03*
X1766033Y766798D03*
Y770144D03*
Y773491D03*
Y776837D03*
Y780184D03*
Y783530D03*
Y786877D03*
Y790223D03*
Y793570D03*
Y796916D03*
Y800263D03*
Y803609D03*
Y806955D03*
Y810302D03*
Y813648D03*
Y816995D03*
Y820341D03*
Y823688D03*
Y827034D03*
Y830381D03*
Y833727D03*
Y837074D03*
Y840420D03*
Y843766D03*
Y847113D03*
Y850459D03*
Y853806D03*
Y857152D03*
Y860499D03*
Y863845D03*
Y867192D03*
Y870538D03*
Y873885D03*
Y877231D03*
Y880577D03*
Y883924D03*
Y887270D03*
Y890617D03*
Y893963D03*
Y897310D03*
Y900656D03*
Y904003D03*
Y907349D03*
Y910696D03*
Y914042D03*
Y917389D03*
Y920735D03*
Y924081D03*
Y927428D03*
Y930774D03*
Y934121D03*
Y937467D03*
Y940814D03*
Y944160D03*
Y947507D03*
Y950853D03*
Y954200D03*
Y957546D03*
Y960892D03*
Y964239D03*
Y967585D03*
Y970932D03*
Y974278D03*
Y977625D03*
Y980971D03*
Y984318D03*
Y987664D03*
Y991011D03*
Y994357D03*
Y1017782D03*
Y1021129D03*
Y1024475D03*
Y1027822D03*
Y1031168D03*
Y1034515D03*
Y1037861D03*
Y1041207D03*
Y1044554D03*
Y1047900D03*
Y1051247D03*
Y1054593D03*
Y1057940D03*
Y1061286D03*
Y1064633D03*
Y1067979D03*
Y1071326D03*
Y1074672D03*
Y1078018D03*
Y1081365D03*
Y1084711D03*
Y1088058D03*
Y1091404D03*
Y1094751D03*
Y1098097D03*
Y1101444D03*
Y1104790D03*
Y1108137D03*
Y1111483D03*
Y1114829D03*
Y1118176D03*
Y1121522D03*
Y1124869D03*
Y1128215D03*
Y1131562D03*
Y1134908D03*
Y1138255D03*
Y1141601D03*
Y1144948D03*
Y1148294D03*
Y1151641D03*
Y1154987D03*
Y1158333D03*
Y1161680D03*
Y1165026D03*
Y1168373D03*
Y1171719D03*
Y1175066D03*
Y1178412D03*
Y1181759D03*
Y1185105D03*
Y1188452D03*
Y1191798D03*
Y1195144D03*
Y1198491D03*
Y1201837D03*
Y1205184D03*
Y1208530D03*
Y1211877D03*
Y1215223D03*
Y1218570D03*
Y1221916D03*
Y1225263D03*
Y1228609D03*
Y1231955D03*
Y1235302D03*
Y1238648D03*
Y1241995D03*
Y1245341D03*
Y1248688D03*
Y1252034D03*
Y1255381D03*
Y1258727D03*
Y1262074D03*
Y1265420D03*
X1779591Y766798D03*
Y770144D03*
Y773491D03*
Y776837D03*
Y780184D03*
Y783530D03*
Y786877D03*
Y790223D03*
Y793570D03*
Y796916D03*
Y800263D03*
Y803609D03*
Y806955D03*
Y810302D03*
Y813648D03*
Y816995D03*
Y820341D03*
Y823688D03*
Y827034D03*
Y830381D03*
Y833727D03*
Y837074D03*
Y840420D03*
Y843766D03*
Y847113D03*
Y850459D03*
Y853806D03*
Y857152D03*
Y860499D03*
Y863845D03*
Y867192D03*
Y870538D03*
Y873885D03*
Y877231D03*
Y880577D03*
Y883924D03*
Y887270D03*
Y890617D03*
Y893963D03*
Y897310D03*
Y900656D03*
Y904003D03*
Y907349D03*
Y910696D03*
Y914042D03*
Y917389D03*
Y920735D03*
Y924081D03*
Y927428D03*
Y930774D03*
Y934121D03*
Y937467D03*
Y940814D03*
Y944160D03*
Y947507D03*
Y950853D03*
Y954200D03*
Y957546D03*
Y960892D03*
Y964239D03*
Y967585D03*
Y970932D03*
Y974278D03*
Y977625D03*
Y980971D03*
Y984318D03*
Y987664D03*
Y991011D03*
Y994357D03*
Y1017782D03*
Y1021129D03*
Y1024475D03*
Y1027822D03*
Y1031168D03*
Y1034515D03*
Y1037861D03*
Y1041207D03*
Y1044554D03*
Y1047900D03*
Y1051247D03*
Y1054593D03*
Y1057940D03*
Y1061286D03*
Y1064633D03*
Y1067979D03*
Y1071326D03*
Y1074672D03*
Y1078018D03*
Y1081365D03*
Y1084711D03*
Y1088058D03*
Y1091404D03*
Y1094751D03*
Y1098097D03*
Y1101444D03*
Y1104790D03*
Y1108137D03*
Y1111483D03*
Y1114829D03*
Y1118176D03*
Y1121522D03*
Y1124869D03*
Y1128215D03*
Y1131562D03*
Y1134908D03*
Y1138255D03*
Y1141601D03*
Y1144948D03*
Y1148294D03*
Y1151641D03*
Y1154987D03*
Y1158333D03*
Y1161680D03*
Y1165026D03*
Y1168373D03*
Y1171719D03*
Y1175066D03*
Y1178412D03*
Y1181759D03*
Y1185105D03*
Y1188452D03*
Y1191798D03*
Y1195144D03*
Y1198491D03*
Y1201837D03*
Y1205184D03*
Y1208530D03*
Y1211877D03*
Y1215223D03*
Y1218570D03*
Y1221916D03*
Y1225263D03*
Y1228609D03*
Y1231955D03*
Y1235302D03*
Y1238648D03*
Y1241995D03*
Y1245341D03*
Y1248688D03*
Y1252034D03*
Y1255381D03*
Y1258727D03*
Y1262074D03*
Y1265420D03*
X1795733Y766798D03*
Y770144D03*
Y773491D03*
Y776837D03*
Y780184D03*
Y783530D03*
Y786877D03*
Y790223D03*
Y793570D03*
Y796916D03*
Y800263D03*
Y803609D03*
Y806955D03*
Y810302D03*
Y813648D03*
Y816995D03*
Y820341D03*
Y823688D03*
Y827034D03*
Y830381D03*
Y833727D03*
Y837074D03*
Y840420D03*
Y843766D03*
Y847113D03*
Y850459D03*
Y853806D03*
Y857152D03*
Y860499D03*
Y863845D03*
Y867192D03*
Y870538D03*
Y873885D03*
Y877231D03*
Y880577D03*
Y883924D03*
Y887270D03*
Y890617D03*
Y893963D03*
Y897310D03*
Y900656D03*
Y904003D03*
Y907349D03*
Y910696D03*
Y914042D03*
Y917389D03*
Y920735D03*
Y924081D03*
Y927428D03*
Y930774D03*
Y934121D03*
Y937467D03*
Y940814D03*
Y944160D03*
Y947507D03*
Y950853D03*
Y954200D03*
Y957546D03*
Y960892D03*
Y964239D03*
Y967585D03*
Y970932D03*
Y974278D03*
Y977625D03*
Y980971D03*
Y984318D03*
Y987664D03*
Y991011D03*
Y994357D03*
Y1017782D03*
Y1021129D03*
Y1024475D03*
Y1027822D03*
Y1031168D03*
Y1034515D03*
Y1037861D03*
Y1041207D03*
Y1044554D03*
Y1047900D03*
Y1051247D03*
Y1054593D03*
Y1057940D03*
Y1061286D03*
Y1064633D03*
Y1067979D03*
Y1071326D03*
Y1074672D03*
Y1078018D03*
Y1081365D03*
Y1084711D03*
Y1088058D03*
Y1091404D03*
Y1094751D03*
Y1098097D03*
Y1101444D03*
Y1104790D03*
Y1108137D03*
Y1111483D03*
Y1114829D03*
Y1118176D03*
Y1121522D03*
Y1124869D03*
Y1128215D03*
Y1131562D03*
Y1134908D03*
Y1138255D03*
Y1141601D03*
Y1144948D03*
Y1148294D03*
Y1151641D03*
Y1154987D03*
Y1158333D03*
Y1161680D03*
Y1165026D03*
Y1168373D03*
Y1171719D03*
Y1175066D03*
Y1178412D03*
Y1181759D03*
Y1185105D03*
Y1188452D03*
Y1191798D03*
Y1195144D03*
Y1198491D03*
Y1201837D03*
Y1205184D03*
Y1208530D03*
Y1211877D03*
Y1215223D03*
Y1218570D03*
Y1221916D03*
Y1225263D03*
Y1228609D03*
Y1231955D03*
Y1235302D03*
Y1238648D03*
Y1241995D03*
Y1245341D03*
Y1248688D03*
Y1252034D03*
Y1255381D03*
Y1258727D03*
Y1262074D03*
Y1265420D03*
X1809291Y766798D03*
Y770144D03*
Y773491D03*
Y776837D03*
Y780184D03*
Y783530D03*
Y786877D03*
Y790223D03*
Y793570D03*
Y796916D03*
Y800263D03*
Y803609D03*
Y806955D03*
Y810302D03*
Y813648D03*
Y816995D03*
Y820341D03*
Y823688D03*
Y827034D03*
Y830381D03*
Y833727D03*
Y837074D03*
Y840420D03*
Y843766D03*
Y847113D03*
Y850459D03*
Y853806D03*
Y857152D03*
Y860499D03*
Y863845D03*
Y867192D03*
Y870538D03*
Y873885D03*
Y877231D03*
Y880577D03*
Y883924D03*
Y887270D03*
Y890617D03*
Y893963D03*
Y897310D03*
Y900656D03*
Y904003D03*
Y907349D03*
Y910696D03*
Y914042D03*
Y917389D03*
Y920735D03*
Y924081D03*
Y927428D03*
Y930774D03*
Y934121D03*
Y937467D03*
Y940814D03*
Y944160D03*
Y947507D03*
Y950853D03*
Y954200D03*
Y957546D03*
Y960892D03*
Y964239D03*
Y967585D03*
Y970932D03*
Y974278D03*
Y977625D03*
Y980971D03*
Y984318D03*
Y987664D03*
Y991011D03*
Y994357D03*
Y1017782D03*
Y1021129D03*
Y1024475D03*
Y1027822D03*
Y1031168D03*
Y1034515D03*
Y1037861D03*
Y1041207D03*
Y1044554D03*
Y1047900D03*
Y1051247D03*
Y1054593D03*
Y1057940D03*
Y1061286D03*
Y1064633D03*
Y1067979D03*
Y1071326D03*
Y1074672D03*
Y1078018D03*
Y1081365D03*
Y1084711D03*
Y1088058D03*
Y1091404D03*
Y1094751D03*
Y1098097D03*
Y1101444D03*
Y1104790D03*
Y1108137D03*
Y1111483D03*
Y1114829D03*
Y1118176D03*
Y1121522D03*
Y1124869D03*
Y1128215D03*
Y1131562D03*
Y1134908D03*
Y1138255D03*
Y1141601D03*
Y1144948D03*
Y1148294D03*
Y1151641D03*
Y1154987D03*
Y1158333D03*
Y1161680D03*
Y1165026D03*
Y1168373D03*
Y1171719D03*
Y1175066D03*
Y1178412D03*
Y1181759D03*
Y1185105D03*
Y1188452D03*
Y1191798D03*
Y1195144D03*
Y1198491D03*
Y1201837D03*
Y1205184D03*
Y1208530D03*
Y1211877D03*
Y1215223D03*
Y1218570D03*
Y1221916D03*
Y1225263D03*
Y1228609D03*
Y1231955D03*
Y1235302D03*
Y1238648D03*
Y1241995D03*
Y1245341D03*
Y1248688D03*
Y1252034D03*
Y1255381D03*
Y1258727D03*
Y1262074D03*
Y1265420D03*
X1825433Y766798D03*
Y770144D03*
Y773491D03*
Y776837D03*
Y780184D03*
Y783530D03*
Y786877D03*
Y790223D03*
Y793570D03*
Y796916D03*
Y800263D03*
Y803609D03*
Y806955D03*
Y810302D03*
Y813648D03*
Y816995D03*
Y820341D03*
Y823688D03*
Y827034D03*
Y830381D03*
Y833727D03*
Y837074D03*
Y840420D03*
Y843766D03*
Y847113D03*
Y850459D03*
Y853806D03*
Y857152D03*
Y860499D03*
Y863845D03*
Y867192D03*
Y870538D03*
Y873885D03*
Y877231D03*
Y880577D03*
Y883924D03*
Y887270D03*
Y890617D03*
Y893963D03*
Y897310D03*
Y900656D03*
Y904003D03*
Y907349D03*
Y910696D03*
Y914042D03*
Y917389D03*
Y920735D03*
Y924081D03*
Y927428D03*
Y930774D03*
Y934121D03*
Y937467D03*
Y940814D03*
Y944160D03*
Y947507D03*
Y950853D03*
Y954200D03*
Y957546D03*
Y960892D03*
Y964239D03*
Y967585D03*
Y970932D03*
Y974278D03*
Y977625D03*
Y980971D03*
Y984318D03*
Y987664D03*
Y991011D03*
Y994357D03*
Y1017782D03*
Y1021129D03*
Y1024475D03*
Y1027822D03*
Y1031168D03*
Y1034515D03*
Y1037861D03*
Y1041207D03*
Y1044554D03*
Y1047900D03*
Y1051247D03*
Y1054593D03*
Y1057940D03*
Y1061286D03*
Y1064633D03*
Y1067979D03*
Y1071326D03*
Y1074672D03*
Y1078018D03*
Y1081365D03*
Y1084711D03*
Y1088058D03*
Y1091404D03*
Y1094751D03*
Y1098097D03*
Y1101444D03*
Y1104790D03*
Y1108137D03*
Y1111483D03*
Y1114829D03*
Y1118176D03*
Y1121522D03*
Y1124869D03*
Y1128215D03*
Y1131562D03*
Y1134908D03*
Y1138255D03*
Y1141601D03*
Y1144948D03*
Y1148294D03*
Y1151641D03*
Y1154987D03*
Y1158333D03*
Y1161680D03*
Y1165026D03*
Y1168373D03*
Y1171719D03*
Y1175066D03*
Y1178412D03*
Y1181759D03*
Y1185105D03*
Y1188452D03*
Y1191798D03*
Y1195144D03*
Y1198491D03*
Y1201837D03*
Y1205184D03*
Y1208530D03*
Y1211877D03*
Y1215223D03*
Y1218570D03*
Y1221916D03*
Y1225263D03*
Y1228609D03*
Y1231955D03*
Y1235302D03*
Y1238648D03*
Y1241995D03*
Y1245341D03*
Y1248688D03*
Y1252034D03*
Y1255381D03*
Y1258727D03*
Y1262074D03*
Y1265420D03*
G54D106*
X168666Y716471D03*
X180084D03*
X290586Y624181D03*
X302004D03*
X1575511Y735362D03*
Y744362D03*
X1586929Y735362D03*
Y744362D03*
G54D142*
X306772Y991220D03*
X350099Y811121D03*
X356063Y1171318D03*
X531240Y811121D03*
X525276Y1171318D03*
X574567Y991220D03*
X1282914D03*
X1326240Y811121D03*
X1332205Y1171318D03*
X1507382Y811121D03*
X1501418Y1171318D03*
X1550709Y991220D03*
G54D40*
X53701Y1631013D03*
Y1654045D03*
X82637Y1631013D03*
Y1654045D03*
G54D241*
X925102Y1531780D03*
X933290D03*
G54D133*
X274299Y224782D03*
X1658169Y414202D03*
G54D13*
X14092Y292892D03*
Y295452D03*
X28068D03*
Y292892D03*
X44692Y293392D03*
Y295952D03*
X58668D03*
Y293392D03*
X1744422Y154282D03*
Y156842D03*
X1758398D03*
Y154282D03*
G54D160*
X370890Y1627042D03*
X368331D03*
Y1634522D03*
X370890D03*
X373449Y1627042D03*
Y1634522D03*
X380668Y1664844D03*
X378109D03*
X375550D03*
Y1672324D03*
X378109D03*
X380668D03*
X448079Y1552197D03*
X445520D03*
X442961D03*
Y1559677D03*
X445520D03*
X448079D03*
X462079Y1562197D03*
X459520D03*
X456961D03*
Y1569677D03*
X459520D03*
X462079D03*
X459779Y1599255D03*
X457220D03*
X454661D03*
Y1606735D03*
X457220D03*
X459779D03*
X600351Y472248D03*
X602910D03*
X605469D03*
Y464768D03*
X602910D03*
X600351D03*
X656877Y504277D03*
X654318D03*
X651759D03*
Y511757D03*
X654318D03*
X656877D03*
X1150704Y222677D03*
Y230157D03*
X1158382Y197407D03*
X1155823D03*
X1153264D03*
Y204887D03*
X1155823D03*
X1158382D03*
X1155822Y222677D03*
X1153263D03*
Y230157D03*
X1155822D03*
X1163789Y1665575D03*
X1161230D03*
X1158671D03*
Y1673055D03*
X1161230D03*
X1163789D03*
X1183230Y1665575D03*
X1180671D03*
X1174789D03*
X1172230D03*
X1169671D03*
X1180671Y1673055D03*
X1183230D03*
X1169671D03*
X1172230D03*
X1174789D03*
X1196459Y1665885D03*
X1193900D03*
X1191341D03*
X1185789Y1665575D03*
X1191341Y1673365D03*
X1193900D03*
X1196459D03*
X1185789Y1673055D03*
X1196199Y1711365D03*
X1193640D03*
X1191081D03*
Y1718845D03*
X1193640D03*
X1196199D03*
X1215210Y1711675D03*
X1212651D03*
X1206969Y1711410D03*
X1204410D03*
X1201851D03*
X1212651Y1719155D03*
X1215210D03*
X1201851Y1718890D03*
X1204410D03*
X1206969D03*
X1217769Y1711675D03*
Y1719155D03*
G54D214*
X761223Y271354D03*
Y273322D03*
Y275290D03*
X769097D03*
Y273322D03*
Y271354D03*
X1509488Y297812D03*
Y301748D03*
G54D205*
X709692Y177187D03*
X711792D03*
X709692Y173587D03*
X711792D03*
X709692Y185587D03*
X711792D03*
X709692Y189187D03*
X711792D03*
X709692Y197087D03*
X711792D03*
X709692Y200687D03*
X711792D03*
X709692Y212521D03*
X711792D03*
X709692Y208921D03*
X711792D03*
X940496Y211897D03*
Y215497D03*
Y204775D03*
Y208375D03*
Y229635D03*
Y226035D03*
X942596Y211897D03*
Y215497D03*
Y204775D03*
Y208375D03*
Y229635D03*
Y226035D03*
X947196Y222548D03*
X949296D03*
X947196Y218948D03*
X949296D03*
X1375400Y249262D03*
X1373300D03*
X1375400Y245662D03*
X1373300D03*
X1379624Y238551D03*
Y242151D03*
X1374916Y263736D03*
X1372816D03*
X1374916Y260136D03*
X1372816D03*
X1375121Y272170D03*
X1373021D03*
X1375121Y268570D03*
X1373021D03*
X1381724Y238551D03*
Y242151D03*
X1385600Y257303D03*
X1383500D03*
X1385600Y253703D03*
X1383500D03*
G54D115*
X207996Y678369D03*
X206027D03*
X204059D03*
X202090D03*
X209964D03*
X435100Y1618242D03*
Y1636942D03*
X437069Y1618242D03*
X439037D03*
X441006D03*
X442974D03*
X444943D03*
X446911D03*
X448880D03*
X437069Y1636942D03*
X439037D03*
X441006D03*
X442974D03*
X444943D03*
X446911D03*
X448880D03*
X923836Y979352D03*
X921868D03*
Y994116D03*
X923836D03*
X931710Y979352D03*
X929742D03*
X927773D03*
X925805D03*
Y994116D03*
X927773D03*
X929742D03*
X931710D03*
X1647009Y610213D03*
X1648977D03*
X1650946D03*
X1652914D03*
X1654883D03*
G54D223*
X779220Y1578633D03*
Y1592413D03*
X796938Y1578633D03*
Y1592413D03*
X821220Y1578633D03*
Y1592413D03*
X838938Y1578633D03*
Y1592413D03*
X863220Y1578633D03*
Y1592413D03*
X880938Y1578633D03*
Y1592413D03*
X905220Y1578633D03*
Y1592413D03*
X922938Y1578633D03*
Y1592413D03*
G54D22*
X39484Y200862D03*
Y192862D03*
X39204Y216362D03*
X30704D03*
X39204Y208362D03*
Y232362D03*
Y224342D03*
X30704Y224362D03*
X39204Y240362D03*
X36164Y302472D03*
X62258Y1520094D03*
Y1536094D03*
Y1540094D03*
Y1560094D03*
X65790Y302926D03*
X68592Y421746D03*
X82624Y278798D03*
Y295798D03*
Y286262D03*
Y303262D03*
X84875Y376026D03*
X84858Y386502D03*
X80975Y424319D03*
Y420319D03*
X91285Y438519D03*
Y442519D03*
X80674Y648574D03*
Y644564D03*
X88624D03*
X80674Y652564D03*
X88624Y648564D03*
Y656564D03*
Y652564D03*
X89503Y685488D03*
X88492Y694209D03*
X89492Y690644D03*
X87122Y1589872D03*
X91729Y1683071D03*
X91704Y1694362D03*
X91714Y1686622D03*
X110999Y216596D03*
X107934Y517925D03*
X110079Y685490D03*
X98734Y718880D03*
X110258Y1524594D03*
Y1544594D03*
Y1548594D03*
Y1536594D03*
Y1540594D03*
Y1560594D03*
Y1564594D03*
X96172Y1581852D03*
Y1597867D03*
X96247Y1601867D03*
Y1615821D03*
Y1619821D03*
X96157Y1630362D03*
Y1642362D03*
X112059Y186362D03*
X113996Y282995D03*
Y278875D03*
Y274800D03*
Y300354D03*
Y306236D03*
X115798Y523785D03*
X127222Y647103D03*
X125658Y665515D03*
Y661515D03*
X125634Y669400D03*
X119217Y1535767D03*
X119319Y1541935D03*
X119390Y1548027D03*
X124704Y1678362D03*
Y1670362D03*
Y1674362D03*
X117704Y1696362D03*
X124704Y1692362D03*
Y1688362D03*
Y1708362D03*
Y1700362D03*
Y1704362D03*
X130466Y404571D03*
X128222Y656603D03*
Y652603D03*
X131665Y643603D03*
X130541Y1727182D03*
Y1731182D03*
X146880Y415062D03*
Y423383D03*
Y427383D03*
Y419383D03*
Y431383D03*
Y435383D03*
Y439383D03*
Y443383D03*
X146981Y498810D03*
Y502810D03*
X146946Y506533D03*
X146981Y522810D03*
X146529Y688207D03*
X145601Y1396275D03*
Y1392745D03*
X160042Y1412173D03*
X151204Y1708362D03*
Y1712362D03*
X158204Y1716362D03*
X161384Y409362D03*
X175380Y421383D03*
Y425383D03*
Y443383D03*
Y430883D03*
X168595Y1443390D03*
X183966Y393071D03*
Y385071D03*
Y389071D03*
Y405071D03*
X182966Y1535462D03*
X182852Y1544028D03*
X182932Y1548486D03*
X182955Y1539723D03*
X182923Y1552874D03*
Y1557874D03*
X185051Y1723592D03*
X204608Y420255D03*
Y414755D03*
Y425755D03*
Y436755D03*
Y431255D03*
Y442255D03*
Y447755D03*
Y453255D03*
Y458755D03*
Y462755D03*
Y468255D03*
X199585Y570901D03*
X200057Y588879D03*
X199585Y604901D03*
X200057Y622879D03*
X199585Y638901D03*
X200057Y656879D03*
X195035Y681291D03*
X194126Y693623D03*
X198185Y1412173D03*
X196352Y1719697D03*
X208102Y1718017D03*
X202109Y1733022D03*
X215038Y452735D03*
X218375Y567981D03*
X217276Y596107D03*
X218375Y601981D03*
X217276Y630107D03*
X218375Y635981D03*
X217276Y664107D03*
X214525Y673737D03*
X233504Y154126D03*
X245204Y71862D03*
X250281Y111743D03*
X272984Y136962D03*
X270034Y142892D03*
X270037Y159203D03*
Y155203D03*
X265704Y214022D03*
X269538Y422735D03*
X269520Y418579D03*
X269538Y426735D03*
X269570Y431039D03*
X269538Y443735D03*
X259754Y458617D03*
X276751Y99183D03*
X279884Y136962D03*
X280764Y210802D03*
X298401Y71513D03*
X298431Y75673D03*
X299537Y151703D03*
Y156203D03*
X292104Y637809D03*
X320041Y91803D03*
X309203Y595318D03*
X317699Y599926D03*
X315130Y1369807D03*
X325526Y69863D03*
X323289Y563176D03*
X342984Y161862D03*
X349717Y709995D03*
X346153Y1347521D03*
X366684Y130162D03*
X366584Y156202D03*
X356204Y221862D03*
X379204Y128452D03*
X379224Y124312D03*
X378281Y1334095D03*
X387834Y1627062D03*
X388644Y124322D03*
X388559Y128491D03*
X399080Y1330142D03*
X397809Y1413619D03*
X399402Y1432571D03*
Y1427569D03*
X402405Y1541810D03*
Y1556810D03*
X411343Y161162D03*
X412027Y1334095D03*
X418461Y1390306D03*
X411799Y1390325D03*
X406388Y1404207D03*
Y1400684D03*
X406315Y1397038D03*
X406383Y1407727D03*
X408202Y1427569D03*
Y1432571D03*
X414184Y1611300D03*
Y1607400D03*
X412916Y1680267D03*
X422821Y67465D03*
Y62665D03*
X426559Y117491D03*
X431948Y128515D03*
Y124015D03*
X420681Y149373D03*
Y157466D03*
Y161466D03*
Y153477D03*
X431204Y214862D03*
Y209862D03*
X426204Y225362D03*
X426904Y232562D03*
Y236562D03*
Y240562D03*
X430639Y1330042D03*
X432905Y1543810D03*
Y1555810D03*
X430029Y1579466D03*
X449805Y149864D03*
X439802Y498733D03*
Y504233D03*
Y509733D03*
Y515233D03*
Y520733D03*
Y526233D03*
Y542733D03*
X448312Y537483D03*
X439802Y547769D03*
Y552769D03*
X442537Y1334095D03*
X454477Y75985D03*
X459623Y115948D03*
X458805Y149864D03*
Y154864D03*
X463564Y1330533D03*
X454073Y1393959D03*
X453085Y1420625D03*
Y1409125D03*
Y1413125D03*
Y1417125D03*
Y1427632D03*
Y1424125D03*
X453074Y1431134D03*
X453064Y1611923D03*
X475237Y66575D03*
X475211Y61129D03*
X475167Y55935D03*
X484305Y158864D03*
X483204Y391362D03*
X474665Y1334095D03*
X480950Y1400385D03*
X479555Y1411144D03*
X469397Y1614682D03*
X469354Y1618626D03*
X475414Y1643242D03*
Y1659242D03*
Y1651242D03*
Y1667242D03*
X475344Y1673462D03*
Y1685462D03*
X492320Y305398D03*
X492294Y313582D03*
X496204Y391362D03*
X494102Y547947D03*
X495724Y1319592D03*
X488134Y1631038D03*
X506934Y86422D03*
X502564Y93582D03*
X509984Y209862D03*
X503984Y228362D03*
X505484Y237862D03*
X508484Y288862D03*
X508241Y315404D03*
X511204Y420862D03*
X507002Y507819D03*
Y511819D03*
Y519819D03*
Y515819D03*
Y523819D03*
Y527819D03*
Y539819D03*
X506793Y1347521D03*
X526204Y420862D03*
X525864Y478492D03*
X529884Y489112D03*
Y495112D03*
X528322Y1338837D03*
X539304Y103352D03*
X539374Y108062D03*
X550454Y149802D03*
X538434Y442376D03*
Y450330D03*
Y446396D03*
X538921Y1370319D03*
X555454Y131756D03*
X562204Y167112D03*
Y161362D03*
X562704Y184862D03*
X557548Y253202D03*
Y257202D03*
X573704Y167112D03*
X578418Y262632D03*
X569673Y305247D03*
X568024Y442656D03*
X568001Y451710D03*
X571899Y498546D03*
X581984Y514362D03*
X591304Y129642D03*
X598204Y174612D03*
X584934Y190092D03*
X584940Y198378D03*
Y210378D03*
Y202378D03*
Y206378D03*
X584704Y225362D03*
Y221362D03*
X599298Y257532D03*
X589548Y252202D03*
X588029Y296657D03*
Y311571D03*
Y304052D03*
X594289Y363354D03*
X591054Y488212D03*
X594484Y524862D03*
X604704Y164612D03*
X614440Y202878D03*
Y207378D03*
X602914Y458688D03*
X602704Y482362D03*
X603704Y514862D03*
X621291Y184022D03*
X630048Y249202D03*
Y260202D03*
X619704Y442862D03*
Y457862D03*
X641537Y88035D03*
X641497Y92085D03*
X648145Y134506D03*
X648128Y144982D03*
X640204Y230362D03*
X640629Y298297D03*
Y315587D03*
Y310962D03*
Y302247D03*
X635984Y392862D03*
X634704Y411362D03*
X634484Y406862D03*
X634704Y426362D03*
Y421362D03*
Y441862D03*
Y431362D03*
X634707Y436650D03*
X634704Y457862D03*
Y452862D03*
Y447862D03*
Y462862D03*
X634684Y482662D03*
X646709Y1653194D03*
X645209Y1695694D03*
X645204Y1718362D03*
Y1722362D03*
X649484Y93362D03*
X655094Y120412D03*
X649204Y161862D03*
Y166362D03*
Y171362D03*
X655729Y290371D03*
X648984Y392862D03*
X649484Y406862D03*
Y402362D03*
X649704Y416362D03*
Y441862D03*
Y431362D03*
Y452862D03*
Y457862D03*
Y447862D03*
Y467862D03*
Y462862D03*
X659220Y1392770D03*
Y1396300D03*
X673114Y391602D03*
X673661Y1412198D03*
X668556Y1642667D03*
X668577Y1655557D03*
X668502Y1651557D03*
X668604Y1672862D03*
Y1668862D03*
X671704Y1708362D03*
X666704Y1720362D03*
X671704Y1724362D03*
Y1716362D03*
Y1732362D03*
X683437Y115868D03*
X684884Y1442245D03*
X694631Y1632667D03*
X694706Y1644667D03*
X694716Y1648843D03*
X695104Y1658862D03*
X690104Y1670862D03*
X695104Y1666862D03*
Y1674862D03*
Y1682862D03*
X709907Y103308D03*
X713204Y161862D03*
Y157362D03*
X711804Y1412198D03*
X707626Y1563733D03*
X707596Y1583683D03*
X706564Y1607102D03*
Y1611022D03*
X707556Y1601963D03*
X721254Y1644550D03*
X721817Y1676500D03*
X733007Y95158D03*
X732977Y90998D03*
X760102Y89348D03*
X754617Y111288D03*
X748719Y142050D03*
X751184Y167537D03*
X751144Y276322D03*
X757596Y1579183D03*
Y1587183D03*
Y1592183D03*
X748139Y1674362D03*
X777773Y158026D03*
X777787Y153728D03*
X766726Y299279D03*
X766627Y311249D03*
X766154Y317432D03*
X763704Y393212D03*
Y418212D03*
Y423212D03*
Y428212D03*
X777824Y464862D03*
Y469862D03*
X762824Y464862D03*
Y469862D03*
Y488862D03*
Y483862D03*
Y479862D03*
X777824Y488862D03*
X762834Y497659D03*
X765004Y1388562D03*
Y1392762D03*
Y1406062D03*
X764904Y1410262D03*
X768636Y1594893D03*
X782644Y267822D03*
Y281822D03*
X780526Y299279D03*
X792904Y393462D03*
X778704Y413212D03*
Y408212D03*
Y403212D03*
Y398212D03*
X792904Y402500D03*
X778704Y418212D03*
Y423212D03*
X792824Y464862D03*
Y474862D03*
X791384Y483262D03*
X805946Y269800D03*
X808324Y469862D03*
Y474862D03*
X810136Y1577793D03*
Y1593793D03*
Y1601793D03*
Y1609793D03*
X824592Y274885D03*
Y279885D03*
X834445Y58632D03*
X831204Y166862D03*
Y176362D03*
X836119Y275045D03*
Y280045D03*
X830462Y389012D03*
Y397276D03*
X830484Y384400D03*
X830461Y413260D03*
X838484Y446800D03*
X827247Y494000D03*
X827254Y498082D03*
X841704Y495362D03*
X827254Y502082D03*
Y523082D03*
Y515082D03*
X851804Y162762D03*
X851394Y185812D03*
X859317Y273217D03*
X859287Y269057D03*
X852384Y476900D03*
X852136Y1577793D03*
Y1593793D03*
Y1601793D03*
Y1609793D03*
X874204Y166362D03*
X867970Y394620D03*
Y390620D03*
Y382415D03*
X868022Y406812D03*
Y418836D03*
X867804Y431462D03*
X860104Y503162D03*
Y499062D03*
X860254Y515582D03*
Y519582D03*
X882204Y176862D03*
Y171362D03*
X884199Y183169D03*
X884209Y187449D03*
X886412Y267407D03*
X880899Y289439D03*
X887806Y874405D03*
X888376Y920325D03*
X894136Y1577793D03*
Y1593793D03*
Y1601793D03*
Y1609793D03*
X936136Y1581393D03*
Y1585393D03*
Y1589393D03*
X958329Y484271D03*
X958304Y480262D03*
X958355Y540727D03*
X958356Y536806D03*
X961274Y997496D03*
X964463Y1551855D03*
X984608Y185347D03*
X984333Y276394D03*
X980778Y356910D03*
X989241Y363660D03*
X987829Y1551855D03*
X997396Y217233D03*
Y221233D03*
X996507Y363155D03*
X1018711Y195114D03*
X1018704Y199076D03*
X1016679Y203423D03*
Y210423D03*
Y214423D03*
Y218423D03*
Y222423D03*
X1011222Y363356D03*
X1021253Y517728D03*
Y512574D03*
X1011195Y1551855D03*
X1037317Y264130D03*
X1027317Y297264D03*
Y305313D03*
Y301313D03*
X1034561Y1551855D03*
X1044011Y291105D03*
X1045472Y502161D03*
X1057927Y1551855D03*
X1082173Y78553D03*
X1072689Y382141D03*
X1076648Y509645D03*
X1081293Y1551855D03*
X1079441Y1663950D03*
X1097703Y65262D03*
X1094594Y379251D03*
X1094474Y369061D03*
X1094534Y374131D03*
X1101514Y1679870D03*
Y1675970D03*
X1100034Y1672030D03*
X1107116Y55505D03*
X1118912Y1429074D03*
Y1432604D03*
X1104659Y1551855D03*
X1124587Y60545D03*
X1124487Y56545D03*
X1124587Y64545D03*
X1133353Y1448502D03*
X1122094Y1612320D03*
X1122064Y1608420D03*
X1151854Y211231D03*
X1140374Y377011D03*
X1145017Y1479313D03*
X1152454Y1618960D03*
X1153494Y373231D03*
X1159145Y1622340D03*
Y1626220D03*
Y1630090D03*
X1163909Y1642600D03*
X1159145Y1633880D03*
X1178729Y202174D03*
Y198174D03*
Y186174D03*
Y218174D03*
Y214174D03*
X1171496Y1448502D03*
X1175364Y1601100D03*
Y1609100D03*
Y1605100D03*
X1175244Y1612960D03*
X1182055D03*
X1174909Y1642600D03*
X1185555Y61311D03*
X1185455Y65811D03*
X1185475Y57111D03*
X1198284Y93200D03*
X1196460Y127804D03*
X1200459Y236592D03*
X1196479Y1642910D03*
X1185909Y1642600D03*
X1196319Y1688390D03*
X1207245Y57130D03*
X1210704Y189362D03*
X1213889Y1673963D03*
X1206565Y1677873D03*
X1213819Y1681773D03*
X1207089Y1688435D03*
X1231484Y94200D03*
Y98400D03*
X1220077Y140962D03*
X1231577Y168162D03*
X1220077Y185462D03*
X1231577Y172962D03*
X1217889Y1688700D03*
X1245366Y98785D03*
X1242044Y191279D03*
X1242077Y197462D03*
X1251077Y201562D03*
Y211762D03*
Y205362D03*
X1262077Y217462D03*
X1251077Y215762D03*
X1262077Y233462D03*
Y221462D03*
X1251077Y219662D03*
X1262077Y229462D03*
Y225462D03*
Y243562D03*
Y238662D03*
Y247562D03*
X1251162Y245442D03*
X1262277Y251562D03*
X1270238Y88572D03*
Y96768D03*
X1281775Y98828D03*
X1269577Y233462D03*
X1291391Y1370043D03*
X1305518Y64572D03*
X1308247Y81775D03*
X1299149Y81169D03*
X1328048Y261514D03*
X1322294Y1347521D03*
X1354422Y1334095D03*
X1371736Y81111D03*
X1375221Y1330142D03*
X1373110Y1417374D03*
X1373950Y1413019D03*
X1388168Y1334095D03*
X1394602Y1390306D03*
X1382529Y1400684D03*
Y1404207D03*
X1387160Y1390335D03*
X1382524Y1407727D03*
X1411867Y227948D03*
X1406780Y1330042D03*
X1409892Y1565037D03*
X1409832Y1576197D03*
X1409892Y1570037D03*
X1402384Y1586400D03*
Y1590200D03*
X1405484Y1626362D03*
Y1634362D03*
Y1638362D03*
X1418678Y1334095D03*
X1420317Y1516435D03*
X1420557Y1532255D03*
X1420317Y1521335D03*
X1420557Y1537155D03*
X1420707Y1548375D03*
Y1543475D03*
X1423754Y1603262D03*
X1427254Y1608442D03*
X1427194Y1616932D03*
X1413959Y1622200D03*
X1439705Y1330533D03*
X1430214Y1393959D03*
X1429226Y1417125D03*
Y1413125D03*
Y1409125D03*
Y1420625D03*
Y1427632D03*
Y1424125D03*
X1429254Y1431150D03*
X1443164Y1590382D03*
X1443884Y1606800D03*
Y1602600D03*
X1439284Y1632900D03*
Y1620300D03*
X1444217Y1665495D03*
X1444127Y1673955D03*
X1444131Y1669629D03*
X1447984Y211862D03*
Y215862D03*
X1450806Y1334095D03*
X1457091Y1400385D03*
X1455696Y1411144D03*
X1455392Y1560037D03*
Y1565037D03*
X1453114Y1586262D03*
X1457449Y1612800D03*
X1474367Y225448D03*
Y233448D03*
X1466867Y242448D03*
X1474569Y263378D03*
Y255378D03*
X1466569Y271378D03*
X1471865Y1319592D03*
X1484392Y281456D03*
X1491884Y421982D03*
X1487864Y431972D03*
X1482934Y1347521D03*
X1498893Y280027D03*
X1504463Y1338837D03*
X1519484Y116462D03*
X1518484Y136162D03*
X1520052Y243362D03*
Y235116D03*
Y258616D03*
Y254616D03*
X1511385Y288030D03*
X1519742Y284956D03*
X1515862Y1369919D03*
X1545436Y152873D03*
X1546221Y634165D03*
X1566063Y655416D03*
Y659416D03*
X1568940Y735691D03*
Y732165D03*
X1592062Y219526D03*
Y227526D03*
X1591823Y248008D03*
X1591843Y243890D03*
X1591803Y252126D03*
X1607264Y654542D03*
X1605444Y722582D03*
X1600400Y1420169D03*
Y1433669D03*
Y1438169D03*
Y1452071D03*
X1614304Y586762D03*
X1620386Y1426366D03*
Y1429896D03*
X1629517Y117627D03*
Y129627D03*
Y121627D03*
X1634827Y1445794D03*
X1649066Y652601D03*
Y686601D03*
Y720601D03*
X1646091Y1476695D03*
X1664787Y550382D03*
X1657713Y544622D03*
X1665844Y598522D03*
X1656892Y635791D03*
Y669791D03*
Y703791D03*
X1672970Y1445794D03*
X1671582Y1493362D03*
Y1501362D03*
Y1516862D03*
Y1533862D03*
Y1520862D03*
Y1545862D03*
X1671657Y1561557D03*
X1671582Y1557557D03*
X1671657Y1581321D03*
X1687415Y495290D03*
Y499290D03*
X1704778Y369773D03*
Y373773D03*
X1702868Y401485D03*
X1696760Y525507D03*
Y529507D03*
Y533507D03*
Y549507D03*
X1703904Y688130D03*
Y691730D03*
Y695330D03*
X1704944Y726552D03*
X1714701Y174970D03*
X1717674Y364962D03*
X1706511Y655141D03*
X1725402Y112867D03*
X1722913Y474859D03*
Y478869D03*
X1725639Y688211D03*
X1751872Y100307D03*
X1754204Y372452D03*
X1739185Y486837D03*
X1744419Y1451841D03*
X1763552Y76797D03*
X1763522Y72637D03*
X1766494Y164362D03*
X1760125Y433221D03*
X1763225Y461393D03*
X1763335Y465893D03*
X1760740Y692742D03*
X1757509Y1475951D03*
X1785162Y92927D03*
X1774859Y169903D03*
X1782912Y291876D03*
X1782927Y295643D03*
Y299243D03*
X1790647Y70987D03*
X1802749Y165565D03*
X1795255Y367866D03*
X1794553Y390252D03*
X1787783Y403932D03*
Y410432D03*
Y418932D03*
Y425432D03*
X1798511Y1527366D03*
X1806274Y156557D03*
X1813234Y179897D03*
X1819283Y407932D03*
Y403225D03*
X1818783Y421432D03*
Y427932D03*
X1818725Y472521D03*
X1809625Y1494318D03*
Y1498318D03*
X1818198Y1504241D03*
X1826535Y363731D03*
X1820216Y371329D03*
X1826535Y367701D03*
X1826153Y379552D03*
X1820053Y395552D03*
X1826153Y383952D03*
X1835425Y459121D03*
X1838819Y182712D03*
X1845939Y176722D03*
G54D322*
X1879155Y344948D03*
Y468898D03*
D03*
Y592848D03*
D03*
Y716798D03*
D03*
Y840748D03*
X1900275Y-19342D03*
X1889155Y344948D03*
Y468898D03*
D03*
X1900275Y592858D03*
X1889155Y592848D03*
D03*
X1900275Y716808D03*
X1889155Y716798D03*
D03*
X1900275Y840758D03*
D03*
X1889155Y840748D03*
X1900275Y964708D03*
X1910275Y-19342D03*
Y592858D03*
Y716808D03*
Y840758D03*
D03*
Y964708D03*
X1921395Y-19332D03*
X1931395D03*
Y592868D03*
X1921395D03*
X1931395D03*
X1921395D03*
Y1205068D03*
X1931395D03*
X1952395Y-19152D03*
X1942395D03*
Y593048D03*
X1952395D03*
X1942395D03*
X1952395D03*
Y1205248D03*
X1942395D03*
X1963362Y-19190D03*
Y593010D03*
D03*
Y1205210D03*
X1984482Y-19180D03*
X1973362Y-19190D03*
X1984482Y593020D03*
D03*
X1973362Y593010D03*
D03*
X1984482Y1205220D03*
X1973362Y1205210D03*
X1994482Y-19180D03*
Y593020D03*
D03*
Y1205220D03*
X2005452Y-19180D03*
X2015452D03*
Y593020D03*
X2005452D03*
X2015452D03*
X2005452D03*
Y1205220D03*
X2015452D03*
X2026452Y-19000D03*
Y593200D03*
D03*
Y1205400D03*
X2047419Y-19038D03*
X2036452Y-19000D03*
X2047419Y593162D03*
X2036452Y593200D03*
X2047419Y593162D03*
X2036452Y593200D03*
X2047419Y1205362D03*
X2036452Y1205400D03*
X2057419Y-19038D03*
Y593162D03*
D03*
Y1205362D03*
X2068539Y593172D03*
X2078539D03*
Y1205372D03*
X2068539D03*
G54D313*
X1772468Y284558D03*
G54D250*
X986830Y-11500D03*
Y18500D03*
X1296222Y-21511D03*
Y-1511D03*
Y18489D03*
X1488581Y-21511D03*
Y-1511D03*
Y18489D03*
G54D232*
X841240Y1407480D03*
X832154Y1411244D03*
X828390Y1420330D03*
X832154Y1429416D03*
X841240Y1433180D03*
X850326Y1411244D03*
X854090Y1420330D03*
X850326Y1429416D03*
X1003390Y1420330D03*
X1016240Y1407480D03*
X1007154Y1411244D03*
Y1429416D03*
X1016240Y1433180D03*
X1025326Y1411244D03*
X1029090Y1420330D03*
X1025326Y1429416D03*
G54D304*
X1683921Y386516D03*
X1708421D03*
G54D124*
X227557Y582055D03*
Y616055D03*
Y650055D03*
X1626416Y638527D03*
Y672527D03*
Y706527D03*
G54D151*
X335787Y859758D03*
Y866166D03*
X337638Y856553D03*
Y862962D03*
X333938Y869370D03*
X336220Y1003842D03*
X338070Y1000637D03*
X346888Y846940D03*
X348738Y850145D03*
X350587Y846940D03*
X345038Y850145D03*
X346888Y853349D03*
X339488D03*
Y859758D03*
Y866166D03*
X341338Y856553D03*
Y862962D03*
X343187Y853349D03*
Y859758D03*
X345038Y856553D03*
X339920Y997433D03*
X534452Y1129091D03*
X530753Y1135500D03*
X532602Y1132295D03*
X534452Y1135500D03*
X545553Y1109865D03*
X543702Y1113070D03*
X536302Y1125887D03*
X538153Y1122682D03*
Y1129091D03*
X540002Y1119478D03*
Y1125887D03*
X541852Y1116274D03*
Y1122682D03*
Y1129091D03*
X543702Y1119478D03*
Y1125887D03*
X545553Y1116274D03*
Y1122682D03*
X536302Y1132295D03*
X1311929Y859758D03*
Y866166D03*
X1313780Y856553D03*
Y862962D03*
X1310080Y869370D03*
X1312362Y1003842D03*
X1314212Y1000637D03*
X1323030Y846940D03*
X1324880Y850145D03*
X1326729Y846940D03*
X1321180Y850145D03*
X1323030Y853349D03*
X1315630D03*
Y859758D03*
Y866166D03*
X1317480Y856553D03*
Y862962D03*
X1319329Y853349D03*
Y859758D03*
X1321180Y856553D03*
X1316062Y997433D03*
X1510594Y1129091D03*
X1506895Y1135500D03*
X1508744Y1132295D03*
X1510594Y1135500D03*
X1521695Y1109865D03*
X1519844Y1113070D03*
X1512444Y1125887D03*
X1514295Y1122682D03*
Y1129091D03*
X1516144Y1119478D03*
Y1125887D03*
X1517994Y1116274D03*
Y1122682D03*
Y1129091D03*
X1519844Y1119478D03*
Y1125887D03*
X1521695Y1116274D03*
Y1122682D03*
X1512444Y1132295D03*
G54D341*
G01X918078Y495177D02*
Y494415D01*
X917527Y493864D01*
X916712Y492766D01*
X916331Y492196D01*
G01X921189Y492086D02*
X920533D01*
X918675Y490228D01*
X918299D01*
G01X918131Y503330D02*
X918181Y503380D01*
Y503760D01*
X916331Y505610D01*
Y505976D01*
G01X921060Y506086D02*
X920477D01*
X918619Y507944D01*
X918299D01*
G01X994322Y388044D02*
X989297D01*
X989022Y387769D01*
X983389D01*
G01X994322Y382138D02*
X988100D01*
X986999Y381037D01*
G01X994322Y386075D02*
X989829D01*
X989674Y385920D01*
X983827D01*
X982972Y385566D01*
G01X994322Y390013D02*
X988817D01*
X988271Y389467D01*
X984691D01*
G01X994322Y395918D02*
X987755D01*
X983629Y397628D01*
G01X1002688Y379678D02*
Y375376D01*
X999440Y372128D01*
Y371782D01*
G01X1000719Y379678D02*
Y375265D01*
X999708Y374254D01*
X999004D01*
X995592Y370842D01*
Y369094D01*
X996922Y367764D01*
G01X1003672Y376725D02*
Y375049D01*
X1001186Y372563D01*
Y369258D01*
G01X1005641Y376725D02*
Y375242D01*
X1004899Y374500D01*
G01X998751Y404284D02*
Y411249D01*
X997617Y412383D01*
G01X1000719Y404284D02*
Y415668D01*
X997225Y419162D01*
G01X1014522Y376078D02*
Y374332D01*
X1015096Y373758D01*
G01X1010562Y379678D02*
Y374664D01*
X1008618Y372720D01*
Y369220D01*
X1009883Y367955D01*
G01X1013515Y376725D02*
Y375157D01*
X1013168Y374810D01*
G01X1018928Y390013D02*
X1031014D01*
X1031153Y390152D01*
G01X1008593Y404284D02*
Y412234D01*
X1010420Y414061D01*
Y416062D01*
G01X1018928Y401824D02*
X1023645D01*
X1024783Y402962D01*
G01X1025693Y380244D02*
X1023842Y382095D01*
X1022917D01*
G01X1021881Y383123D02*
X1024945D01*
X1028787Y379281D01*
X1032765D01*
G01X1021881Y385091D02*
X1024560D01*
X1028964Y380687D01*
X1033211D01*
G01X1021881Y394934D02*
X1023654D01*
X1025344Y396624D01*
X1029224D01*
X1030225Y395623D01*
X1031547D01*
G01X1021881Y390997D02*
X1028799D01*
X1029953Y392151D01*
X1031946D01*
G01X1021881Y392965D02*
X1023755D01*
X1024686Y392034D01*
X1028230D01*
X1030005Y393809D01*
X1031568D01*
G01X1022732Y399860D02*
X1025837D01*
X1026548Y400571D01*
G01X1021881Y398871D02*
X1023755D01*
X1023834Y398792D01*
X1030991D01*
G01X1021881Y400839D02*
X1024145D01*
X1025699Y402393D01*
X1030617D01*
G01X1021881Y396902D02*
X1023303D01*
X1024022Y397621D01*
X1030493D01*
X1031075Y397039D01*
X1031705D01*
G01X1272334Y154852D02*
X1273294Y155812D01*
X1274034D01*
X1282400Y164178D01*
X1284631D01*
X1285566Y163993D01*
X1286437Y164035D01*
X1286913Y164352D01*
X1287990D01*
X1288564Y163856D01*
X1289243Y163177D01*
X1290669D01*
G01X1269981Y170424D02*
X1271371Y171000D01*
X1273483D01*
X1275429Y172946D01*
X1285689D01*
X1285767Y173024D01*
G01X1276074Y185848D02*
X1277079D01*
X1278041Y186810D01*
X1287401D01*
G01X1270888Y189067D02*
X1271393Y188562D01*
X1284393D01*
X1284611Y188780D01*
X1285767D01*
G01X1274263Y154632D02*
X1282808Y163177D01*
X1287401D01*
G01X1285767Y161207D02*
X1282469D01*
X1274914Y153652D01*
G01X1271444Y156076D02*
X1272381Y157013D01*
X1273563D01*
X1281696Y165146D01*
X1285767D01*
G01X1275013Y191742D02*
X1275248Y191507D01*
X1286231D01*
X1286730Y191937D01*
X1287966D01*
X1287986Y191927D01*
X1288608Y191390D01*
X1289249Y190749D01*
X1290669D01*
G01X1289035Y192718D02*
X1287927D01*
X1286293Y193808D01*
X1285064D01*
X1284650Y193686D01*
X1280968D01*
X1278937Y195717D01*
X1271026D01*
G01X1270244Y199112D02*
X1272139Y197217D01*
X1279638D01*
X1281334Y195521D01*
X1286378D01*
X1286792Y195863D01*
X1287990D01*
X1289165Y194688D01*
X1290669D01*
G01X1279900Y154796D02*
X1280838Y155734D01*
Y156127D01*
X1283949Y159238D01*
X1287401D01*
G01X1279411Y156236D02*
X1283316Y160141D01*
X1284796D01*
X1285251Y160051D01*
X1286293Y160099D01*
X1286307Y160105D01*
X1287016Y160577D01*
X1287800D01*
X1289139Y159238D01*
X1290669D01*
G01X1269925Y158192D02*
Y159623D01*
X1271812Y161510D01*
X1273389D01*
X1278995Y167116D01*
X1287401D01*
G01X1269981Y168637D02*
X1271457Y169248D01*
X1273235D01*
X1275876Y171889D01*
X1286436D01*
X1286966Y172242D01*
X1287918D01*
X1288051Y172176D01*
X1288564Y171733D01*
X1289242Y171055D01*
X1290669D01*
G01X1269981Y163436D02*
X1270736Y164191D01*
X1272816D01*
X1277710Y169085D01*
X1285767D01*
G01X1269981Y178379D02*
X1271176D01*
X1271926Y177629D01*
X1283639D01*
X1285074Y178052D01*
X1286293D01*
X1287924Y176963D01*
X1289035D01*
G01X1285767Y180902D02*
X1282593D01*
X1280153Y178462D01*
X1273093D01*
X1271978Y179577D01*
X1269981D01*
G01X1270137Y177298D02*
X1270636Y176799D01*
X1284655D01*
X1284819Y176963D01*
X1285767D01*
G01X1269981Y175648D02*
X1272279D01*
X1272374Y175743D01*
X1285388D01*
X1286264Y175783D01*
X1286725Y176181D01*
X1287975D01*
X1288976Y175316D01*
X1289299Y174993D01*
X1290669D01*
G01X1269981Y172212D02*
X1271333Y172481D01*
X1273113D01*
X1274623Y173991D01*
X1284671D01*
X1285078Y174111D01*
X1286296D01*
X1286861Y173736D01*
X1287739Y173024D01*
X1289035D01*
G01X1269981Y182937D02*
X1273118D01*
X1274593Y181462D01*
X1279593D01*
X1281835Y183704D01*
X1286291D01*
X1286725Y184059D01*
X1286741Y184070D01*
X1287962D01*
X1288916Y183246D01*
X1289291Y182871D01*
X1290669D01*
G01X1270197Y188158D02*
X1270787Y187568D01*
X1285563D01*
X1286286Y187602D01*
X1286882Y187999D01*
X1287974D01*
X1288210Y187795D01*
X1289195Y186810D01*
X1290669D01*
G01X1269981Y184062D02*
X1273493D01*
X1275093Y182462D01*
X1279093D01*
X1281472Y184841D01*
X1285767D01*
G01X1269981Y181813D02*
X1272742D01*
X1274093Y180462D01*
X1279684D01*
X1282093Y182871D01*
X1287401D01*
G01Y194688D02*
X1281067D01*
X1279288Y196467D01*
X1271589D01*
X1270394Y197662D01*
G01X1290927Y151438D02*
Y150072D01*
X1290427Y149572D01*
X1287635D01*
X1286079Y148016D01*
G01X1281178Y153638D02*
X1281993Y154453D01*
Y156221D01*
X1283986Y158214D01*
X1284419D01*
X1285262Y158462D01*
X1286164D01*
X1286293Y158406D01*
X1286396Y158361D01*
X1288030Y157268D01*
X1289035D01*
G01X1282788Y152828D02*
X1283708Y153748D01*
X1284019D01*
X1286726Y156455D01*
X1287538Y156589D01*
X1287674Y156522D01*
X1288280Y156223D01*
X1289351Y155299D01*
X1290669D01*
G01X1269856Y161227D02*
X1271075Y162446D01*
X1272581D01*
X1278083Y167948D01*
X1286336D01*
X1286856Y168294D01*
X1287916D01*
X1289094Y167116D01*
X1290669D01*
G01X1269981Y166850D02*
X1270488Y167357D01*
X1271213Y167657D01*
X1273049D01*
X1276447Y171055D01*
X1287401D01*
G01X1289035Y180902D02*
X1287573D01*
X1286637Y181838D01*
X1286284Y181991D01*
X1285133D01*
X1284601Y181834D01*
X1282191D01*
X1279819Y179462D01*
X1273593D01*
X1272366Y180689D01*
X1269981D01*
G01Y173998D02*
X1269983Y173999D01*
X1274412Y174880D01*
X1274853Y174968D01*
X1287376D01*
X1287401Y174993D01*
G01X1271322Y190332D02*
X1272192Y189462D01*
X1283760D01*
X1285141Y189869D01*
X1286293D01*
X1287924Y188780D01*
X1289035D01*
G01X1285767Y200596D02*
X1284377D01*
X1284183Y200402D01*
X1282710D01*
X1280150Y202962D01*
X1271341D01*
X1270883Y203420D01*
G01X1271478Y213167D02*
X1273183Y211462D01*
X1276354D01*
X1278499Y209317D01*
X1284363D01*
X1285099Y209586D01*
X1286429D01*
X1286930Y209153D01*
X1287609Y208474D01*
X1289035D01*
G01X1285767Y196657D02*
X1281397D01*
X1280087Y197967D01*
X1272766D01*
X1270131Y200602D01*
G01X1290669Y206505D02*
X1289351D01*
X1287974Y207693D01*
X1286940D01*
X1286422Y207348D01*
X1275429D01*
X1274004Y208773D01*
G01X1270293Y202322D02*
X1270853Y201762D01*
X1274262D01*
X1276462Y199562D01*
X1281008D01*
X1281943Y198627D01*
X1287401D01*
G01X1274623Y215892D02*
X1279517Y210998D01*
X1282811D01*
X1283075Y211262D01*
X1286376D01*
X1286457Y211343D01*
X1287184Y211827D01*
X1287590D01*
X1287963Y211642D01*
X1288564Y211123D01*
X1289243Y210444D01*
X1290668D01*
X1290669Y210443D01*
G01X1273645Y207712D02*
X1274852Y206505D01*
X1287401D01*
G01X1273176Y205121D02*
X1273575Y204722D01*
X1284664D01*
X1284851Y204535D01*
X1285767D01*
G01X1272564Y207293D02*
X1274109Y205748D01*
X1286167D01*
X1287981Y204535D01*
X1289035D01*
G01X1274954Y221601D02*
Y220373D01*
X1278975Y216352D01*
X1285767D01*
G01X1289035D02*
X1287925D01*
X1286861Y217065D01*
X1286296Y217440D01*
X1285192D01*
X1284127Y217126D01*
X1279496D01*
X1276514Y220108D01*
Y221302D01*
G01X1287401Y222260D02*
X1287400Y222261D01*
X1285308D01*
X1283407Y224162D01*
X1282165D01*
X1280878Y225449D01*
Y226322D01*
G01X1279801Y224646D02*
X1281295Y223152D01*
X1282907D01*
X1284680Y221379D01*
X1286296D01*
X1287925Y220291D01*
X1289035D01*
G01Y224230D02*
Y226373D01*
X1287513Y227895D01*
Y229126D01*
X1286628Y230011D01*
Y230927D01*
X1284979Y232576D01*
G01X1288059Y236117D02*
X1289190Y234986D01*
X1289538Y234144D01*
Y232420D01*
X1289811Y232147D01*
Y230625D01*
X1289727Y230249D01*
Y229554D01*
X1290669Y227815D01*
Y226199D01*
G01X1286274Y240182D02*
X1291774Y234682D01*
Y234175D01*
X1290927Y233328D01*
G01X1298805Y151438D02*
Y150330D01*
X1299470Y149665D01*
Y149417D01*
X1299618Y149060D01*
X1300014Y148664D01*
Y147852D01*
X1300114Y147752D01*
Y143717D01*
X1298040Y141643D01*
Y135666D01*
X1293813Y131439D01*
G01X1300774Y149804D02*
Y148732D01*
X1300864Y148642D01*
Y143201D01*
X1299011Y141348D01*
Y134853D01*
X1295394Y131236D01*
Y130826D01*
X1294910Y130342D01*
G01X1286293Y143762D02*
X1288206D01*
X1289434Y144271D01*
X1290762Y145599D01*
Y145931D01*
X1292896Y148065D01*
Y149804D01*
G01X1278738Y164788D02*
X1280063Y166113D01*
X1284800D01*
X1285214Y166235D01*
X1286293D01*
X1287924Y165146D01*
X1289035D01*
G01X1271593Y165962D02*
X1273017D01*
X1277229Y170174D01*
X1286114D01*
X1286629Y169951D01*
X1286861Y169797D01*
X1287924Y169085D01*
X1289035D01*
G01X1278093Y184462D02*
X1279439Y185808D01*
X1284837D01*
X1285312Y185948D01*
X1286266D01*
X1287668Y185012D01*
X1287924Y184841D01*
X1289035D01*
G01X1278993Y193262D02*
X1280185D01*
X1280729Y192718D01*
X1285767D01*
G01X1273093Y200038D02*
X1274369Y198762D01*
X1280441D01*
X1281578Y197625D01*
X1284804D01*
X1285279Y197765D01*
X1286266D01*
X1287925Y196657D01*
X1289035D01*
G01X1278183Y201262D02*
X1280659D01*
X1282445Y199476D01*
X1286517D01*
X1287054Y199834D01*
X1287953D01*
X1289350Y198627D01*
X1290669D01*
G01X1272893Y191262D02*
X1274133D01*
X1275013Y190382D01*
X1283133D01*
X1284980Y190749D01*
X1287401D01*
G01X1273629Y220427D02*
X1279242Y214813D01*
X1280726D01*
X1281220Y215307D01*
X1284724D01*
X1285563Y215141D01*
X1286286Y215175D01*
X1286773Y215499D01*
X1286838Y215542D01*
X1287071Y215697D01*
X1287391Y215677D01*
X1287722Y215542D01*
X1288070Y215400D01*
X1289213Y214413D01*
X1289244Y214382D01*
X1290669D01*
G01X1273154Y218182D02*
X1274563D01*
X1279186Y213559D01*
X1280689D01*
X1281434Y214304D01*
X1283891D01*
X1283969Y214382D01*
X1287401D01*
G01X1271960Y204186D02*
X1272310Y203836D01*
X1284508D01*
X1285020Y203324D01*
X1285563D01*
X1286395Y203363D01*
X1286983Y203754D01*
X1287914D01*
X1289289Y202566D01*
X1290669D01*
G01X1273093Y213962D02*
X1275028D01*
X1278714Y210248D01*
X1283593D01*
X1283788Y210443D01*
X1287401D01*
G01X1275727Y209597D02*
X1277076Y208248D01*
X1284479D01*
X1284705Y208474D01*
X1285767D01*
G01X1290669Y222260D02*
X1289244D01*
X1288564Y222940D01*
X1287800Y223600D01*
Y224261D01*
X1284269Y227408D01*
X1283301Y228376D01*
G01X1290669Y218321D02*
X1290668Y218322D01*
X1289161D01*
X1287964Y219519D01*
X1286941D01*
X1286394Y219155D01*
X1282000D01*
X1280476Y220679D01*
Y222179D01*
X1279493Y223162D01*
X1278629D01*
X1277969Y223822D01*
G01X1278783Y221386D02*
Y219993D01*
X1280455Y218321D01*
X1287401D01*
G01X1296835Y231694D02*
X1297061Y232831D01*
Y239732D01*
X1293435Y243358D01*
X1288129D01*
X1287789Y243698D01*
G01X1296835Y228426D02*
Y229600D01*
X1296193Y230242D01*
X1295745Y231217D01*
X1295601Y231572D01*
X1295645Y232038D01*
X1295868Y232385D01*
X1296072Y232618D01*
X1296311Y233167D01*
Y233474D01*
X1296135Y234456D01*
Y239452D01*
X1292979Y242608D01*
X1281448D01*
G01X1305241Y240159D02*
X1306044Y239356D01*
Y234634D01*
X1305469Y234059D01*
Y232752D01*
X1306111Y231848D01*
X1306683Y231276D01*
Y230060D01*
G01X1307659Y243487D02*
X1308573Y242573D01*
X1309907Y239352D01*
X1310669Y238590D01*
X1311222D01*
X1311717Y238095D01*
Y237542D01*
X1312211Y237048D01*
Y234548D01*
X1312591Y234168D01*
Y231694D01*
G01X1294691Y117129D02*
X1296388Y121229D01*
X1298982Y123823D01*
X1300190Y126740D01*
Y129159D01*
X1302911Y131880D01*
Y135130D01*
X1306682Y138901D01*
Y148169D01*
X1306683Y148170D01*
G01X1304713Y153072D02*
Y151645D01*
X1304035Y150967D01*
X1303375Y150203D01*
X1303256Y149963D01*
Y149576D01*
X1303843Y148694D01*
Y147053D01*
X1303838Y147048D01*
Y139857D01*
X1300661Y136680D01*
Y133830D01*
X1297153Y130322D01*
Y128327D01*
X1295693Y126867D01*
G01X1300774Y153072D02*
Y151646D01*
X1301453Y150967D01*
X1302113Y150203D01*
X1302232Y149963D01*
Y149667D01*
X1301640Y148777D01*
Y142677D01*
X1299911Y140948D01*
Y134480D01*
X1296168Y130737D01*
Y129408D01*
X1295343Y128582D01*
G01X1291184Y113350D02*
X1291452Y116052D01*
X1293743Y120334D01*
X1294333Y121757D01*
X1297093Y124517D01*
Y126406D01*
X1298086Y127399D01*
Y130083D01*
X1301411Y133408D01*
Y136058D01*
X1304777Y139424D01*
Y148178D01*
X1304713Y148242D01*
Y149804D01*
G01X1296929Y116962D02*
X1297118Y117041D01*
X1301246Y127003D01*
Y128942D01*
X1303661Y131357D01*
Y134380D01*
X1307651Y138370D01*
Y147244D01*
X1307692Y147452D01*
X1307798Y147558D01*
Y147987D01*
X1307855Y148275D01*
X1307798Y148431D01*
Y148782D01*
X1307488Y149092D01*
X1307313Y149354D01*
Y149830D01*
X1307557Y150486D01*
X1307973Y150967D01*
X1308652Y151646D01*
Y153072D01*
G01X1306683Y151438D02*
Y150327D01*
X1305630Y148752D01*
X1305554Y148577D01*
Y147565D01*
X1305716Y147015D01*
Y139301D01*
X1302161Y135746D01*
Y132830D01*
X1299093Y129762D01*
Y126966D01*
X1298293Y126166D01*
Y124232D01*
X1295055Y120994D01*
X1293151Y116401D01*
G01X1298805Y148170D02*
Y147190D01*
X1299314Y146681D01*
Y144074D01*
X1296966Y141726D01*
Y136785D01*
X1292716Y132535D01*
G01X1290566Y142835D02*
Y144335D01*
X1293647Y147416D01*
Y148659D01*
X1294866Y149878D01*
Y151438D01*
G01X1297605Y145824D02*
Y148435D01*
X1297751Y148788D01*
X1298111Y149148D01*
Y149951D01*
X1297830Y150629D01*
X1296835Y151624D01*
Y153072D01*
G01X1288637Y240448D02*
X1289037D01*
X1290361Y239124D01*
Y238064D01*
X1292681Y235744D01*
Y233279D01*
X1292887Y232248D01*
G02X1292894Y232208I-870J-173D01*
G01Y231696D01*
X1292896Y231694D01*
G01X1292630Y240462D02*
X1292637D01*
Y240448D01*
X1292237D01*
X1291111Y239322D01*
Y238375D01*
X1293439Y236047D01*
X1293463Y233862D01*
X1293471Y233187D01*
X1293584Y232773D01*
X1293709Y232559D01*
X1293904Y232340D01*
X1294054Y232210D01*
X1294234Y232083D01*
X1294401Y231929D01*
X1294866Y231046D01*
Y230060D01*
G01X1282176Y221436D02*
X1283544D01*
X1284689Y220291D01*
X1285767D01*
G01X1282645Y255671D02*
X1284005Y254311D01*
X1287623D01*
X1290480Y251454D01*
X1291047D01*
X1291613Y250887D01*
Y250321D01*
X1292178Y249756D01*
X1292745D01*
X1293311Y249189D01*
Y248623D01*
X1293876Y248058D01*
X1294443D01*
X1295009Y247491D01*
Y246925D01*
X1295574Y246360D01*
X1296141D01*
X1296707Y245793D01*
Y245227D01*
X1297272Y244662D01*
X1297839D01*
X1298405Y244095D01*
Y243529D01*
X1298970Y242964D01*
X1299537D01*
X1300103Y242397D01*
Y241831D01*
X1300668Y241266D01*
X1301235D01*
X1301801Y240699D01*
Y240133D01*
X1302366Y239568D01*
X1302933D01*
X1303499Y239002D01*
Y238435D01*
X1304712Y237222D01*
Y232678D01*
X1304713Y232677D01*
Y231694D01*
G01X1282645Y252271D02*
X1283936Y253562D01*
X1287312D01*
X1303963Y236911D01*
Y232678D01*
X1303500Y232215D01*
Y231118D01*
X1304533Y229748D01*
X1304713Y229568D01*
Y228426D01*
G01X1298805Y233328D02*
Y234061D01*
X1297811Y235055D01*
Y240115D01*
X1293364Y244562D01*
X1290083D01*
X1286274Y248371D01*
Y248618D01*
X1285710Y249182D01*
G01X1290293Y247562D02*
X1292193Y245662D01*
X1293393D01*
X1298561Y240494D01*
Y235457D01*
X1300018Y234000D01*
Y232752D01*
X1298805Y231539D01*
Y230060D01*
G01X1305963Y241870D02*
X1306794Y241039D01*
Y233439D01*
X1306683Y233328D01*
G01X1310899Y243246D02*
X1311293Y242852D01*
Y240966D01*
X1314560Y237699D01*
Y233328D01*
G01X1309068Y243486D02*
X1309507Y243047D01*
X1310465Y240733D01*
X1313810Y237388D01*
Y234522D01*
X1313347Y234059D01*
Y232752D01*
X1314560Y231539D01*
Y230060D01*
G01X1306349Y243306D02*
X1307522Y242133D01*
X1308552Y239646D01*
X1311461Y236737D01*
Y234237D01*
X1311841Y233857D01*
Y232678D01*
X1311378Y232215D01*
Y231118D01*
X1312411Y229748D01*
X1312591Y229568D01*
Y228426D01*
G01X1311320Y245964D02*
X1311381Y245903D01*
Y245711D01*
X1313159Y243933D01*
Y241235D01*
X1314536Y239856D01*
X1315074D01*
X1315803Y239127D01*
Y238589D01*
X1316530Y237861D01*
Y235988D01*
X1316920Y235598D01*
Y234898D01*
X1316530Y234508D01*
Y231694D01*
G01X1310598Y245242D02*
X1310659Y245181D01*
X1310851D01*
X1312410Y243622D01*
Y240924D01*
X1315781Y237550D01*
Y235988D01*
X1315780Y235987D01*
Y232716D01*
X1315317Y232253D01*
Y231118D01*
X1316530Y229905D01*
Y228426D01*
G01X1306129Y121306D02*
X1306917Y122094D01*
Y133052D01*
X1311590Y137725D01*
Y146888D01*
X1311776Y147827D01*
X1311731Y148826D01*
X1311403Y149318D01*
Y150378D01*
X1311912Y150967D01*
X1312591Y151646D01*
Y153072D01*
G01X1308652Y149804D02*
Y137971D01*
X1304656Y133975D01*
Y123525D01*
X1303280Y122149D01*
X1300344Y117756D01*
X1299730Y116274D01*
G01X1314560Y151438D02*
Y150326D01*
X1313472Y148698D01*
Y147608D01*
X1313615Y147122D01*
Y137626D01*
X1308417Y132428D01*
Y121810D01*
X1309164Y121063D01*
Y120432D01*
G01X1318499Y151438D02*
Y150326D01*
X1317290Y148518D01*
Y147748D01*
X1317554Y146851D01*
Y134196D01*
X1315696Y132338D01*
X1313627D01*
X1312588Y131299D01*
Y127632D01*
X1314065Y126155D01*
Y123095D01*
G01X1320469Y153072D02*
Y151646D01*
X1319790Y150967D01*
X1319281Y150378D01*
Y149431D01*
X1319491Y149118D01*
X1319630Y148699D01*
X1319665Y147966D01*
X1319468Y146971D01*
Y132810D01*
X1318800Y132142D01*
Y123996D01*
G01X1312591Y149804D02*
Y137664D01*
X1307667Y132740D01*
Y120792D01*
G01X1314560Y148170D02*
Y137509D01*
X1309167Y132116D01*
Y122958D01*
X1310525Y121600D01*
Y120822D01*
G01X1312384Y120118D02*
Y124089D01*
X1311241Y125232D01*
G01X1310621Y151438D02*
Y150326D01*
X1309493Y148639D01*
Y147773D01*
X1309676Y147151D01*
Y137933D01*
X1305417Y133674D01*
Y123224D01*
X1303866Y121673D01*
X1302080Y117361D01*
Y117032D01*
G01X1310621Y148170D02*
Y137817D01*
X1306167Y133363D01*
Y122912D01*
X1305034Y121779D01*
X1303810Y118824D01*
Y115602D01*
X1302060Y113852D01*
G01X1316530Y149804D02*
Y148850D01*
X1316532Y148848D01*
Y146410D01*
X1316610Y146332D01*
Y134652D01*
X1315461Y133503D01*
X1312926D01*
X1311241Y131818D01*
Y125232D01*
G01X1300493Y238062D02*
X1302744Y235811D01*
Y233328D01*
G01X1300393Y235762D02*
X1301393Y234762D01*
Y232762D01*
X1302744Y231411D01*
Y230060D01*
G01X1312643Y248368D02*
Y247380D01*
X1315400Y244623D01*
Y241442D01*
X1318011Y238831D01*
Y234773D01*
X1317286Y234048D01*
Y232752D01*
X1318499Y231539D01*
Y230060D01*
G01X1309993Y265099D02*
Y265055D01*
X1310129Y264919D01*
Y259569D01*
X1319073Y250625D01*
Y242521D01*
X1323658Y237936D01*
Y232796D01*
X1323195Y232333D01*
Y231118D01*
X1324408Y229905D01*
Y228426D01*
G01X1311013Y265099D02*
Y265012D01*
X1310878Y264877D01*
Y262297D01*
X1311268Y261907D01*
Y261207D01*
X1310878Y260817D01*
Y259880D01*
X1312112Y258646D01*
X1312665D01*
X1313160Y258151D01*
Y257598D01*
X1313654Y257104D01*
X1314207D01*
X1314702Y256609D01*
Y256056D01*
X1315196Y255562D01*
X1315749D01*
X1316244Y255067D01*
Y254514D01*
X1316738Y254020D01*
X1317291D01*
X1317786Y253525D01*
Y252972D01*
X1318280Y252478D01*
X1318833D01*
X1319328Y251983D01*
Y251430D01*
X1319822Y250936D01*
Y249372D01*
X1320212Y248982D01*
Y248282D01*
X1319822Y247892D01*
Y247192D01*
X1320212Y246802D01*
Y246102D01*
X1319822Y245712D01*
Y245012D01*
X1320212Y244622D01*
Y243922D01*
X1319822Y243532D01*
Y242832D01*
X1320316Y242338D01*
X1320869D01*
X1321364Y241843D01*
Y241290D01*
X1321858Y240796D01*
X1322411D01*
X1322906Y240301D01*
Y239748D01*
X1324407Y238247D01*
Y237547D01*
X1324797Y237157D01*
Y236457D01*
X1324407Y236067D01*
Y232796D01*
X1324408Y232795D01*
Y231694D01*
G01X1302332Y263777D02*
Y263497D01*
X1307107Y258722D01*
X1307387D01*
X1316303Y249806D01*
Y241620D01*
X1318799Y239124D01*
Y234136D01*
X1318499Y233836D01*
Y233328D01*
G01X1308653Y259758D02*
X1317804Y250607D01*
Y242579D01*
X1320411Y239972D01*
Y233906D01*
X1320469Y233848D01*
Y231694D01*
G01X1307512Y259720D02*
X1317054Y250178D01*
Y242108D01*
X1319661Y239501D01*
Y233906D01*
X1319619Y233864D01*
Y232738D01*
X1319256Y232375D01*
Y231118D01*
X1320469Y229905D01*
Y228426D01*
G01X1323354Y119071D02*
X1324923Y122859D01*
Y133507D01*
X1324446Y133984D01*
Y144304D01*
X1325541Y145399D01*
Y146473D01*
X1325242Y147489D01*
Y148803D01*
X1325670Y149446D01*
X1326377Y150153D01*
Y151438D01*
G01X1320469Y149804D02*
Y131166D01*
X1319694Y130391D01*
Y122772D01*
G01X1321810Y125106D02*
Y123202D01*
X1321018Y121290D01*
X1319623Y119202D01*
X1319468Y118828D01*
G01X1322438Y148170D02*
Y147106D01*
X1322193Y146861D01*
Y134796D01*
X1323883Y133106D01*
Y123355D01*
X1322896Y120969D01*
X1321595Y119671D01*
X1321490Y119417D01*
G01X1328346Y153072D02*
X1328347Y153071D01*
Y151646D01*
X1327668Y150967D01*
X1327159Y150378D01*
Y149278D01*
X1327555Y148683D01*
X1327590Y147952D01*
X1327371Y146846D01*
Y143412D01*
X1326893Y142934D01*
Y120943D01*
G01X1328346Y149804D02*
Y148948D01*
X1328347D01*
Y143080D01*
X1327741Y142474D01*
Y126862D01*
X1327904Y126699D01*
Y125582D01*
G01X1326377Y148170D02*
X1326441Y148106D01*
Y144478D01*
X1326195Y144232D01*
G01X1322438Y151438D02*
Y150330D01*
X1321350Y148696D01*
Y133644D01*
X1321810Y133184D01*
Y125106D01*
G01X1332285Y153072D02*
X1332286Y153071D01*
Y151646D01*
X1331607Y150967D01*
X1331098Y150378D01*
Y149228D01*
X1331281Y148952D01*
X1331436Y148797D01*
Y147274D01*
X1331285Y146509D01*
Y142197D01*
X1329988Y140900D01*
Y132517D01*
X1333783Y128722D01*
Y118173D01*
G01X1330316Y151438D02*
Y150331D01*
X1329157Y148589D01*
Y142685D01*
X1328490Y142018D01*
Y127452D01*
X1329054Y126888D01*
Y125582D01*
G01X1330316Y148170D02*
Y142551D01*
X1329239Y141474D01*
Y132017D01*
X1332161Y129095D01*
Y128642D01*
G01X1315156Y130656D02*
X1318499Y133999D01*
Y148170D01*
G01X1314920Y135361D02*
X1315529Y135970D01*
Y144618D01*
X1315597Y144962D01*
X1315666Y145309D01*
Y148889D01*
X1315344Y149211D01*
Y150380D01*
X1315851Y150967D01*
X1316530Y151646D01*
Y153072D01*
G01X1327523Y239232D02*
X1327963Y238792D01*
Y233365D01*
X1328346Y232982D01*
Y231694D01*
G01X1329186Y240202D02*
Y232633D01*
X1329531Y232288D01*
Y231089D01*
X1328346Y229904D01*
Y228426D01*
G01X1332285D02*
X1331911Y229748D01*
X1331298Y230749D01*
X1331104Y231437D01*
Y232241D01*
X1331536Y232673D01*
Y233745D01*
X1331231Y234050D01*
Y236100D01*
X1332400Y237269D01*
Y257755D01*
X1331130Y259025D01*
Y261246D01*
X1330994Y261382D01*
Y261469D01*
G01X1332285Y231694D02*
Y234056D01*
X1331980Y234361D01*
Y235789D01*
X1333149Y236958D01*
Y238322D01*
X1333529Y238702D01*
Y239702D01*
X1333149Y240082D01*
Y241082D01*
X1333529Y241462D01*
Y242462D01*
X1333149Y242842D01*
Y243842D01*
X1333529Y244222D01*
Y245222D01*
X1333149Y245602D01*
Y246602D01*
X1333529Y246982D01*
Y247982D01*
X1333149Y248362D01*
Y249362D01*
X1333529Y249742D01*
Y250742D01*
X1333149Y251122D01*
Y252122D01*
X1333529Y252502D01*
Y253502D01*
X1333149Y253882D01*
Y254882D01*
X1333529Y255262D01*
Y256262D01*
X1333149Y256642D01*
Y258066D01*
X1331879Y259336D01*
Y261247D01*
X1332014Y261382D01*
Y261469D01*
G01X1335199Y264231D02*
Y264144D01*
X1335340Y264003D01*
Y236907D01*
X1335474Y236583D01*
Y232672D01*
X1335011Y232209D01*
Y231118D01*
X1335850Y229748D01*
X1336224Y228426D01*
G01X1336219Y264231D02*
Y264134D01*
X1336089Y264004D01*
Y251013D01*
X1336469Y250633D01*
Y249633D01*
X1336089Y249253D01*
Y248253D01*
X1336469Y247873D01*
Y246873D01*
X1336089Y246493D01*
Y245493D01*
X1336469Y245113D01*
Y244113D01*
X1336089Y243733D01*
Y242733D01*
X1336469Y242353D01*
Y241353D01*
X1336089Y240973D01*
Y239973D01*
X1336469Y239593D01*
Y238593D01*
X1336089Y238213D01*
Y237057D01*
X1336223Y236732D01*
Y232672D01*
X1336224Y232671D01*
Y231694D01*
G01Y149804D02*
Y148948D01*
X1336225D01*
Y145495D01*
X1336500Y145220D01*
Y133569D01*
X1340912Y129157D01*
Y125092D01*
G01X1332285Y149804D02*
Y148851D01*
X1332288Y148848D01*
Y141742D01*
X1330737Y140191D01*
Y133138D01*
X1334883Y128992D01*
Y119082D01*
G01X1337943Y124721D02*
X1337449Y125215D01*
Y131204D01*
X1335751Y132902D01*
Y144493D01*
X1335476Y144768D01*
Y148619D01*
X1335037Y149278D01*
Y150378D01*
X1335546Y150967D01*
X1336225Y151646D01*
Y153071D01*
X1336224Y153072D01*
G01X1337114Y118849D02*
X1335658Y120305D01*
Y130097D01*
X1334200Y131555D01*
Y141242D01*
X1333633Y141809D01*
Y145964D01*
X1333167Y147548D01*
Y148696D01*
X1333811Y149663D01*
Y149880D01*
X1334255Y150324D01*
Y151438D01*
G01X1342519Y124877D02*
X1341804Y125592D01*
Y129714D01*
X1337249Y134269D01*
Y146834D01*
X1337106Y147320D01*
Y148696D01*
X1337611Y149455D01*
Y149779D01*
X1338194Y150362D01*
Y151438D01*
G01X1347257Y134986D02*
X1346344Y135899D01*
Y143105D01*
X1345127Y144322D01*
Y146904D01*
X1344984Y147390D01*
Y148841D01*
X1345356Y149701D01*
Y150026D01*
X1344893Y151146D01*
Y152062D01*
X1345903Y153072D01*
X1348041D01*
G01X1346174Y132812D02*
X1344744Y134242D01*
Y142522D01*
X1343102Y144164D01*
Y146600D01*
X1343351Y147855D01*
X1343311Y148683D01*
X1342915Y149278D01*
Y150378D01*
X1344102Y151752D01*
Y153072D01*
G01X1342133Y151438D02*
Y150402D01*
X1341689Y149958D01*
Y149663D01*
X1340974Y148589D01*
Y147820D01*
X1341188Y147093D01*
Y136130D01*
X1348504Y128814D01*
Y127662D01*
X1348939Y127227D01*
G01X1346564Y134052D02*
X1345523Y135093D01*
Y142812D01*
X1344103Y144232D01*
Y148948D01*
X1344102D01*
Y149804D01*
G01X1346900Y125097D02*
X1346374Y125623D01*
Y128079D01*
X1339163Y135290D01*
Y147008D01*
X1339320Y147800D01*
X1339270Y148836D01*
X1338976Y149278D01*
Y150378D01*
X1339485Y150967D01*
X1340164Y151646D01*
Y153071D01*
X1340163Y153072D01*
G01X1348094Y125832D02*
X1347474Y126452D01*
Y128398D01*
X1340166Y135706D01*
Y148848D01*
X1340163Y148851D01*
Y149804D01*
G01X1338194Y148170D02*
Y134661D01*
X1342913Y129942D01*
Y126563D01*
X1344259Y125217D01*
G01X1334255Y148170D02*
X1334470Y147955D01*
Y143727D01*
X1335002Y143195D01*
Y132280D01*
X1336575Y130707D01*
G01X1346071Y151438D02*
X1348217D01*
X1349293Y150362D01*
Y149571D01*
X1348667Y148058D01*
Y146587D01*
X1348042Y145962D01*
Y144871D01*
X1349334Y143579D01*
X1349758D01*
X1352575Y140762D01*
Y139971D01*
X1353089Y139457D01*
G01X1347644Y138422D02*
X1347128Y138938D01*
Y143398D01*
X1346072Y144454D01*
Y148169D01*
X1346071Y148170D01*
G01X1343034Y141698D02*
X1342133Y142599D01*
Y148170D01*
G01X1339329Y260109D02*
Y260022D01*
X1339465Y259886D01*
Y258886D01*
X1338311Y257732D01*
Y235980D01*
X1337444Y235113D01*
Y234306D01*
X1336981Y233843D01*
Y232752D01*
X1337820Y231382D01*
X1338194Y230060D01*
G01X1340349Y260109D02*
Y260022D01*
X1340214Y259887D01*
Y258575D01*
X1339060Y257421D01*
Y252008D01*
X1339445Y251623D01*
Y250873D01*
X1339060Y250488D01*
Y249738D01*
X1339445Y249353D01*
Y248603D01*
X1339060Y248218D01*
Y247468D01*
X1339445Y247083D01*
Y246333D01*
X1339060Y245948D01*
Y245198D01*
X1339451Y244807D01*
Y244107D01*
X1339061Y243717D01*
Y243017D01*
X1339451Y242627D01*
Y241927D01*
X1339060Y241536D01*
Y235669D01*
X1338194Y234803D01*
Y233328D01*
G01X1342133D02*
X1341670Y233791D01*
Y234391D01*
X1342060Y234781D01*
Y235381D01*
X1341670Y235771D01*
Y236371D01*
X1342060Y236761D01*
Y237361D01*
X1341670Y237751D01*
Y238351D01*
X1342060Y238741D01*
Y239341D01*
X1341669Y239732D01*
Y240477D01*
X1342570Y241378D01*
Y242097D01*
X1342960Y242487D01*
Y243087D01*
X1342570Y243477D01*
Y244077D01*
X1342960Y244467D01*
Y245067D01*
X1342570Y245457D01*
Y246057D01*
X1342960Y246447D01*
Y247047D01*
X1342570Y247437D01*
Y248037D01*
X1342960Y248427D01*
Y249027D01*
X1342570Y249417D01*
Y250017D01*
X1342960Y250407D01*
Y251007D01*
X1342570Y251397D01*
Y251997D01*
X1342960Y252387D01*
Y252987D01*
X1342570Y253377D01*
Y254842D01*
X1344634Y256906D01*
Y258635D01*
X1344774Y258775D01*
Y258852D01*
X1344764Y258862D01*
G01X1344102Y231694D02*
Y240112D01*
X1344877Y240887D01*
Y241487D01*
X1345267Y241877D01*
Y242477D01*
X1344877Y242867D01*
Y243467D01*
X1345267Y243857D01*
Y244457D01*
X1344877Y244847D01*
Y245447D01*
X1345267Y245837D01*
Y246437D01*
X1344877Y246827D01*
Y247427D01*
X1345267Y247817D01*
Y248417D01*
X1344877Y248807D01*
Y249407D01*
X1345267Y249797D01*
Y250397D01*
X1344877Y250787D01*
Y252586D01*
X1345396Y253105D01*
X1345948D01*
X1346373Y253530D01*
Y254082D01*
X1347202Y254911D01*
X1347755D01*
X1348179Y255335D01*
Y255888D01*
X1349171Y256880D01*
Y258077D01*
X1349306Y258212D01*
Y258299D01*
G01X1355451Y260899D02*
Y260812D01*
X1355316Y260677D01*
Y258092D01*
X1353940Y256716D01*
Y256163D01*
X1353515Y255739D01*
X1352963D01*
X1352539Y255315D01*
Y254762D01*
X1352114Y254338D01*
X1351562D01*
X1351138Y253914D01*
Y253361D01*
X1350713Y252937D01*
X1350161D01*
X1349737Y252513D01*
Y251960D01*
X1349312Y251536D01*
X1348760D01*
X1348336Y251112D01*
Y250559D01*
X1347911Y250135D01*
X1347359D01*
X1346935Y249711D01*
Y248496D01*
X1347325Y248106D01*
Y247506D01*
X1346935Y247116D01*
Y246516D01*
X1347325Y246126D01*
Y245526D01*
X1346935Y245136D01*
Y244536D01*
X1347325Y244146D01*
Y243546D01*
X1346935Y243156D01*
Y242556D01*
X1347325Y242166D01*
Y241566D01*
X1346935Y241176D01*
Y240356D01*
X1345608Y239029D01*
Y238429D01*
X1345998Y238039D01*
Y237439D01*
X1345608Y237049D01*
Y236449D01*
X1345998Y236059D01*
Y235459D01*
X1345608Y235069D01*
Y233791D01*
X1346071Y233328D01*
G01X1342133Y230060D02*
X1340920Y232988D01*
Y240788D01*
X1341821Y241689D01*
Y255153D01*
X1343885Y257217D01*
Y258677D01*
X1343744Y258818D01*
Y258862D01*
G01X1348286Y258299D02*
Y258212D01*
X1348422Y258076D01*
Y257191D01*
X1344128Y252897D01*
Y241198D01*
X1343353Y240423D01*
Y232841D01*
X1342955Y232105D01*
X1342887Y231790D01*
X1342911Y231441D01*
X1342991Y231100D01*
X1344102Y228426D01*
G01X1346071Y230060D02*
X1344858Y232988D01*
Y233790D01*
X1344859Y233791D01*
Y239340D01*
X1346186Y240667D01*
Y250022D01*
X1354567Y258403D01*
Y260676D01*
X1354431Y260812D01*
Y260899D01*
G01X1348041Y149804D02*
Y148710D01*
X1347693Y148362D01*
Y146862D01*
X1347041Y146210D01*
Y144698D01*
X1349275Y142464D01*
X1349699D01*
X1350974Y141189D01*
Y139462D01*
X1351434Y139002D01*
G01X1361196Y133519D02*
X1351493Y143222D01*
Y146170D01*
X1351101Y146562D01*
Y147376D01*
X1351145Y148634D01*
X1350523Y149568D01*
Y149963D01*
X1350642Y150203D01*
X1351302Y150967D01*
X1351981Y151646D01*
Y153071D01*
X1351980Y153072D01*
G01X1362606Y133453D02*
X1352243Y143816D01*
Y146799D01*
X1351980Y147062D01*
Y149804D01*
G01X1353949Y151438D02*
Y150318D01*
X1353511Y149880D01*
Y149670D01*
X1352862Y148696D01*
Y147671D01*
X1353005Y147185D01*
Y144554D01*
X1364016Y133543D01*
G01X1362704Y139706D02*
X1361797D01*
X1355919Y145584D01*
Y149804D01*
G01X1363314Y142985D02*
X1362611D01*
X1360393Y145203D01*
Y148670D01*
X1360746Y149023D01*
X1361574Y150033D01*
X1361794Y150361D01*
X1361827Y150441D01*
Y151438D01*
G01X1359738Y144125D02*
X1359444Y144419D01*
Y148513D01*
X1357898Y150187D01*
X1357888Y150209D01*
Y151438D01*
G01X1364039Y137936D02*
X1363573Y138402D01*
X1361861D01*
X1354919Y145344D01*
Y146586D01*
X1355048Y147235D01*
Y148982D01*
X1354693Y149337D01*
Y150093D01*
X1354850Y150514D01*
X1355241Y150967D01*
X1355920Y151646D01*
Y153071D01*
X1355919Y153072D01*
G01X1363005Y136192D02*
X1353949Y145248D01*
Y148170D01*
G01X1371418Y157806D02*
X1371016Y158208D01*
X1368457D01*
X1368010Y158655D01*
X1366748D01*
X1366301Y158492D01*
X1365895Y158150D01*
X1365793Y158048D01*
X1364787D01*
X1363597Y159238D01*
X1362085D01*
G01X1393482Y146456D02*
X1393421Y146517D01*
X1393229D01*
X1392124Y147622D01*
Y150812D01*
X1376790Y166146D01*
X1376763D01*
X1375988Y166921D01*
X1372732D01*
X1371771Y167882D01*
X1366499D01*
X1366254Y168127D01*
X1365809Y168311D01*
X1364787D01*
X1364325Y167912D01*
X1364190Y167795D01*
X1363789Y167394D01*
X1363117Y167116D01*
X1362085D01*
G01X1380491Y150804D02*
Y150891D01*
X1380356Y151026D01*
Y153456D01*
X1380355Y153457D01*
Y156199D01*
X1373405Y163149D01*
X1370457D01*
X1369676Y163930D01*
X1366720D01*
X1365660Y164369D01*
X1364784D01*
X1364209Y163872D01*
X1363168Y163177D01*
X1362085D01*
G01X1395773Y177016D02*
X1393598Y179191D01*
Y180061D01*
X1392697Y180962D01*
X1390198D01*
X1387257Y183903D01*
X1384872D01*
X1384410Y183902D01*
X1367753D01*
X1367526Y183675D01*
X1366304D01*
X1365930Y184049D01*
X1364756D01*
X1364188Y183558D01*
X1363501Y182871D01*
X1362085D01*
G01Y171055D02*
X1363119D01*
X1364377Y171895D01*
X1364792Y172254D01*
X1365590D01*
X1366680Y171803D01*
X1367604D01*
X1368982Y171232D01*
X1378331D01*
X1394756Y154807D01*
X1396792D01*
X1396927Y154942D01*
X1397014D01*
G01X1373591Y176430D02*
X1374545Y175476D01*
Y174812D01*
X1373965Y174232D01*
X1370447D01*
X1368914Y175765D01*
X1366597D01*
X1365585Y176184D01*
X1364879D01*
X1364543Y175893D01*
X1363196Y174993D01*
X1362085D01*
G01Y178932D02*
X1363154D01*
X1364843Y180062D01*
X1365763Y180199D01*
X1366468Y179679D01*
X1367812Y179675D01*
X1368501Y180362D01*
X1369417Y180741D01*
X1382114D01*
X1393754Y169101D01*
X1397122D01*
X1397257Y169236D01*
X1397344D01*
G01X1362085Y190749D02*
X1363511D01*
X1364190Y190070D01*
X1364766Y189573D01*
X1366091D01*
X1366543Y190025D01*
X1372235D01*
X1374011Y188249D01*
X1404483D01*
X1406139Y186593D01*
Y185573D01*
X1404829Y184263D01*
G01X1406500Y193762D02*
X1406413D01*
X1406278Y193897D01*
X1404835D01*
X1403403Y192465D01*
X1374594D01*
X1373137Y193922D01*
X1366499D01*
X1366057Y193480D01*
X1364803D01*
X1364190Y194009D01*
X1363511Y194688D01*
X1362085D01*
G01X1389256Y197668D02*
X1390581Y198993D01*
Y199501D01*
X1390229Y199853D01*
X1377075D01*
X1375100Y197878D01*
X1366509D01*
X1366156Y197525D01*
X1365212Y197432D01*
X1364755Y197547D01*
X1363140Y198627D01*
X1362085D01*
G01Y214382D02*
X1363203D01*
X1363869Y214106D01*
X1364656Y213319D01*
X1364962Y213192D01*
X1365675D01*
X1366424Y213502D01*
X1367827D01*
X1369266Y214098D01*
X1369268Y214099D01*
X1380411D01*
X1381198Y214425D01*
X1384305Y215712D01*
X1389758D01*
X1391241Y216326D01*
X1392174Y217260D01*
X1392366D01*
X1392427Y217321D01*
G01X1362085Y202566D02*
X1363045D01*
X1363839Y202237D01*
X1364190Y201886D01*
X1364489Y201628D01*
X1365170Y201375D01*
X1366075D01*
X1366452Y201752D01*
X1373240D01*
X1374850Y203362D01*
X1386750D01*
X1387721Y204333D01*
X1404299D01*
X1408111Y200521D01*
Y198993D01*
X1406786Y197668D01*
G01X1394387Y211181D02*
X1394300D01*
X1394164Y211045D01*
X1374500D01*
X1370237Y206782D01*
X1367515D01*
X1367043Y207254D01*
X1366401D01*
X1365973Y207682D01*
X1364988D01*
X1364690Y207559D01*
X1363113Y206505D01*
X1362085D01*
G01X1349653Y246749D02*
Y246662D01*
X1349518Y246527D01*
Y244409D01*
X1349908Y244019D01*
Y243419D01*
X1349518Y243029D01*
Y242429D01*
X1349908Y242039D01*
Y241439D01*
X1349518Y241049D01*
Y240771D01*
X1348041Y239294D01*
Y238372D01*
X1348431Y237982D01*
Y237382D01*
X1348041Y236992D01*
Y236392D01*
X1348431Y236002D01*
Y235402D01*
X1348041Y235012D01*
Y231694D01*
G01X1350010Y233328D02*
Y233999D01*
X1350410Y234399D01*
Y234999D01*
X1350010Y235399D01*
Y236061D01*
X1350410Y236461D01*
Y237061D01*
X1350010Y237461D01*
Y238251D01*
X1350632Y238873D01*
X1351185D01*
X1351609Y239297D01*
Y239850D01*
X1352195Y240436D01*
Y241142D01*
X1352585Y241532D01*
Y242132D01*
X1352195Y242522D01*
Y243166D01*
X1352336Y243307D01*
Y243384D01*
X1352326Y243394D01*
G01X1351980Y231694D02*
Y234988D01*
X1352360Y235368D01*
Y236068D01*
X1351980Y236448D01*
Y237148D01*
X1352915Y238083D01*
X1353454D01*
X1353949Y238578D01*
Y239117D01*
X1354563Y239731D01*
Y240156D01*
X1355057Y240650D01*
X1355596D01*
X1356091Y241145D01*
Y241684D01*
X1356585Y242178D01*
X1357124D01*
X1357619Y242673D01*
Y243212D01*
X1358113Y243706D01*
X1358652D01*
X1359147Y244201D01*
Y244740D01*
X1359641Y245234D01*
X1360180D01*
X1360675Y245729D01*
Y246268D01*
X1361817Y247410D01*
X1362009D01*
X1362070Y247471D01*
G01X1353949Y233328D02*
Y233787D01*
X1354339Y234177D01*
Y234577D01*
X1353949Y234967D01*
Y235421D01*
X1354302Y235774D01*
X1354855D01*
X1355208Y236128D01*
Y236680D01*
X1355561Y237033D01*
X1356114D01*
X1356467Y237387D01*
Y237939D01*
X1356820Y238292D01*
X1357373D01*
X1357726Y238646D01*
Y239198D01*
X1358392Y239864D01*
X1358825Y240112D01*
X1359358Y239968D01*
X1359792Y240217D01*
X1359937Y240750D01*
X1360370Y240998D01*
X1360903Y240854D01*
X1361337Y241103D01*
X1361482Y241636D01*
X1361915Y241884D01*
X1362448Y241740D01*
X1362882Y241989D01*
X1363027Y242522D01*
X1364320Y243264D01*
X1364505Y243213D01*
X1364580Y243256D01*
G01X1369461Y239374D02*
X1369374D01*
X1369238Y239510D01*
X1368240D01*
X1367850Y239120D01*
X1367250D01*
X1366860Y239510D01*
X1366260D01*
X1365870Y239120D01*
X1365270D01*
X1364880Y239510D01*
X1364280D01*
X1363890Y239120D01*
X1363290D01*
X1362900Y239510D01*
X1362300D01*
X1362299Y239509D01*
X1361604Y239221D01*
X1361393Y238711D01*
X1360838Y238481D01*
X1360328Y238692D01*
X1359814Y238479D01*
X1359746Y238451D01*
X1358721Y237426D01*
Y236873D01*
X1358296Y236449D01*
X1357744D01*
X1357320Y236025D01*
Y235473D01*
X1356895Y235049D01*
X1356343D01*
X1355919Y234625D01*
Y234125D01*
X1356309Y233735D01*
Y233235D01*
X1355919Y232845D01*
Y231694D01*
G01X1348633Y246749D02*
Y246662D01*
X1348769Y246526D01*
Y241082D01*
X1347292Y239605D01*
Y232713D01*
X1346828Y232249D01*
Y231354D01*
X1348041Y228426D01*
G01X1351306Y243384D02*
Y243307D01*
X1351446Y243167D01*
Y240747D01*
X1349261Y238562D01*
Y234783D01*
X1348860Y234382D01*
Y232836D01*
X1350010Y230060D01*
G01X1351980Y228426D02*
X1350804Y231264D01*
Y232118D01*
X1351231Y233150D01*
Y237459D01*
X1353814Y240042D01*
Y240467D01*
X1361287Y247940D01*
Y248132D01*
X1361348Y248193D01*
G01X1364072Y244141D02*
X1363997Y244098D01*
X1363948Y243915D01*
X1357948Y240474D01*
X1357942D01*
X1355937Y238469D01*
X1355936D01*
X1353200Y235732D01*
Y234659D01*
X1352859Y234318D01*
Y233149D01*
X1353034Y232269D01*
X1353949Y230060D01*
G01X1355919Y228426D02*
X1355327Y229961D01*
X1354693Y231387D01*
Y231908D01*
X1354925Y232468D01*
X1355170Y232713D01*
Y234936D01*
X1359321Y239087D01*
X1359814Y239291D01*
X1362150Y240259D01*
X1369239D01*
X1369374Y240394D01*
X1369461D01*
G01X1364001Y236980D02*
X1362077Y235056D01*
X1360646Y234463D01*
X1360423Y234240D01*
Y232829D01*
X1361020Y232172D01*
X1361719Y231318D01*
X1361827Y231059D01*
Y230060D01*
G01X1360186Y226264D02*
Y226287D01*
X1359858Y226615D01*
Y228426D01*
G01X1371638Y223507D02*
X1370941Y222810D01*
X1366826D01*
X1366290Y223011D01*
X1366044Y223227D01*
X1365701Y223446D01*
X1365235Y223539D01*
X1364060Y223061D01*
X1363259Y222260D01*
X1362085D01*
G01X1371244Y218398D02*
X1369007D01*
X1368166Y217557D01*
X1366500D01*
X1366058Y217115D01*
X1364938D01*
X1363543Y218321D01*
X1362085D01*
G01X1363719Y157268D02*
X1364997D01*
X1365735Y156530D01*
X1365744Y156522D01*
X1366877Y155543D01*
X1369100D01*
X1369349Y155792D01*
X1370624D01*
X1371004Y155412D01*
G01X1371324Y156432D02*
X1370824Y156932D01*
X1369063D01*
X1368545Y156414D01*
X1367842Y156413D01*
X1366987Y157268D01*
G01Y161207D02*
X1369045Y161206D01*
X1369986Y160265D01*
X1371873D01*
X1372600Y159538D01*
G01X1363719Y161207D02*
X1365212D01*
X1366050Y162046D01*
X1366318Y162313D01*
X1367793D01*
X1368056Y162050D01*
X1369262D01*
X1370297Y161015D01*
X1372539D01*
X1373298Y160256D01*
G01X1365353Y159238D02*
X1366131D01*
X1366485Y159592D01*
X1368394D01*
X1368608Y159378D01*
X1371255D01*
X1371953Y158680D01*
G01X1397128Y148886D02*
X1397041D01*
X1396914Y149013D01*
X1396002D01*
X1393323Y151692D01*
X1392771D01*
X1392276Y152187D01*
Y152739D01*
X1391782Y153233D01*
X1391230D01*
X1390735Y153728D01*
Y154280D01*
X1390241Y154774D01*
X1389689D01*
X1389194Y155269D01*
Y155821D01*
X1388700Y156315D01*
X1388148D01*
X1387653Y156810D01*
Y157362D01*
X1387159Y157856D01*
X1386607D01*
X1386112Y158351D01*
Y158903D01*
X1385618Y159397D01*
X1385066D01*
X1384571Y159892D01*
Y160444D01*
X1384077Y160938D01*
X1383525D01*
X1383030Y161433D01*
Y161985D01*
X1382536Y162479D01*
X1381984D01*
X1381489Y162974D01*
Y163526D01*
X1380995Y164020D01*
X1380443D01*
X1379948Y164515D01*
Y165067D01*
X1379454Y165561D01*
X1378902D01*
X1378407Y166056D01*
Y166608D01*
X1377913Y167102D01*
X1377361D01*
X1376866Y167597D01*
Y168133D01*
X1376516Y168483D01*
X1374973D01*
X1374584Y168094D01*
X1373884D01*
X1373495Y168483D01*
X1372533D01*
X1372034Y168982D01*
X1367090D01*
X1366987Y169085D01*
G01X1397128Y149906D02*
X1397041D01*
X1396897Y149762D01*
X1396313D01*
X1377631Y168444D01*
X1377615D01*
X1376827Y169232D01*
X1372844D01*
X1372345Y169731D01*
X1368010D01*
X1367569Y170172D01*
X1366296D01*
X1365824Y169764D01*
X1365145Y169085D01*
X1363719D01*
G01X1392760Y145734D02*
X1392699Y145795D01*
Y145987D01*
X1391375Y147311D01*
Y148323D01*
X1390986Y148712D01*
Y149412D01*
X1391375Y149801D01*
Y150501D01*
X1389506Y152370D01*
X1388954D01*
X1388459Y152865D01*
Y153417D01*
X1387965Y153911D01*
X1387413D01*
X1386918Y154406D01*
Y154958D01*
X1386424Y155452D01*
X1385872D01*
X1385377Y155947D01*
Y156499D01*
X1384883Y156993D01*
X1384331D01*
X1383836Y157488D01*
Y158040D01*
X1383342Y158534D01*
X1382791D01*
X1382296Y159029D01*
Y159580D01*
X1381697Y160179D01*
X1381145D01*
X1380650Y160674D01*
Y161226D01*
X1380156Y161720D01*
X1379604D01*
X1379109Y162215D01*
Y162767D01*
X1378615Y163261D01*
X1378063D01*
X1377568Y163756D01*
Y164308D01*
X1377074Y164802D01*
X1376522D01*
X1376027Y165297D01*
Y165822D01*
X1375677Y166172D01*
X1372421D01*
X1371460Y167133D01*
X1366482D01*
X1366465Y167116D01*
X1365353D01*
G01X1382409Y149782D02*
Y149869D01*
X1382545Y150005D01*
Y153243D01*
X1382156Y153632D01*
Y154332D01*
X1382545Y154721D01*
Y155702D01*
X1381582Y156665D01*
X1381030D01*
X1380535Y157160D01*
Y157712D01*
X1380041Y158206D01*
X1379489D01*
X1378994Y158701D01*
Y159253D01*
X1378500Y159747D01*
X1377948D01*
X1377453Y160242D01*
Y160794D01*
X1376959Y161288D01*
X1376407D01*
X1375912Y161783D01*
Y162335D01*
X1375418Y162829D01*
X1374866D01*
X1374371Y163324D01*
Y163876D01*
X1373877Y164370D01*
X1371345D01*
X1370569Y165146D01*
X1369683D01*
X1369294Y164757D01*
X1368594D01*
X1368205Y165146D01*
X1366987D01*
G01X1383429Y149782D02*
Y149869D01*
X1383294Y150004D01*
Y156013D01*
X1374188Y165119D01*
X1371656D01*
X1370880Y165895D01*
X1368150D01*
X1367803Y166242D01*
X1366307D01*
X1365272Y165348D01*
X1364729Y165146D01*
X1363719D01*
G01X1379471Y150804D02*
Y150891D01*
X1379606Y151026D01*
Y153710D01*
X1379217Y154099D01*
Y154799D01*
X1379606Y155188D01*
Y155888D01*
X1377717Y157777D01*
X1377165D01*
X1376670Y158272D01*
Y158824D01*
X1376176Y159318D01*
X1375624D01*
X1375129Y159813D01*
Y160365D01*
X1374635Y160859D01*
X1374083D01*
X1373588Y161354D01*
Y161906D01*
X1373094Y162400D01*
X1372324D01*
X1371935Y162011D01*
X1371235D01*
X1370846Y162400D01*
X1370146D01*
X1369365Y163181D01*
X1367416D01*
X1367411Y163176D01*
X1366720D01*
X1365353Y163177D01*
G01X1391038Y178871D02*
X1386756Y183153D01*
X1368340D01*
X1367719Y182896D01*
X1365378D01*
X1365353Y182871D01*
G01X1396781Y182349D02*
X1396644Y182486D01*
X1394363D01*
X1393739Y181862D01*
X1390757D01*
X1387960Y184659D01*
X1383677D01*
X1372075Y184651D01*
X1367177D01*
X1366987Y184841D01*
G01X1392025Y184062D02*
X1390553Y185534D01*
X1382609D01*
X1371501Y185526D01*
X1371375Y185400D01*
X1369759D01*
X1369514Y185645D01*
X1368362D01*
X1368071Y185936D01*
X1366298D01*
X1365826Y185528D01*
X1365139Y184841D01*
X1363719D01*
G01X1365353Y171055D02*
X1366485Y171054D01*
X1367454D01*
X1368832Y170483D01*
X1373085D01*
X1373474Y170094D01*
X1374174D01*
X1374563Y170483D01*
X1375263D01*
X1375652Y170094D01*
X1376352D01*
X1376741Y170483D01*
X1378020D01*
X1378389Y170114D01*
Y169562D01*
X1378884Y169067D01*
X1379436D01*
X1379930Y168573D01*
Y168021D01*
X1380425Y167526D01*
X1380977D01*
X1381471Y167032D01*
Y166480D01*
X1381966Y165985D01*
X1382518D01*
X1383012Y165491D01*
Y164939D01*
X1383507Y164444D01*
X1384059D01*
X1384553Y163950D01*
Y163398D01*
X1385048Y162903D01*
X1385600D01*
X1386094Y162409D01*
Y161857D01*
X1386589Y161362D01*
X1387141D01*
X1387635Y160868D01*
Y160316D01*
X1388130Y159821D01*
X1388682D01*
X1389176Y159327D01*
Y158775D01*
X1389671Y158280D01*
X1390223D01*
X1390717Y157786D01*
Y157234D01*
X1391212Y156739D01*
X1391764D01*
X1392258Y156245D01*
Y155693D01*
X1392753Y155198D01*
X1393305D01*
X1394445Y154058D01*
X1396791D01*
X1396927Y153922D01*
X1397014D01*
G01X1365353Y174993D02*
X1368626D01*
X1370136Y173483D01*
X1374276D01*
X1375294Y174501D01*
Y176956D01*
X1375680Y177342D01*
X1376451D01*
X1376991Y176802D01*
Y176430D01*
G01X1395447Y163996D02*
X1395360D01*
X1395224Y164132D01*
X1392890D01*
X1390200Y166822D01*
X1389677D01*
X1388948Y167551D01*
Y168074D01*
X1388220Y168802D01*
X1387697D01*
X1386968Y169531D01*
Y170054D01*
X1386240Y170782D01*
X1385717D01*
X1384988Y171511D01*
Y172034D01*
X1384260Y172762D01*
X1383737D01*
X1383008Y173491D01*
Y174014D01*
X1382280Y174742D01*
Y176798D01*
X1380809Y178269D01*
X1379753D01*
X1379364Y177880D01*
X1378664D01*
X1378275Y178269D01*
X1372853D01*
X1372464Y177880D01*
X1371764D01*
X1371375Y178269D01*
X1369812D01*
X1368854Y177311D01*
X1368073D01*
X1367725Y176963D01*
X1366987D01*
G01X1395447Y165016D02*
X1395360D01*
X1395225Y164881D01*
X1393201D01*
X1383029Y175053D01*
Y177109D01*
X1381120Y179018D01*
X1369501D01*
X1368543Y178060D01*
X1366468D01*
X1364827Y176963D01*
X1363719D01*
G01X1365353Y178932D02*
X1368122Y178925D01*
X1368928Y179727D01*
X1369566Y179992D01*
X1381803D01*
X1382797Y178998D01*
Y178446D01*
X1383292Y177951D01*
X1383844D01*
X1384338Y177457D01*
Y176906D01*
X1384832Y176411D01*
X1385384D01*
X1385878Y175916D01*
Y175365D01*
X1386373Y174870D01*
X1386924D01*
X1387418Y174376D01*
Y173824D01*
X1387913Y173329D01*
X1388465D01*
X1388959Y172835D01*
Y172283D01*
X1389454Y171788D01*
X1390007D01*
X1390735Y171060D01*
Y170537D01*
X1391464Y169808D01*
X1391987D01*
X1393443Y168352D01*
X1397121D01*
X1397257Y168216D01*
X1397344D01*
G01X1394182Y171470D02*
X1395791Y173079D01*
Y173494D01*
X1395283Y174002D01*
X1392395D01*
X1390690Y174708D01*
X1390099Y175299D01*
X1389547D01*
X1389052Y175794D01*
Y176346D01*
X1388558Y176840D01*
X1388007D01*
X1387512Y177335D01*
Y177886D01*
X1387018Y178381D01*
X1386466D01*
X1385972Y178876D01*
Y179427D01*
X1385478Y179921D01*
X1384926D01*
X1384431Y180416D01*
Y180968D01*
X1383744Y181655D01*
X1369662D01*
X1368738Y181517D01*
X1368154Y181273D01*
X1367780Y180900D01*
X1366987Y180902D01*
G01X1398182Y171470D02*
X1396825Y172827D01*
Y173581D01*
X1395624Y174782D01*
X1392680D01*
X1390969Y175490D01*
X1384055Y182404D01*
X1369606D01*
X1366298Y181912D01*
X1364788Y180902D01*
X1363719D01*
G01X1395184Y159630D02*
X1395097D01*
X1394961Y159766D01*
X1392453D01*
X1391494Y160725D01*
X1390942D01*
X1390447Y161220D01*
Y161772D01*
X1389953Y162266D01*
X1389401D01*
X1388906Y162761D01*
Y163313D01*
X1388412Y163807D01*
X1387860D01*
X1387365Y164302D01*
Y164854D01*
X1386871Y165348D01*
X1386319D01*
X1385824Y165843D01*
Y166395D01*
X1385330Y166889D01*
X1384778D01*
X1384283Y167384D01*
Y167936D01*
X1383789Y168430D01*
X1383237D01*
X1382742Y168925D01*
Y169477D01*
X1382248Y169971D01*
X1381696D01*
X1381201Y170466D01*
Y171018D01*
X1380707Y171512D01*
X1380155D01*
X1379660Y172007D01*
Y172559D01*
X1379076Y173143D01*
X1378563D01*
X1378174Y172754D01*
X1377474D01*
X1377085Y173143D01*
X1376485D01*
X1375325Y171983D01*
X1369305D01*
X1368283Y173005D01*
X1368237Y173024D01*
X1366987D01*
G01X1395184Y160650D02*
X1395097D01*
X1394962Y160515D01*
X1392764D01*
X1379387Y173892D01*
X1376174D01*
X1375014Y172732D01*
X1369616D01*
X1368708Y173641D01*
X1367571Y174112D01*
X1366298D01*
X1366123Y173961D01*
X1364721Y173024D01*
X1363719D01*
G01X1401341Y177159D02*
X1402711Y178529D01*
Y179140D01*
X1399385Y182466D01*
Y183704D01*
X1396806Y186283D01*
X1373576D01*
X1371358Y188501D01*
X1368409D01*
X1367601Y187693D01*
X1366296D01*
X1365824Y188101D01*
X1365145Y188780D01*
X1363719D01*
G01X1409850Y188470D02*
X1409789Y188531D01*
Y188723D01*
X1408164Y190348D01*
X1374211D01*
X1372615Y191944D01*
X1368384D01*
X1368071Y191631D01*
X1366296D01*
X1365824Y192039D01*
X1365145Y192718D01*
X1363719D01*
G01X1366987Y188780D02*
X1367628D01*
X1368098Y189250D01*
X1371669D01*
X1373887Y187032D01*
X1374487D01*
X1374867Y187412D01*
X1375467D01*
X1375847Y187032D01*
X1376447D01*
X1376827Y187412D01*
X1377427D01*
X1377807Y187032D01*
X1378407D01*
X1378787Y187412D01*
X1379387D01*
X1379767Y187032D01*
X1380367D01*
X1380747Y187412D01*
X1381347D01*
X1381727Y187032D01*
X1382327D01*
X1382707Y187412D01*
X1383307D01*
X1383687Y187032D01*
X1384287D01*
X1384667Y187412D01*
X1385267D01*
X1385647Y187032D01*
X1386247D01*
X1386627Y187412D01*
X1387227D01*
X1387607Y187032D01*
X1388207D01*
X1388587Y187412D01*
X1389187D01*
X1389567Y187032D01*
X1390167D01*
X1390547Y187412D01*
X1391147D01*
X1391527Y187032D01*
X1397117D01*
X1400134Y184015D01*
Y182777D01*
X1403460Y179451D01*
Y178440D01*
X1404741Y177159D01*
G01X1365353Y190749D02*
X1365378Y190774D01*
X1372546D01*
X1374322Y188998D01*
X1374922D01*
X1375312Y189388D01*
X1375912D01*
X1376302Y188998D01*
X1376902D01*
X1377292Y189388D01*
X1377892D01*
X1378282Y188998D01*
X1378882D01*
X1379272Y189388D01*
X1379872D01*
X1380262Y188998D01*
X1380862D01*
X1381252Y189388D01*
X1381852D01*
X1382242Y188998D01*
X1382842D01*
X1383232Y189388D01*
X1383832D01*
X1384222Y188998D01*
X1384822D01*
X1385212Y189388D01*
X1385812D01*
X1386202Y188998D01*
X1386802D01*
X1387192Y189388D01*
X1387792D01*
X1388182Y188998D01*
X1388782D01*
X1389172Y189388D01*
X1389772D01*
X1390162Y188998D01*
X1390762D01*
X1391152Y189388D01*
X1391752D01*
X1392142Y188998D01*
X1404794D01*
X1406888Y186904D01*
Y185604D01*
X1408229Y184263D01*
G01X1366987Y192718D02*
X1367325Y192380D01*
X1367760D01*
X1368073Y192693D01*
X1372926D01*
X1374522Y191097D01*
X1375122D01*
X1375502Y191477D01*
X1376102D01*
X1376482Y191097D01*
X1377082D01*
X1377462Y191477D01*
X1378062D01*
X1378442Y191097D01*
X1379042D01*
X1379422Y191477D01*
X1380022D01*
X1380402Y191097D01*
X1381002D01*
X1381382Y191477D01*
X1381982D01*
X1382362Y191097D01*
X1382962D01*
X1383342Y191477D01*
X1383942D01*
X1384322Y191097D01*
X1384922D01*
X1385302Y191477D01*
X1385902D01*
X1386282Y191097D01*
X1386882D01*
X1387262Y191477D01*
X1387862D01*
X1388242Y191097D01*
X1408475D01*
X1410319Y189253D01*
X1410511D01*
X1410572Y189192D01*
G01X1365353Y194688D02*
Y194687D01*
X1366172D01*
X1366188Y194671D01*
X1373448D01*
X1374905Y193214D01*
X1375505D01*
X1375905Y193614D01*
X1376505D01*
X1376905Y193214D01*
X1377505D01*
X1377905Y193614D01*
X1378505D01*
X1378905Y193214D01*
X1379505D01*
X1379905Y193614D01*
X1380505D01*
X1380905Y193214D01*
X1381505D01*
X1381905Y193614D01*
X1382505D01*
X1382905Y193214D01*
X1383505D01*
X1383905Y193614D01*
X1384505D01*
X1384905Y193214D01*
X1385505D01*
X1385905Y193614D01*
X1386505D01*
X1386905Y193214D01*
X1387505D01*
X1387905Y193614D01*
X1388505D01*
X1388905Y193214D01*
X1403092D01*
X1404524Y194646D01*
X1406277D01*
X1406413Y194782D01*
X1406500D01*
G01X1384002Y197668D02*
X1383043Y196709D01*
Y195536D01*
X1382255Y194748D01*
X1374643D01*
X1373821Y195570D01*
X1366477D01*
X1364716Y196657D01*
X1363719D01*
G01X1398006Y197668D02*
X1398930Y198592D01*
Y200152D01*
X1397239Y201843D01*
X1375851D01*
X1373855Y199847D01*
X1368025D01*
X1367660Y199482D01*
X1366360D01*
X1365246Y200596D01*
X1363719D01*
G01X1380602Y197668D02*
X1380873Y198322D01*
X1381403Y198852D01*
X1381944D01*
X1382294Y198502D01*
Y195847D01*
X1381944Y195497D01*
X1379731D01*
X1379342Y195886D01*
X1378642D01*
X1378253Y195497D01*
X1377553D01*
X1377164Y195886D01*
X1376464D01*
X1376075Y195497D01*
X1374954D01*
X1374132Y196319D01*
X1372561D01*
X1372172Y196708D01*
X1371472D01*
X1371083Y196319D01*
X1370383D01*
X1369994Y196708D01*
X1369294D01*
X1368905Y196319D01*
X1368167D01*
X1367829Y196657D01*
X1366987D01*
G01X1365353Y198627D02*
X1368177D01*
X1368557Y199007D01*
X1369257D01*
X1369637Y198627D01*
X1370337D01*
X1370726Y199016D01*
X1371426D01*
X1371815Y198627D01*
X1372515D01*
X1372904Y199016D01*
X1373604D01*
X1373993Y198627D01*
X1374789D01*
X1376764Y200602D01*
X1378555D01*
X1378935Y200982D01*
X1379635D01*
X1380015Y200602D01*
X1380715D01*
X1381095Y200982D01*
X1381795D01*
X1382175Y200602D01*
X1382875D01*
X1383255Y200982D01*
X1383955D01*
X1384335Y200602D01*
X1385035D01*
X1385424Y200991D01*
X1386124D01*
X1386513Y200602D01*
X1387213D01*
X1387602Y200991D01*
X1388302D01*
X1388691Y200602D01*
X1390540D01*
X1391330Y199812D01*
Y198994D01*
X1392656Y197668D01*
G01X1366987Y200596D02*
X1368860D01*
X1369240Y200976D01*
X1370240D01*
X1370620Y200596D01*
X1373544D01*
X1375540Y202592D01*
X1388960D01*
X1389340Y202972D01*
X1390340D01*
X1390720Y202592D01*
X1391720D01*
X1392100Y202972D01*
X1393100D01*
X1393480Y202592D01*
X1394480D01*
X1394860Y202972D01*
X1395860D01*
X1396240Y202592D01*
X1397550D01*
X1399679Y200463D01*
Y198273D01*
X1400284Y197668D01*
X1401406D01*
G01X1408347Y207328D02*
X1408260D01*
X1408125Y207463D01*
X1387831D01*
X1385240Y204872D01*
X1372261D01*
X1368808Y203442D01*
X1366304D01*
X1365824Y203856D01*
X1365145Y204535D01*
X1363719D01*
G01X1366987D02*
X1367517D01*
X1367861Y204191D01*
X1368659D01*
X1372112Y205621D01*
X1376355D01*
X1376744Y206010D01*
X1377784D01*
X1378173Y205621D01*
X1379213D01*
X1379602Y206010D01*
X1380642D01*
X1381031Y205621D01*
X1382071D01*
X1382460Y206010D01*
X1383500D01*
X1383889Y205621D01*
X1384929D01*
X1387520Y208212D01*
X1390251D01*
X1390640Y208601D01*
X1391680D01*
X1392069Y208212D01*
X1393109D01*
X1393498Y208601D01*
X1394538D01*
X1394927Y208212D01*
X1395967D01*
X1396356Y208601D01*
X1397396D01*
X1397785Y208212D01*
X1398815D01*
X1399205Y208602D01*
X1400235D01*
X1400625Y208212D01*
X1401673D01*
X1402063Y208602D01*
X1403093D01*
X1403483Y208212D01*
X1408124D01*
X1408260Y208348D01*
X1408347D01*
G01X1398580Y216917D02*
X1398519Y216856D01*
X1398327D01*
X1393670Y212199D01*
X1372851D01*
X1372850Y212198D01*
X1372849Y212199D01*
X1369311D01*
X1368776Y211664D01*
X1368027D01*
X1367689Y211326D01*
X1366296D01*
X1365824Y211734D01*
X1365145Y212413D01*
X1363719D01*
G01X1397858Y217639D02*
X1397797Y217578D01*
Y217386D01*
X1393359Y212948D01*
X1385109D01*
X1384729Y213328D01*
X1384029D01*
X1383649Y212948D01*
X1382949D01*
X1382569Y213328D01*
X1381869D01*
X1381489Y212948D01*
X1380789D01*
X1380409Y213328D01*
X1379709D01*
X1379329Y212948D01*
X1378629D01*
X1378249Y213328D01*
X1377549D01*
X1377169Y212948D01*
X1376469D01*
X1376089Y213328D01*
X1375389D01*
X1375009Y212948D01*
X1374309D01*
X1373929Y213328D01*
X1373229D01*
X1372849Y212948D01*
X1372149D01*
X1371759Y213338D01*
X1371059D01*
X1370669Y212948D01*
X1369000D01*
X1368465Y212413D01*
X1366987D01*
G01X1391705Y218043D02*
X1391644Y217982D01*
Y217790D01*
X1390816Y216962D01*
X1389608Y216461D01*
X1389274D01*
X1388884Y216851D01*
X1387844D01*
X1387454Y216461D01*
X1386414D01*
X1386024Y216851D01*
X1384984D01*
X1384594Y216461D01*
X1384156D01*
X1383129Y216036D01*
X1382606Y216252D01*
X1381866Y215946D01*
X1381650Y215423D01*
X1380911Y215117D01*
X1380262Y214848D01*
X1379711D01*
X1379321Y215238D01*
X1378621D01*
X1378231Y214848D01*
X1377531D01*
X1377141Y215238D01*
X1376441D01*
X1376051Y214848D01*
X1375351D01*
X1374961Y215238D01*
X1374261D01*
X1373871Y214848D01*
X1373171D01*
X1372781Y215238D01*
X1372081D01*
X1371691Y214848D01*
X1370991D01*
X1370601Y215238D01*
X1369901D01*
X1369510Y214847D01*
X1369117D01*
X1367678Y214251D01*
X1366424D01*
X1366413Y214262D01*
X1365479D01*
X1365353Y214382D01*
G01X1410186Y197668D02*
X1408860Y198994D01*
Y200832D01*
X1406562Y203130D01*
Y203667D01*
X1405854Y204375D01*
X1405317D01*
X1404610Y205082D01*
X1401210D01*
X1400830Y205462D01*
X1399830D01*
X1399450Y205082D01*
X1398450D01*
X1398070Y205462D01*
X1397070D01*
X1396690Y205082D01*
X1395690D01*
X1395310Y205462D01*
X1394310D01*
X1393930Y205082D01*
X1392930D01*
X1392550Y205462D01*
X1391550D01*
X1391170Y205082D01*
X1390170D01*
X1389790Y205462D01*
X1388790D01*
X1388410Y205082D01*
X1387410D01*
X1386439Y204111D01*
X1374539D01*
X1372929Y202501D01*
X1371929D01*
X1371549Y202881D01*
X1370549D01*
X1370169Y202501D01*
X1365418D01*
X1365353Y202566D01*
G01X1370884Y216352D02*
X1369180D01*
X1368081Y215259D01*
X1367303Y215260D01*
X1366780D01*
X1366443Y215249D01*
X1366026Y215608D01*
X1365257Y215856D01*
X1364761Y216352D01*
X1363719D01*
G01X1370664Y217338D02*
X1369108D01*
X1367934Y216172D01*
X1367331Y216173D01*
X1367166D01*
X1366987Y216352D01*
G01X1394387Y210161D02*
X1394300D01*
X1394165Y210296D01*
X1385701D01*
X1385312Y209907D01*
X1384612D01*
X1384223Y210296D01*
X1383523D01*
X1383134Y209907D01*
X1382434D01*
X1382045Y210296D01*
X1381345D01*
X1380956Y209907D01*
X1380256D01*
X1379867Y210296D01*
X1379167D01*
X1378778Y209907D01*
X1378078D01*
X1377689Y210296D01*
X1376989D01*
X1376600Y209907D01*
X1375900D01*
X1375511Y210296D01*
X1374811D01*
X1373630Y209115D01*
Y208563D01*
X1373135Y208068D01*
X1372583D01*
X1372089Y207574D01*
Y207022D01*
X1371594Y206527D01*
X1371042D01*
X1370548Y206033D01*
X1369382D01*
X1368993Y205644D01*
X1368293D01*
X1367904Y206033D01*
X1367204D01*
X1366732Y206505D01*
X1365353D01*
G01X1369974Y220302D02*
X1368766D01*
X1367657Y219193D01*
X1366391D01*
X1365954Y219570D01*
X1365233Y220291D01*
X1363719D01*
G01X1373435Y221252D02*
X1368599D01*
X1367638Y220291D01*
X1366987D01*
G01X1372592Y222553D02*
X1372099Y222060D01*
X1366313D01*
X1366113Y222260D01*
X1365353D01*
G01X1371024Y219352D02*
X1368900D01*
X1367855Y218307D01*
X1366411D01*
X1365353Y218321D01*
G01X1461921Y850286D02*
X1461940Y850253D01*
X1462532Y849227D01*
X1462433Y848861D01*
G03X1462366Y848808I1347J-1772D01*
G03X1461545Y847137I1404J-1727D01*
G01Y847079D01*
G03X1462707Y845124I2226J0D01*
G01X1462708D01*
G02X1463396Y843878I-787J-1248D01*
G01Y840714D01*
X1462800Y840118D01*
Y838024D01*
X1462801Y838023D01*
Y836099D01*
X1442982Y816281D01*
X1440369Y815198D01*
X1434724Y809552D01*
Y808117D01*
X1434588Y807981D01*
Y807894D01*
G01X1456370Y847081D02*
X1455759Y848140D01*
X1455440Y848225D01*
G03X1454895Y847081I930J-1145D01*
G03X1455677Y845778I1475J-1D01*
G02X1455686Y845773I-358J-656D01*
G02X1455709Y845758I-1204J-1871D01*
G02X1456746Y843879I-1188J-1882D01*
G01Y842350D01*
X1457136Y841960D01*
Y841360D01*
X1456746Y840970D01*
Y840370D01*
X1455886Y839510D01*
Y838288D01*
X1456276Y837898D01*
Y837298D01*
X1455885Y836907D01*
Y836244D01*
X1440300Y820659D01*
X1433268Y817745D01*
X1425171Y809648D01*
Y808117D01*
X1425307Y807981D01*
Y807894D01*
G01X1463770Y847081D02*
X1463159Y848140D01*
X1462840Y848225D01*
G03X1462295Y847081I930J-1145D01*
G03X1463077Y845778I1475J-1D01*
G02X1463086Y845773I-358J-656D01*
G02X1464146Y843879I-1166J-1896D01*
G01Y842579D01*
X1464536Y842189D01*
Y841589D01*
X1464146Y841199D01*
Y840403D01*
X1463550Y839807D01*
Y839403D01*
X1463940Y839013D01*
Y838413D01*
X1463550Y838023D01*
Y835788D01*
X1443407Y815645D01*
X1440794Y814562D01*
X1435473Y809241D01*
Y808116D01*
X1435608Y807981D01*
Y807894D01*
G01X1454521Y850286D02*
X1454540Y850253D01*
X1455132Y849227D01*
X1455033Y848861D01*
G03X1454966Y848808I1347J-1772D01*
G03X1454145Y847137I1404J-1727D01*
G01Y847079D01*
G03X1455307Y845124I2226J0D01*
G01X1455308D01*
G02X1455996Y843878I-787J-1248D01*
G01Y840680D01*
X1455137Y839821D01*
Y838288D01*
X1455136Y838287D01*
Y836555D01*
X1439875Y821294D01*
X1432843Y818381D01*
X1424422Y809959D01*
Y808116D01*
X1424287Y807981D01*
Y807894D01*
G01X1447121Y850286D02*
X1447732Y849227D01*
X1447633Y848861D01*
G03X1447566Y848808I1347J-1772D01*
G03X1446745Y847137I1404J-1727D01*
G01Y847079D01*
G03X1447907Y845124I2226J0D01*
G01X1447908D01*
G02X1448596Y843878I-787J-1248D01*
G01Y838623D01*
X1435460Y825488D01*
X1425146Y821215D01*
X1414122Y810190D01*
Y808116D01*
X1413987Y807981D01*
Y807894D01*
G01X1448970Y847081D02*
X1448359Y848140D01*
X1448040Y848225D01*
G03X1447495Y847081I930J-1145D01*
G03X1448277Y845778I1475J-1D01*
G02X1448286Y845773I-358J-656D01*
G02X1448309Y845758I-1204J-1871D01*
G02X1449346Y843879I-1188J-1882D01*
G01Y842754D01*
X1449736Y842364D01*
Y841764D01*
X1449345Y841373D01*
Y840725D01*
X1449735Y840335D01*
Y839735D01*
X1449345Y839345D01*
Y838312D01*
X1435885Y824852D01*
X1425571Y820579D01*
X1414871Y809879D01*
Y808117D01*
X1415007Y807981D01*
Y807894D01*
G01X1439721Y850286D02*
X1440332Y849227D01*
X1440233Y848861D01*
G03X1440166Y848808I1347J-1772D01*
G03X1439345Y847137I1404J-1727D01*
G01Y847079D01*
G03X1440507Y845124I2226J0D01*
G01X1440508D01*
G02X1441237Y843802I-834J-1322D01*
G01Y839935D01*
X1430735Y829433D01*
X1417283Y823863D01*
X1403822Y810401D01*
Y808116D01*
X1403687Y807981D01*
Y807894D01*
G01X1441570Y847081D02*
X1440959Y848140D01*
X1440640Y848225D01*
G03X1440095Y847081I930J-1145D01*
G03X1440877Y845778I1475J-1D01*
G02X1440886Y845773I-358J-656D01*
G02X1440906Y845760I-1203J-1872D01*
G01X1440907Y845758D01*
G02X1441986Y843803I-1233J-1956D01*
G01Y841865D01*
X1442376Y841475D01*
Y840875D01*
X1441986Y840485D01*
Y839624D01*
X1441010Y838648D01*
Y838096D01*
X1440586Y837672D01*
X1440034D01*
X1431160Y828797D01*
X1417708Y823227D01*
X1404571Y810090D01*
Y808117D01*
X1404707Y807981D01*
Y807894D01*
G01X1434170Y847081D02*
X1433559Y848140D01*
X1433240Y848225D01*
G03X1433477Y845778I929J-1145D01*
G02X1433486Y845773I-358J-656D01*
G02X1434546Y843879I-1166J-1896D01*
G01Y842499D01*
X1434936Y842109D01*
Y841509D01*
X1434546Y841119D01*
Y840519D01*
X1434122Y840095D01*
Y839543D01*
X1433932Y839353D01*
X1433698Y839118D01*
X1433146D01*
X1428093Y834065D01*
X1428091Y834064D01*
X1412408Y827565D01*
X1394271Y809428D01*
Y808117D01*
X1394407Y807981D01*
Y807894D01*
G01X1432321Y850286D02*
X1432340Y850253D01*
X1432932Y849227D01*
X1432833Y848861D01*
G03X1432768Y848808I1373J-1750D01*
G03X1433107Y845124I1401J-1729D01*
G02X1433796Y843878I-786J-1248D01*
G01Y840830D01*
X1427666Y834700D01*
X1411983Y828201D01*
X1393522Y809739D01*
Y808116D01*
X1393387Y807981D01*
Y807894D01*
G01X1424921Y850286D02*
X1424940Y850253D01*
X1425532Y849227D01*
X1425433Y848861D01*
G03X1425366Y848809I1331J-1784D01*
G03X1424545Y847111I1405J-1727D01*
G01X1424546Y847113D01*
Y846504D01*
X1424419Y846377D01*
Y842265D01*
X1424420Y842264D01*
Y841000D01*
X1422366Y838947D01*
X1406334Y832302D01*
X1383222Y809190D01*
Y808116D01*
X1383087Y807981D01*
Y807894D01*
G01X1426771Y847081D02*
X1426160Y848140D01*
X1425841Y848225D01*
G03X1425296Y847082I930J-1145D01*
G01Y846193D01*
X1425169Y846066D01*
Y845624D01*
X1425559Y845234D01*
Y844634D01*
X1425169Y844244D01*
Y843644D01*
X1425559Y843254D01*
Y842654D01*
X1425169Y842264D01*
Y840689D01*
X1422791Y838311D01*
X1406759Y831666D01*
X1383971Y808879D01*
Y808117D01*
X1384107Y807981D01*
Y807894D01*
G01X1460070Y847081D02*
X1459459Y846022D01*
X1459558Y845657D01*
G02X1459626Y845604I-1334J-1781D01*
G02X1460446Y843877I-1405J-1725D01*
G01Y839371D01*
X1460445Y839370D01*
Y838458D01*
X1459626Y837639D01*
Y835974D01*
X1441995Y818342D01*
X1437367Y816425D01*
X1430322Y809380D01*
Y808117D01*
X1430458Y807981D01*
Y807894D01*
G01X1458221Y843877D02*
X1458832Y844936D01*
X1459151Y845021D01*
G02X1459696Y843877I-930J-1145D01*
G01Y842730D01*
X1459306Y842340D01*
Y841740D01*
X1459696Y841350D01*
Y840750D01*
X1459306Y840360D01*
Y839760D01*
X1459696Y839370D01*
Y838769D01*
X1458877Y837950D01*
Y836285D01*
X1441570Y818978D01*
X1436942Y817061D01*
X1429573Y809691D01*
Y808116D01*
X1429438Y807981D01*
Y807894D01*
G01X1452670Y847081D02*
X1452059Y846022D01*
X1452158Y845657D01*
G02X1452226Y845604I-1334J-1781D01*
G02X1453046Y843877I-1405J-1725D01*
G01X1453045Y843876D01*
Y837643D01*
X1438177Y822774D01*
X1429127Y819025D01*
X1420021Y809919D01*
Y808117D01*
X1420157Y807981D01*
Y807894D01*
G01X1450821Y843877D02*
X1451432Y844936D01*
X1451751Y845021D01*
G02X1452296Y843877I-930J-1145D01*
G01Y842434D01*
X1451896Y842034D01*
Y841234D01*
X1452296Y840834D01*
Y840234D01*
X1451906Y839844D01*
Y839244D01*
X1452296Y838854D01*
Y837954D01*
X1437752Y823410D01*
X1428702Y819661D01*
X1419272Y810230D01*
Y808116D01*
X1419137Y807981D01*
Y807894D01*
G01X1445270Y847081D02*
X1444659Y846022D01*
X1444758Y845657D01*
G02X1444826Y845604I-1334J-1781D01*
G02X1445646Y843877I-1405J-1725D01*
G01Y841192D01*
X1445643Y838862D01*
X1433666Y826885D01*
X1421412Y821810D01*
X1409721Y810120D01*
Y808117D01*
X1409857Y807981D01*
Y807894D01*
G01X1443421Y843877D02*
X1444032Y844936D01*
X1444351Y845021D01*
G02X1444896Y843877I-930J-1145D01*
G01Y842654D01*
X1444506Y842264D01*
Y841774D01*
X1444897Y841383D01*
Y841193D01*
X1444894Y839173D01*
X1444470Y838749D01*
X1443918D01*
X1443493Y838325D01*
Y837772D01*
X1433241Y827521D01*
X1420987Y822446D01*
X1408972Y810431D01*
Y808116D01*
X1408837Y807981D01*
Y807894D01*
G01X1437870Y847081D02*
X1437259Y846022D01*
X1437358Y845657D01*
G02X1437426Y845604I-1334J-1781D01*
G02X1438246Y843877I-1405J-1725D01*
G01Y839738D01*
X1429839Y831330D01*
X1414683Y825052D01*
X1399421Y809790D01*
Y808117D01*
X1399557Y807981D01*
Y807894D01*
G01X1436021Y843877D02*
X1436632Y844936D01*
X1436951Y845021D01*
G02X1437496Y843878I-930J-1145D01*
G01Y842813D01*
X1437106Y842423D01*
Y841823D01*
X1437497Y841432D01*
Y840049D01*
X1437073Y839625D01*
X1436521D01*
X1436096Y839201D01*
Y838648D01*
X1429414Y831966D01*
X1414258Y825688D01*
X1398672Y810101D01*
Y808116D01*
X1398537Y807981D01*
Y807894D01*
G01X1428621Y843877D02*
X1429232Y844936D01*
X1429551Y845021D01*
G02X1430096Y843878I-930J-1145D01*
G01Y841477D01*
X1429572Y840953D01*
X1429020D01*
X1428595Y840528D01*
Y839977D01*
X1428171Y839553D01*
X1427619D01*
X1427194Y839129D01*
Y838576D01*
X1426103Y837485D01*
X1409598Y830646D01*
X1388372Y809420D01*
Y808116D01*
X1388237Y807981D01*
Y807894D01*
G01X1430470Y847081D02*
X1429859Y846022D01*
X1429958Y845657D01*
G02X1430023Y845604I-1372J-1750D01*
G02X1430846Y843879I-1402J-1728D01*
G01X1430845Y843878D01*
Y841166D01*
X1426528Y836849D01*
X1410023Y830010D01*
X1389121Y809109D01*
Y808117D01*
X1389257Y807981D01*
Y807894D01*
G01X1465621Y843877D02*
X1466232Y844936D01*
X1466551Y845021D01*
G02X1467096Y843878I-930J-1145D01*
G01Y842455D01*
X1466706Y842065D01*
Y841465D01*
X1467096Y841075D01*
Y840475D01*
X1466706Y840085D01*
Y839485D01*
X1467096Y839095D01*
Y838262D01*
X1466869Y838035D01*
Y836298D01*
X1439873Y809302D01*
Y808116D01*
X1439738Y807981D01*
Y807894D01*
G01X1467470Y847081D02*
X1466859Y846022D01*
X1466958Y845657D01*
G02X1467026Y845604I-1334J-1781D01*
G02X1467846Y843877I-1405J-1725D01*
G01Y839096D01*
X1467845Y839095D01*
Y837951D01*
X1467618Y837724D01*
Y835987D01*
X1440622Y808991D01*
Y808117D01*
X1440758Y807981D01*
Y807894D01*
G01X1510021Y850286D02*
X1509461Y849726D01*
Y849018D01*
X1510532Y847947D01*
Y845690D01*
X1510160Y845318D01*
Y834725D01*
X1505767Y824117D01*
X1499390Y817740D01*
X1497271Y812626D01*
Y808074D01*
X1497407Y807938D01*
Y807894D01*
G01X1508170Y847081D02*
Y847829D01*
X1508632Y848291D01*
X1509127D01*
X1509782Y847636D01*
Y846000D01*
X1509411Y845629D01*
Y843295D01*
X1509021Y842905D01*
Y842305D01*
X1509411Y841915D01*
Y834874D01*
X1505131Y824542D01*
X1498754Y818165D01*
X1496522Y812776D01*
Y808116D01*
X1496387Y807981D01*
Y807894D01*
G01X1498921Y850286D02*
X1499532Y849227D01*
X1499896Y849130D01*
G02X1499976Y849162I867J-2051D01*
G02X1502996Y847137I794J-2081D01*
G01Y835444D01*
X1499425Y826814D01*
X1489779Y817169D01*
X1486971Y810391D01*
Y808117D01*
X1487107Y807981D01*
Y807894D01*
G01X1500770Y847081D02*
X1500159Y848140D01*
X1500245Y848458D01*
X1500244Y848461D01*
G02X1502247Y847126I526J-1380D01*
G01Y844684D01*
X1501847Y844284D01*
Y843484D01*
X1502247Y843084D01*
Y842220D01*
X1501847Y841820D01*
Y841020D01*
X1502247Y840620D01*
Y839820D01*
X1501847Y839420D01*
Y838620D01*
X1502247Y838220D01*
Y837620D01*
X1501857Y837230D01*
Y836630D01*
X1502247Y836240D01*
Y835593D01*
X1498789Y827239D01*
X1489143Y817594D01*
X1486222Y810541D01*
Y808116D01*
X1486087Y807981D01*
Y807894D01*
G01X1493370Y847081D02*
X1492759Y848140D01*
X1492440Y848225D01*
G03X1491895Y847081I930J-1145D01*
G01Y846981D01*
G03X1492598Y845724I1475J0D01*
G01X1492627Y845707D01*
X1492633Y845704D01*
X1492642Y845699D01*
G02X1493746Y843776I-1123J-1923D01*
G01Y841625D01*
X1494136Y841235D01*
Y840635D01*
X1493746Y840245D01*
Y839645D01*
X1494136Y839255D01*
Y838655D01*
X1493746Y838265D01*
Y832535D01*
X1492827Y830317D01*
X1480305Y817795D01*
X1476671Y809022D01*
Y808117D01*
X1476807Y807981D01*
Y807894D01*
G01X1491521Y850286D02*
X1491540Y850253D01*
X1492132Y849227D01*
X1492033Y848861D01*
G03X1491966Y848808I1347J-1772D01*
G01X1491967D01*
G03X1491145Y847082I1403J-1727D01*
G01Y846982D01*
G03X1492212Y845080I2226J-2D01*
G01X1492254Y845056D01*
X1492256Y845055D01*
X1492257Y845054D01*
X1492258D01*
X1492283Y845039D01*
G02X1492996Y843776I-762J-1263D01*
G01Y840246D01*
X1492997Y840245D01*
Y832685D01*
X1492191Y830742D01*
X1479669Y818220D01*
X1475922Y809171D01*
Y808116D01*
X1475787Y807981D01*
Y807894D01*
G01X1485970Y847081D02*
X1485359Y848140D01*
X1485040Y848225D01*
G03X1484495Y847081I930J-1145D01*
G01Y846981D01*
G03X1485198Y845724I1475J0D01*
G01X1485227Y845707D01*
X1485233Y845704D01*
X1485242Y845699D01*
G02X1486346Y843776I-1123J-1923D01*
G01Y842044D01*
X1486736Y841654D01*
Y841054D01*
X1486346Y840664D01*
Y840064D01*
X1487318Y839092D01*
Y838162D01*
X1487708Y837772D01*
Y837172D01*
X1487318Y836782D01*
Y834076D01*
X1468583Y815341D01*
X1466371Y810003D01*
Y808117D01*
X1466507Y807981D01*
Y807894D01*
G01X1476721Y850286D02*
X1476740Y850253D01*
X1477332Y849227D01*
X1477233Y848861D01*
G03X1477166Y848808I1347J-1772D01*
G01X1477167D01*
G03X1476345Y847082I1403J-1727D01*
G01Y846982D01*
G03X1477412Y845080I2226J-2D01*
G01X1477454Y845056D01*
X1477456Y845055D01*
X1477457Y845054D01*
X1477458D01*
X1477483Y845039D01*
G02X1478196Y843776I-762J-1263D01*
G01Y839753D01*
X1478659Y839290D01*
Y835127D01*
X1457426Y813894D01*
X1455322Y808813D01*
Y808116D01*
X1455187Y807981D01*
Y807894D01*
G01X1484121Y850286D02*
X1484140Y850253D01*
X1484732Y849227D01*
X1484633Y848861D01*
G03X1484566Y848808I1347J-1772D01*
G01X1484567D01*
G03X1483745Y847082I1403J-1727D01*
G01Y846982D01*
G03X1484812Y845080I2226J-2D01*
G01X1484854Y845056D01*
X1484856Y845055D01*
X1484857Y845054D01*
X1484858D01*
X1484883Y845039D01*
G02X1485596Y843776I-762J-1263D01*
G01X1485597Y843775D01*
X1485596Y843774D01*
Y839753D01*
X1486568Y838781D01*
Y836783D01*
X1486569Y836782D01*
Y834387D01*
X1467947Y815766D01*
X1465622Y810153D01*
Y808116D01*
X1465487Y807981D01*
Y807894D01*
G01X1478570Y847081D02*
X1477959Y848140D01*
X1477640Y848225D01*
G03X1477095Y847081I930J-1145D01*
G01Y846981D01*
G03X1477798Y845724I1475J0D01*
G01X1477827Y845707D01*
X1477833Y845704D01*
X1477842Y845699D01*
G02X1478946Y843776I-1123J-1923D01*
G01Y842044D01*
X1479336Y841654D01*
Y841054D01*
X1478946Y840664D01*
Y840064D01*
X1479409Y839601D01*
Y836677D01*
X1479799Y836287D01*
Y835687D01*
X1479408Y835296D01*
Y834816D01*
X1458062Y813469D01*
X1456071Y808664D01*
Y808117D01*
X1456207Y807981D01*
Y807894D01*
G01X1469321Y850286D02*
X1469340Y850253D01*
X1469932Y849227D01*
X1469833Y848861D01*
G03X1469766Y848808I1347J-1772D01*
G01X1469767D01*
G03X1468945Y847082I1403J-1727D01*
G01Y846802D01*
G03X1469905Y845085I2015J0D01*
G03X1469958Y845054I1058J1747D01*
G01X1470064Y844992D01*
G02X1470796Y843718I-743J-1274D01*
G01Y839707D01*
X1470797Y839706D01*
Y835686D01*
X1445819Y810708D01*
X1445023Y808781D01*
Y808116D01*
X1444888Y807981D01*
Y807894D01*
G01X1471170Y847081D02*
X1470559Y848140D01*
X1470240Y848225D01*
G03X1469695Y847081I930J-1145D01*
G01Y846802D01*
G03X1470298Y845724I1265J0D01*
G01X1470442Y845640D01*
G02X1471546Y843718I-1121J-1922D01*
G01Y843066D01*
X1471936Y842676D01*
Y842076D01*
X1471546Y841686D01*
Y841086D01*
X1471936Y840696D01*
Y840096D01*
X1471546Y839706D01*
Y835375D01*
X1446455Y810283D01*
X1445772Y808632D01*
Y808117D01*
X1445908Y807981D01*
Y807894D01*
G01X1473021Y843877D02*
X1473632Y844936D01*
X1473951Y845021D01*
G02X1474496Y843877I-930J-1145D01*
G01Y842850D01*
X1474106Y842460D01*
Y841860D01*
X1474496Y841470D01*
Y840383D01*
X1474732Y840147D01*
Y839787D01*
X1474342Y839397D01*
Y838797D01*
X1474733Y838406D01*
Y835471D01*
X1454313Y815051D01*
X1450173Y808853D01*
Y808116D01*
X1450038Y807981D01*
Y807894D01*
G01X1474870Y847081D02*
X1474259Y846022D01*
X1474358Y845657D01*
G02X1474426Y845604I-1334J-1781D01*
G02X1475246Y843877I-1405J-1725D01*
G01Y840694D01*
X1475482Y840458D01*
Y835160D01*
X1454896Y814573D01*
X1450922Y808625D01*
Y808117D01*
X1451058Y807981D01*
Y807894D01*
G01X1480421Y843877D02*
X1480643Y844262D01*
X1481032Y844936D01*
X1481351Y845021D01*
G02X1481896Y843878I-930J-1145D01*
G01Y842377D01*
X1481506Y841987D01*
Y841387D01*
X1481896Y840997D01*
Y839851D01*
X1482646Y839101D01*
Y838501D01*
X1482256Y838111D01*
Y837511D01*
X1482647Y837120D01*
Y834797D01*
X1462806Y814957D01*
X1460472Y809319D01*
Y808116D01*
X1460337Y807981D01*
Y807894D01*
G01X1502621Y850286D02*
X1502996D01*
G02X1503335Y850196I2J-677D01*
G02X1504000Y849738I-2567J-4439D01*
G02X1504261Y849428I-709J-862D01*
G02X1504303Y849345I-974J-545D01*
G03X1504677Y848786I2020J947D01*
G03X1504808Y848653I1654J1498D01*
G03X1505170Y848378I1555J1671D01*
G01X1505493Y848181D01*
G02X1505946Y847375I-492J-807D01*
G01Y845230D01*
X1505947Y845229D01*
Y834233D01*
X1502781Y826592D01*
X1494609Y818420D01*
X1491372Y810607D01*
Y808116D01*
X1491237Y807981D01*
Y807894D01*
G01X1495221Y843877D02*
X1495618Y844566D01*
X1495832Y844936D01*
X1496151Y845021D01*
G02X1496696Y843877I-930J-1145D01*
G01Y841795D01*
X1496306Y841405D01*
Y840805D01*
X1496696Y840415D01*
Y839815D01*
X1496306Y839425D01*
Y838825D01*
X1496696Y838435D01*
Y832354D01*
X1495234Y828823D01*
X1484915Y818504D01*
X1481072Y809223D01*
Y808116D01*
X1480937Y807981D01*
Y807894D01*
G01X1492257D02*
Y807981D01*
X1492121Y808117D01*
Y810457D01*
X1495245Y817995D01*
X1503417Y826167D01*
X1506696Y834084D01*
Y845229D01*
X1507086Y845619D01*
Y846219D01*
X1506696Y846609D01*
Y847375D01*
G03X1505884Y848822I-1695J0D01*
G01X1505561Y849019D01*
X1505558Y849021D01*
Y849022D01*
X1505469Y849111D01*
G02X1505180Y849809I698J698D01*
G01Y849949D01*
X1505309Y850131D01*
G02X1505608Y850286I299J-211D01*
G01X1506321D01*
G01X1487821Y843877D02*
X1488432Y844936D01*
X1488751Y845021D01*
G02X1489296Y843878I-930J-1145D01*
G01Y842377D01*
X1488906Y841987D01*
Y841387D01*
X1489297Y840996D01*
Y839645D01*
X1490150Y838792D01*
Y837340D01*
X1489760Y836950D01*
Y836350D01*
X1490151Y835959D01*
Y834286D01*
X1489313Y832263D01*
X1474258Y817208D01*
X1470772Y808794D01*
Y808116D01*
X1470637Y807981D01*
Y807894D01*
G01X1497070Y847081D02*
X1496459Y846022D01*
X1496558Y845657D01*
G02X1496626Y845604I-1334J-1781D01*
G02X1497446Y843878I-1405J-1725D01*
G01X1497445Y843877D01*
Y832205D01*
X1495870Y828398D01*
X1485551Y818079D01*
X1481821Y809074D01*
Y808117D01*
X1481957Y807981D01*
Y807894D01*
G01X1489670Y847081D02*
X1489059Y846022D01*
X1489158Y845657D01*
G02X1489226Y845604I-1334J-1781D01*
G02X1490046Y843877I-1405J-1725D01*
G01Y839956D01*
X1490900Y839102D01*
Y834137D01*
X1489949Y831838D01*
X1474894Y816783D01*
X1471521Y808644D01*
Y808117D01*
X1471657Y807981D01*
Y807894D01*
G01X1482270Y847081D02*
X1481659Y846022D01*
X1481758Y845657D01*
G02X1481826Y845604I-1334J-1781D01*
G02X1482646Y843877I-1405J-1725D01*
G01Y840162D01*
X1483396Y839412D01*
Y834486D01*
X1463442Y814532D01*
X1461221Y809170D01*
Y808117D01*
X1461357Y807981D01*
Y807894D01*
G54D332*
G01X-6350Y-464479D02*
Y-539479D01*
X493650D01*
Y-464479D01*
X-6350D01*
G01X5650Y-529479D02*
Y-534479D01*
G01X4193Y-529479D02*
X7107D01*
G01X12017Y-534479D02*
X9483D01*
Y-529479D01*
X12017D01*
G01X11003Y-531896D02*
X9483D01*
G01X14583Y-529479D02*
Y-534479D01*
X17117D01*
G01X20950Y-534646D02*
X20823Y-534562D01*
Y-534396D01*
X20950Y-534312D01*
X21077Y-534396D01*
Y-534562D01*
X20950Y-534646D01*
G01Y-532396D02*
X20823Y-532312D01*
Y-532146D01*
X20950Y-532062D01*
X21077Y-532146D01*
Y-532312D01*
X20950Y-532396D01*
G01X25733Y-536146D02*
X25100Y-535312D01*
X24783Y-534479D01*
Y-531146D01*
X25100Y-530312D01*
X25733Y-529479D01*
G01X31150D02*
X30643Y-529646D01*
X30263Y-530062D01*
X30010Y-530562D01*
X29820Y-531229D01*
X29757Y-531979D01*
X29820Y-532729D01*
X30010Y-533396D01*
X30263Y-533896D01*
X30643Y-534312D01*
X31150Y-534479D01*
X31657Y-534312D01*
X32037Y-533896D01*
X32290Y-533396D01*
X32480Y-532729D01*
X32543Y-531979D01*
X32480Y-531229D01*
X32290Y-530562D01*
X32037Y-530062D01*
X31657Y-529646D01*
X31150Y-529479D01*
G01X34857Y-533479D02*
X35237Y-534062D01*
X35743Y-534396D01*
X36313Y-534479D01*
X36820Y-534396D01*
X37327Y-533979D01*
X37643Y-533479D01*
X37707Y-532979D01*
X37580Y-532396D01*
X37137Y-531979D01*
X36693Y-531812D01*
X36123D01*
G01X36693D02*
X37073Y-531562D01*
X37390Y-531146D01*
X37517Y-530646D01*
X37390Y-530146D01*
X37073Y-529729D01*
X36503Y-529479D01*
X35933Y-529562D01*
X35363Y-529896D01*
G01X41667Y-536146D02*
X42300Y-535312D01*
X42617Y-534479D01*
Y-531146D01*
X42300Y-530312D01*
X41667Y-529479D01*
G01X45057Y-533479D02*
X45437Y-534062D01*
X45943Y-534396D01*
X46513Y-534479D01*
X47020Y-534396D01*
X47527Y-533979D01*
X47843Y-533479D01*
X47907Y-532979D01*
X47780Y-532396D01*
X47337Y-531979D01*
X46893Y-531812D01*
X46323D01*
G01X46893D02*
X47273Y-531562D01*
X47590Y-531146D01*
X47717Y-530646D01*
X47590Y-530146D01*
X47273Y-529729D01*
X46703Y-529479D01*
X46133Y-529562D01*
X45563Y-529896D01*
G01X50347Y-530312D02*
X50727Y-529812D01*
X51170Y-529562D01*
X51677Y-529479D01*
X52310Y-529646D01*
X52753Y-530062D01*
X52880Y-530562D01*
X52817Y-531062D01*
X52563Y-531479D01*
X51297Y-532312D01*
X50727Y-532896D01*
X50347Y-533729D01*
X50220Y-534479D01*
X52880D01*
G01X56523D02*
X56650Y-533396D01*
X56840Y-532479D01*
X57093Y-531646D01*
X57410Y-530729D01*
X57917Y-529479D01*
X55383D01*
G01X60927Y-532812D02*
X62573D01*
G01X65647Y-530312D02*
X66027Y-529812D01*
X66470Y-529562D01*
X66977Y-529479D01*
X67610Y-529646D01*
X68053Y-530062D01*
X68180Y-530562D01*
X68117Y-531062D01*
X67863Y-531479D01*
X66597Y-532312D01*
X66027Y-532896D01*
X65647Y-533729D01*
X65520Y-534479D01*
X68180D01*
G01X70557Y-533479D02*
X70937Y-534062D01*
X71443Y-534396D01*
X72013Y-534479D01*
X72520Y-534396D01*
X73027Y-533979D01*
X73343Y-533479D01*
X73407Y-532979D01*
X73280Y-532396D01*
X72837Y-531979D01*
X72393Y-531812D01*
X71823D01*
G01X72393D02*
X72773Y-531562D01*
X73090Y-531146D01*
X73217Y-530646D01*
X73090Y-530146D01*
X72773Y-529729D01*
X72203Y-529479D01*
X71633Y-529562D01*
X71063Y-529896D01*
G01X77810Y-534479D02*
Y-529479D01*
X75467Y-533062D01*
X78633D01*
G01X80757Y-533729D02*
X81137Y-534146D01*
X81580Y-534396D01*
X82150Y-534479D01*
X82720Y-534312D01*
X83163Y-533979D01*
X83480Y-533396D01*
X83543Y-532729D01*
X83417Y-532062D01*
X83100Y-531646D01*
X82657Y-531312D01*
X82213Y-531229D01*
X81770Y-531312D01*
X81200Y-531646D01*
X81390Y-529479D01*
X83100D01*
G01X91147Y-534479D02*
Y-529479D01*
X93553D01*
G01X92667Y-531896D02*
X91147D01*
G01X95867Y-534479D02*
X97450Y-529479D01*
X99033Y-534479D01*
G01X98463Y-532729D02*
X96437D01*
G01X101220Y-534479D02*
X103880Y-529479D01*
G01X101220D02*
X103880Y-534479D01*
G01X107650Y-534646D02*
X107523Y-534562D01*
Y-534396D01*
X107650Y-534312D01*
X107777Y-534396D01*
Y-534562D01*
X107650Y-534646D01*
G01Y-532396D02*
X107523Y-532312D01*
Y-532146D01*
X107650Y-532062D01*
X107777Y-532146D01*
Y-532312D01*
X107650Y-532396D01*
G01X112433Y-536146D02*
X111800Y-535312D01*
X111483Y-534479D01*
Y-531146D01*
X111800Y-530312D01*
X112433Y-529479D01*
G01X117850D02*
X117343Y-529646D01*
X116963Y-530062D01*
X116710Y-530562D01*
X116520Y-531229D01*
X116457Y-531979D01*
X116520Y-532729D01*
X116710Y-533396D01*
X116963Y-533896D01*
X117343Y-534312D01*
X117850Y-534479D01*
X118357Y-534312D01*
X118737Y-533896D01*
X118990Y-533396D01*
X119180Y-532729D01*
X119243Y-531979D01*
X119180Y-531229D01*
X118990Y-530562D01*
X118737Y-530062D01*
X118357Y-529646D01*
X117850Y-529479D01*
G01X121557Y-533479D02*
X121937Y-534062D01*
X122443Y-534396D01*
X123013Y-534479D01*
X123520Y-534396D01*
X124027Y-533979D01*
X124343Y-533479D01*
X124407Y-532979D01*
X124280Y-532396D01*
X123837Y-531979D01*
X123393Y-531812D01*
X122823D01*
G01X123393D02*
X123773Y-531562D01*
X124090Y-531146D01*
X124217Y-530646D01*
X124090Y-530146D01*
X123773Y-529729D01*
X123203Y-529479D01*
X122633Y-529562D01*
X122063Y-529896D01*
G01X128367Y-536146D02*
X129000Y-535312D01*
X129317Y-534479D01*
Y-531146D01*
X129000Y-530312D01*
X128367Y-529479D01*
G01X131757Y-533479D02*
X132137Y-534062D01*
X132643Y-534396D01*
X133213Y-534479D01*
X133720Y-534396D01*
X134227Y-533979D01*
X134543Y-533479D01*
X134607Y-532979D01*
X134480Y-532396D01*
X134037Y-531979D01*
X133593Y-531812D01*
X133023D01*
G01X133593D02*
X133973Y-531562D01*
X134290Y-531146D01*
X134417Y-530646D01*
X134290Y-530146D01*
X133973Y-529729D01*
X133403Y-529479D01*
X132833Y-529562D01*
X132263Y-529896D01*
G01X137173Y-533896D02*
X137617Y-534312D01*
X138123Y-534479D01*
X138630Y-534312D01*
X139073Y-533812D01*
X139390Y-533062D01*
X139517Y-532312D01*
Y-531396D01*
X139390Y-530646D01*
X139073Y-529979D01*
X138693Y-529646D01*
X138250Y-529479D01*
X137743Y-529646D01*
X137363Y-529979D01*
X137110Y-530479D01*
X136983Y-531146D01*
X137110Y-531729D01*
X137427Y-532312D01*
X137807Y-532646D01*
X138250Y-532729D01*
X138757Y-532562D01*
X139137Y-532146D01*
X139517Y-531396D01*
G01X143223Y-534479D02*
X143350Y-533396D01*
X143540Y-532479D01*
X143793Y-531646D01*
X144110Y-530729D01*
X144617Y-529479D01*
X142083D01*
G01X147627Y-532812D02*
X149273D01*
G01X152157Y-533479D02*
X152537Y-534062D01*
X153043Y-534396D01*
X153613Y-534479D01*
X154120Y-534396D01*
X154627Y-533979D01*
X154943Y-533479D01*
X155007Y-532979D01*
X154880Y-532396D01*
X154437Y-531979D01*
X153993Y-531812D01*
X153423D01*
G01X153993D02*
X154373Y-531562D01*
X154690Y-531146D01*
X154817Y-530646D01*
X154690Y-530146D01*
X154373Y-529729D01*
X153803Y-529479D01*
X153233Y-529562D01*
X152663Y-529896D01*
G01X157447Y-532396D02*
X157890Y-531812D01*
X158270Y-531479D01*
X158777Y-531312D01*
X159220Y-531479D01*
X159537Y-531812D01*
X159790Y-532312D01*
X159853Y-532896D01*
X159790Y-533396D01*
X159537Y-533896D01*
X159157Y-534312D01*
X158713Y-534479D01*
X158207Y-534312D01*
X157763Y-533812D01*
X157510Y-533062D01*
X157447Y-532229D01*
X157573Y-531146D01*
X157763Y-530562D01*
X158080Y-529979D01*
X158523Y-529562D01*
X158967Y-529479D01*
X159410Y-529646D01*
X159727Y-530062D01*
G01X163750Y-534479D02*
Y-529479D01*
X162990Y-530479D01*
G01Y-534479D02*
X164510D01*
G01X169610D02*
Y-529479D01*
X167267Y-533062D01*
X170433D01*
G01X188650Y-464479D02*
Y-539479D01*
G01Y-514479D02*
X291650D01*
Y-489479D01*
G01X188650D02*
X291650D01*
G01Y-464479D02*
Y-539479D01*
G01X293650Y-464479D02*
Y-539479D01*
G01X299157Y-524479D02*
Y-519479D01*
X300423D01*
X300930Y-519729D01*
X301310Y-520062D01*
X301627Y-520562D01*
X301880Y-521146D01*
X301943Y-521979D01*
X301880Y-522812D01*
X301627Y-523396D01*
X301310Y-523896D01*
X300930Y-524229D01*
X300423Y-524479D01*
X299157D01*
G01X304067D02*
X305650Y-519479D01*
X307233Y-524479D01*
G01X306663Y-522729D02*
X304637D01*
G01X310750Y-519479D02*
Y-524479D01*
G01X309293Y-519479D02*
X312207D01*
G01X317117Y-524479D02*
X314583D01*
Y-519479D01*
X317117D01*
G01X316103Y-521896D02*
X314583D01*
G01X320950Y-524646D02*
X320823Y-524562D01*
Y-524396D01*
X320950Y-524312D01*
X321077Y-524396D01*
Y-524562D01*
X320950Y-524646D01*
G01Y-522396D02*
X320823Y-522312D01*
Y-522146D01*
X320950Y-522062D01*
X321077Y-522146D01*
Y-522312D01*
X320950Y-522396D01*
G01X299283Y-499479D02*
Y-494479D01*
X300803D01*
X301310Y-494729D01*
X301690Y-495312D01*
X301817Y-495979D01*
X301690Y-496646D01*
X301373Y-497146D01*
X300803Y-497396D01*
X299283D01*
G01X304510Y-499646D02*
X306790Y-494479D01*
G01X309293Y-499479D02*
Y-494479D01*
X312207Y-499479D01*
Y-494479D01*
G01X315850Y-499646D02*
X315723Y-499562D01*
Y-499396D01*
X315850Y-499312D01*
X315977Y-499396D01*
Y-499562D01*
X315850Y-499646D01*
G01Y-497396D02*
X315723Y-497312D01*
Y-497146D01*
X315850Y-497062D01*
X315977Y-497146D01*
Y-497312D01*
X315850Y-497396D01*
G01X293650Y-514479D02*
X493650D01*
G01X293650Y-489479D02*
X493650D01*
G01X299283Y-474479D02*
Y-469479D01*
X300803D01*
X301310Y-469729D01*
X301690Y-470312D01*
X301817Y-470979D01*
X301690Y-471646D01*
X301373Y-472146D01*
X300803Y-472396D01*
X299283D01*
G01X304383Y-474479D02*
Y-469479D01*
X305967D01*
X306473Y-469729D01*
X306790Y-470062D01*
X306917Y-470729D01*
X306790Y-471396D01*
X306410Y-471812D01*
X305967Y-472062D01*
X304383D01*
G01X305967D02*
X306917Y-474479D01*
G01X310750D02*
X310243Y-474396D01*
X309800Y-474062D01*
X309420Y-473562D01*
X309167Y-472979D01*
X309040Y-472312D01*
Y-471646D01*
X309167Y-470979D01*
X309420Y-470396D01*
X309800Y-469896D01*
X310243Y-469562D01*
X310750Y-469479D01*
X311257Y-469562D01*
X311700Y-469896D01*
X312080Y-470396D01*
X312333Y-470979D01*
X312460Y-471646D01*
Y-472312D01*
X312333Y-472979D01*
X312080Y-473562D01*
X311700Y-474062D01*
X311257Y-474396D01*
X310750Y-474479D01*
G01X314583Y-473479D02*
X314900Y-473979D01*
X315280Y-474312D01*
X315723Y-474479D01*
X316230Y-474312D01*
X316610Y-473979D01*
X316990Y-473479D01*
X317117Y-472812D01*
Y-469479D01*
G01X322217Y-474479D02*
X319683D01*
Y-469479D01*
X322217D01*
G01X321203Y-471896D02*
X319683D01*
G01X327443Y-469896D02*
X327063Y-469646D01*
X326620Y-469479D01*
X326113D01*
X325543Y-469729D01*
X325100Y-470146D01*
X324783Y-470646D01*
X324530Y-471479D01*
X324467Y-472229D01*
X324593Y-472979D01*
X324783Y-473479D01*
X325163Y-473979D01*
X325607Y-474312D01*
X326050Y-474479D01*
X326493D01*
X326937Y-474312D01*
X327317Y-474062D01*
X327633Y-473729D01*
G01X331150Y-469479D02*
Y-474479D01*
G01X329693Y-469479D02*
X332607D01*
G01X336250Y-474646D02*
X336123Y-474562D01*
Y-474396D01*
X336250Y-474312D01*
X336377Y-474396D01*
Y-474562D01*
X336250Y-474646D01*
G01Y-472396D02*
X336123Y-472312D01*
Y-472146D01*
X336250Y-472062D01*
X336377Y-472146D01*
Y-472312D01*
X336250Y-472396D01*
G01X408650Y-514479D02*
Y-539479D01*
G01X411283Y-516979D02*
Y-521979D01*
X413817D01*
G01X416890Y-516979D02*
X418410D01*
G01X417650D02*
Y-521979D01*
G01X416890D02*
X418410D01*
G01X423257Y-519312D02*
X423510Y-519062D01*
X423700Y-518646D01*
X423827Y-518062D01*
X423700Y-517562D01*
X423447Y-517229D01*
X423003Y-516979D01*
X421293D01*
Y-521979D01*
X423383D01*
X423827Y-521646D01*
X424080Y-521146D01*
X424207Y-520562D01*
X424080Y-519979D01*
X423700Y-519479D01*
X423257Y-519312D01*
X421293D01*
G01X427850Y-522146D02*
X427723Y-522062D01*
Y-521896D01*
X427850Y-521812D01*
X427977Y-521896D01*
Y-522062D01*
X427850Y-522146D01*
G01Y-519896D02*
X427723Y-519812D01*
Y-519646D01*
X427850Y-519562D01*
X427977Y-519646D01*
Y-519812D01*
X427850Y-519896D01*
G01X451650Y-514479D02*
Y-539479D01*
G01Y-489479D02*
Y-514479D01*
G01X456663Y-541646D02*
X456770Y-541521D01*
X456850Y-541312D01*
X456903Y-541021D01*
X456850Y-540771D01*
X456743Y-540604D01*
X456557Y-540479D01*
X455837D01*
Y-542979D01*
X456717D01*
X456903Y-542812D01*
X457010Y-542562D01*
X457063Y-542271D01*
X457010Y-541979D01*
X456850Y-541729D01*
X456663Y-541646D01*
X455837D01*
G01X459130Y-542979D02*
Y-541312D01*
G01Y-541604D02*
X459023Y-541437D01*
X458863Y-541354D01*
X458677Y-541312D01*
X458490Y-541396D01*
X458330Y-541562D01*
X458223Y-541812D01*
X458170Y-542146D01*
X458223Y-542479D01*
X458330Y-542729D01*
X458490Y-542896D01*
X458677Y-542979D01*
X458863Y-542937D01*
X459023Y-542812D01*
X459130Y-542646D01*
G01X460450Y-542687D02*
X460583Y-542854D01*
X460770Y-542979D01*
X460930D01*
X461090Y-542896D01*
X461197Y-542771D01*
X461250Y-542604D01*
X461223Y-542354D01*
X461117Y-542229D01*
X460637Y-541979D01*
X460530Y-541687D01*
X460583Y-541479D01*
X460690Y-541354D01*
X460850Y-541312D01*
X461010Y-541354D01*
X461170Y-541479D01*
G01X462650Y-541854D02*
X463503D01*
X463423Y-541562D01*
X463290Y-541396D01*
X463103Y-541312D01*
X462917Y-541354D01*
X462757Y-541479D01*
X462650Y-541771D01*
X462597Y-542021D01*
Y-542271D01*
X462650Y-542521D01*
X462783Y-542771D01*
X462943Y-542937D01*
X463130Y-542979D01*
X463317Y-542896D01*
X463503Y-542646D01*
G01X464770Y-542979D02*
Y-540479D01*
G01Y-541729D02*
X464903Y-541479D01*
X465063Y-541354D01*
X465223Y-541312D01*
X465463Y-541396D01*
X465623Y-541562D01*
X465730Y-541854D01*
Y-542187D01*
X465677Y-542521D01*
X465570Y-542771D01*
X465383Y-542937D01*
X465223Y-542979D01*
X465063Y-542937D01*
X464903Y-542812D01*
X464770Y-542604D01*
G01X467450Y-542979D02*
X467290Y-542937D01*
X467130Y-542771D01*
X467023Y-542479D01*
X466970Y-542146D01*
X467023Y-541812D01*
X467130Y-541521D01*
X467290Y-541354D01*
X467450Y-541312D01*
X467610Y-541354D01*
X467770Y-541521D01*
X467877Y-541812D01*
X467903Y-542146D01*
X467877Y-542479D01*
X467770Y-542771D01*
X467610Y-542937D01*
X467450Y-542979D01*
G01X470130D02*
Y-541312D01*
G01Y-541604D02*
X470023Y-541437D01*
X469863Y-541354D01*
X469677Y-541312D01*
X469490Y-541396D01*
X469330Y-541562D01*
X469223Y-541812D01*
X469170Y-542146D01*
X469223Y-542479D01*
X469330Y-542729D01*
X469490Y-542896D01*
X469677Y-542979D01*
X469863Y-542937D01*
X470023Y-542812D01*
X470130Y-542646D01*
G01X471477Y-542979D02*
Y-541312D01*
G01Y-541646D02*
X471610Y-541479D01*
X471743Y-541354D01*
X471930Y-541312D01*
X472063Y-541354D01*
X472223Y-541479D01*
G01X474530Y-540479D02*
Y-542979D01*
G01Y-542604D02*
X474423Y-542812D01*
X474263Y-542937D01*
X474077Y-542979D01*
X473863Y-542896D01*
X473703Y-542687D01*
X473597Y-542437D01*
X473570Y-542146D01*
X473597Y-541854D01*
X473703Y-541604D01*
X473863Y-541396D01*
X474077Y-541312D01*
X474263Y-541354D01*
X474397Y-541437D01*
X474530Y-541604D01*
G01X477917Y-542979D02*
Y-540479D01*
X478583D01*
X478797Y-540604D01*
X478930Y-540771D01*
X478983Y-541104D01*
X478930Y-541437D01*
X478770Y-541646D01*
X478583Y-541771D01*
X477917D01*
G01X478583D02*
X478983Y-542979D01*
G01X480250Y-541854D02*
X481103D01*
X481023Y-541562D01*
X480890Y-541396D01*
X480703Y-541312D01*
X480517Y-541354D01*
X480357Y-541479D01*
X480250Y-541771D01*
X480197Y-542021D01*
Y-542271D01*
X480250Y-542521D01*
X480383Y-542771D01*
X480543Y-542937D01*
X480730Y-542979D01*
X480917Y-542896D01*
X481103Y-542646D01*
G01X482370Y-541312D02*
X482850Y-542979D01*
X483330Y-541312D01*
G01X485050Y-543062D02*
X484997Y-543021D01*
Y-542937D01*
X485050Y-542896D01*
X485103Y-542937D01*
Y-543021D01*
X485050Y-543062D01*
G01X487250Y-542979D02*
X487437Y-542937D01*
X487650Y-542812D01*
X487783Y-542604D01*
X487837Y-542312D01*
X487783Y-542021D01*
X487623Y-541771D01*
X487383Y-541646D01*
X487117D01*
X486957Y-541562D01*
X486823Y-541354D01*
X486770Y-541062D01*
X486850Y-540771D01*
X487037Y-540562D01*
X487250Y-540479D01*
X487463Y-540562D01*
X487650Y-540771D01*
X487730Y-541062D01*
X487677Y-541354D01*
X487543Y-541562D01*
X487383Y-541646D01*
X487117D01*
X486877Y-541771D01*
X486717Y-542021D01*
X486663Y-542312D01*
X486717Y-542604D01*
X486850Y-542812D01*
X487063Y-542937D01*
X487250Y-542979D01*
G01X489663Y-541646D02*
X489770Y-541521D01*
X489850Y-541312D01*
X489903Y-541021D01*
X489850Y-540771D01*
X489743Y-540604D01*
X489557Y-540479D01*
X488837D01*
Y-542979D01*
X489717D01*
X489903Y-542812D01*
X490010Y-542562D01*
X490063Y-542271D01*
X490010Y-541979D01*
X489850Y-541729D01*
X489663Y-541646D01*
X488837D01*
G01X455550Y-516979D02*
Y-521979D01*
G01X454093Y-516979D02*
X457007D01*
G01X460650Y-521979D02*
X460270Y-521896D01*
X459890Y-521562D01*
X459637Y-520979D01*
X459510Y-520312D01*
X459637Y-519646D01*
X459890Y-519062D01*
X460270Y-518729D01*
X460650Y-518646D01*
X461030Y-518729D01*
X461410Y-519062D01*
X461663Y-519646D01*
X461727Y-520312D01*
X461663Y-520979D01*
X461410Y-521562D01*
X461030Y-521896D01*
X460650Y-521979D01*
G01X465750D02*
X465370Y-521896D01*
X464990Y-521562D01*
X464737Y-520979D01*
X464610Y-520312D01*
X464737Y-519646D01*
X464990Y-519062D01*
X465370Y-518729D01*
X465750Y-518646D01*
X466130Y-518729D01*
X466510Y-519062D01*
X466763Y-519646D01*
X466827Y-520312D01*
X466763Y-520979D01*
X466510Y-521562D01*
X466130Y-521896D01*
X465750Y-521979D01*
G01X470850D02*
Y-516979D01*
G01X475950Y-522146D02*
X475823Y-522062D01*
Y-521896D01*
X475950Y-521812D01*
X476077Y-521896D01*
Y-522062D01*
X475950Y-522146D01*
G01Y-519896D02*
X475823Y-519812D01*
Y-519646D01*
X475950Y-519562D01*
X476077Y-519646D01*
Y-519812D01*
X475950Y-519896D01*
G01X454283Y-496979D02*
Y-491979D01*
X455867D01*
X456373Y-492229D01*
X456690Y-492562D01*
X456817Y-493229D01*
X456690Y-493896D01*
X456310Y-494312D01*
X455867Y-494562D01*
X454283D01*
G01X455867D02*
X456817Y-496979D01*
G01X461917D02*
X459383D01*
Y-491979D01*
X461917D01*
G01X460903Y-494396D02*
X459383D01*
G01X464167Y-491979D02*
X465750Y-496979D01*
X467333Y-491979D01*
G01X470850Y-497146D02*
X470723Y-497062D01*
Y-496896D01*
X470850Y-496812D01*
X470977Y-496896D01*
Y-497062D01*
X470850Y-497146D01*
G01Y-494896D02*
X470723Y-494812D01*
Y-494646D01*
X470850Y-494562D01*
X470977Y-494646D01*
Y-494812D01*
X470850Y-494896D01*
G01X-984580Y-698988D02*
Y4193602D01*
X5868320D01*
Y-698988D01*
X-984580D01*
G01X7723Y-521204D02*
X7253Y-520889D01*
X6705Y-520679D01*
X6078D01*
X5373Y-520994D01*
X4825Y-521519D01*
X4433Y-522149D01*
X4120Y-523199D01*
X4042Y-524144D01*
X4198Y-525089D01*
X4433Y-525719D01*
X4903Y-526349D01*
X5452Y-526769D01*
X6000Y-526979D01*
X6548D01*
X7097Y-526769D01*
X7567Y-526454D01*
X7958Y-526034D01*
G01X11360Y-520679D02*
X13240D01*
G01X12300D02*
Y-526979D01*
G01X11360D02*
X13240D01*
G01X18600Y-520679D02*
Y-526979D01*
G01X16798Y-520679D02*
X20402D01*
G01X24900Y-526979D02*
Y-524144D01*
X23333Y-520679D01*
G01X26467D02*
X24900Y-524144D01*
G01X35777Y-525719D02*
X36247Y-526454D01*
X36873Y-526874D01*
X37578Y-526979D01*
X38205Y-526874D01*
X38832Y-526349D01*
X39223Y-525719D01*
X39302Y-525089D01*
X39145Y-524354D01*
X38597Y-523829D01*
X38048Y-523619D01*
X37343D01*
G01X38048D02*
X38518Y-523304D01*
X38910Y-522779D01*
X39067Y-522149D01*
X38910Y-521519D01*
X38518Y-520994D01*
X37813Y-520679D01*
X37108Y-520784D01*
X36403Y-521204D01*
G01X42077Y-525719D02*
X42547Y-526454D01*
X43173Y-526874D01*
X43878Y-526979D01*
X44505Y-526874D01*
X45132Y-526349D01*
X45523Y-525719D01*
X45602Y-525089D01*
X45445Y-524354D01*
X44897Y-523829D01*
X44348Y-523619D01*
X43643D01*
G01X44348D02*
X44818Y-523304D01*
X45210Y-522779D01*
X45367Y-522149D01*
X45210Y-521519D01*
X44818Y-520994D01*
X44113Y-520679D01*
X43408Y-520784D01*
X42703Y-521204D01*
G01X48377Y-525719D02*
X48847Y-526454D01*
X49473Y-526874D01*
X50178Y-526979D01*
X50805Y-526874D01*
X51432Y-526349D01*
X51823Y-525719D01*
X51902Y-525089D01*
X51745Y-524354D01*
X51197Y-523829D01*
X50648Y-523619D01*
X49943D01*
G01X50648D02*
X51118Y-523304D01*
X51510Y-522779D01*
X51667Y-522149D01*
X51510Y-521519D01*
X51118Y-520994D01*
X50413Y-520679D01*
X49708Y-520784D01*
X49003Y-521204D01*
G01X56243Y-526979D02*
X56400Y-525614D01*
X56635Y-524459D01*
X56948Y-523409D01*
X57340Y-522254D01*
X57967Y-520679D01*
X54833D01*
G01X62543Y-526979D02*
X62700Y-525614D01*
X62935Y-524459D01*
X63248Y-523409D01*
X63640Y-522254D01*
X64267Y-520679D01*
X61133D01*
G01X68843Y-528134D02*
X69157Y-526769D01*
G01X75300Y-520679D02*
Y-526979D01*
G01X73498Y-520679D02*
X77102D01*
G01X79642Y-526979D02*
X81600Y-520679D01*
X83558Y-526979D01*
G01X82853Y-524774D02*
X80347D01*
G01X86960Y-520679D02*
X88840D01*
G01X87900D02*
Y-526979D01*
G01X86960D02*
X88840D01*
G01X91850Y-520679D02*
X92947Y-526979D01*
X94200Y-520679D01*
X95453Y-526979D01*
X96550Y-520679D01*
G01X98542Y-526979D02*
X100500Y-520679D01*
X102458Y-526979D01*
G01X101753Y-524774D02*
X99247D01*
G01X104998Y-526979D02*
Y-520679D01*
X108602Y-526979D01*
Y-520679D01*
G01X119008Y-529079D02*
X118225Y-528029D01*
X117833Y-526979D01*
Y-522779D01*
X118225Y-521729D01*
X119008Y-520679D01*
G01X130433Y-526979D02*
Y-520679D01*
X132392D01*
X133018Y-520994D01*
X133410Y-521414D01*
X133567Y-522254D01*
X133410Y-523094D01*
X132940Y-523619D01*
X132392Y-523934D01*
X130433D01*
G01X132392D02*
X133567Y-526979D01*
G01X138300Y-527189D02*
X138143Y-527084D01*
Y-526874D01*
X138300Y-526769D01*
X138457Y-526874D01*
Y-527084D01*
X138300Y-527189D01*
G01X144600Y-526979D02*
X143973Y-526874D01*
X143425Y-526454D01*
X142955Y-525824D01*
X142642Y-525089D01*
X142485Y-524249D01*
Y-523409D01*
X142642Y-522569D01*
X142955Y-521834D01*
X143425Y-521204D01*
X143973Y-520784D01*
X144600Y-520679D01*
X145227Y-520784D01*
X145775Y-521204D01*
X146245Y-521834D01*
X146558Y-522569D01*
X146715Y-523409D01*
Y-524249D01*
X146558Y-525089D01*
X146245Y-525824D01*
X145775Y-526454D01*
X145227Y-526874D01*
X144600Y-526979D01*
G01X150900Y-527189D02*
X150743Y-527084D01*
Y-526874D01*
X150900Y-526769D01*
X151057Y-526874D01*
Y-527084D01*
X150900Y-527189D01*
G01X158923Y-521204D02*
X158453Y-520889D01*
X157905Y-520679D01*
X157278D01*
X156573Y-520994D01*
X156025Y-521519D01*
X155633Y-522149D01*
X155320Y-523199D01*
X155242Y-524144D01*
X155398Y-525089D01*
X155633Y-525719D01*
X156103Y-526349D01*
X156652Y-526769D01*
X157200Y-526979D01*
X157748D01*
X158297Y-526769D01*
X158767Y-526454D01*
X159158Y-526034D01*
G01X163500Y-527189D02*
X163343Y-527084D01*
Y-526874D01*
X163500Y-526769D01*
X163657Y-526874D01*
Y-527084D01*
X163500Y-527189D01*
G01X170192Y-529079D02*
X170975Y-528029D01*
X171367Y-526979D01*
Y-522779D01*
X170975Y-521729D01*
X170192Y-520679D01*
G01X6470Y-513829D02*
X8037D01*
Y-515719D01*
X7567Y-516349D01*
X7018Y-516769D01*
X6235Y-516979D01*
X5452Y-516769D01*
X4903Y-516349D01*
X4433Y-515719D01*
X4120Y-514984D01*
X3963Y-514144D01*
Y-513409D01*
X4120Y-512779D01*
X4433Y-512044D01*
X4903Y-511414D01*
X5373Y-510994D01*
X6000Y-510679D01*
X6548D01*
X7175Y-510889D01*
X7645Y-511309D01*
G01X10577Y-510679D02*
Y-515194D01*
X10890Y-516139D01*
X11517Y-516769D01*
X12300Y-516979D01*
X13083Y-516769D01*
X13710Y-516139D01*
X14023Y-515194D01*
Y-510679D01*
G01X17660D02*
X19540D01*
G01X18600D02*
Y-516979D01*
G01X17660D02*
X19540D01*
G01X23255Y-516139D02*
X23882Y-516664D01*
X24587Y-516979D01*
X25213D01*
X25840Y-516664D01*
X26310Y-516139D01*
X26545Y-515404D01*
X26388Y-514669D01*
X25997Y-514039D01*
X25292Y-513619D01*
X24352Y-513409D01*
X23803Y-512989D01*
X23568Y-512254D01*
X23725Y-511519D01*
X24117Y-510994D01*
X24665Y-510679D01*
X25213D01*
X25762Y-510889D01*
X26232Y-511414D01*
G01X29555Y-516979D02*
Y-510679D01*
G01X32845D02*
Y-516979D01*
G01Y-513829D02*
X29555D01*
G01X35542Y-516979D02*
X37500Y-510679D01*
X39458Y-516979D01*
G01X38753Y-514774D02*
X36247D01*
G01X41998Y-516979D02*
Y-510679D01*
X45602Y-516979D01*
Y-510679D01*
G01X54677Y-516979D02*
Y-510679D01*
X56243D01*
X56870Y-510994D01*
X57340Y-511414D01*
X57732Y-512044D01*
X58045Y-512779D01*
X58123Y-513829D01*
X58045Y-514879D01*
X57732Y-515614D01*
X57340Y-516244D01*
X56870Y-516664D01*
X56243Y-516979D01*
X54677D01*
G01X61760Y-510679D02*
X63640D01*
G01X62700D02*
Y-516979D01*
G01X61760D02*
X63640D01*
G01X67355Y-516139D02*
X67982Y-516664D01*
X68687Y-516979D01*
X69313D01*
X69940Y-516664D01*
X70410Y-516139D01*
X70645Y-515404D01*
X70488Y-514669D01*
X70097Y-514039D01*
X69392Y-513619D01*
X68452Y-513409D01*
X67903Y-512989D01*
X67668Y-512254D01*
X67825Y-511519D01*
X68217Y-510994D01*
X68765Y-510679D01*
X69313D01*
X69862Y-510889D01*
X70332Y-511414D01*
G01X75300Y-510679D02*
Y-516979D01*
G01X73498Y-510679D02*
X77102D01*
G01X81600Y-517189D02*
X81443Y-517084D01*
Y-516874D01*
X81600Y-516769D01*
X81757Y-516874D01*
Y-517084D01*
X81600Y-517189D01*
G01X87743Y-518134D02*
X88057Y-516769D01*
G01X94200Y-510679D02*
Y-516979D01*
G01X92398Y-510679D02*
X96002D01*
G01X98542Y-516979D02*
X100500Y-510679D01*
X102458Y-516979D01*
G01X101753Y-514774D02*
X99247D01*
G01X106800Y-516979D02*
X106173Y-516874D01*
X105625Y-516454D01*
X105155Y-515824D01*
X104842Y-515089D01*
X104685Y-514249D01*
Y-513409D01*
X104842Y-512569D01*
X105155Y-511834D01*
X105625Y-511204D01*
X106173Y-510784D01*
X106800Y-510679D01*
X107427Y-510784D01*
X107975Y-511204D01*
X108445Y-511834D01*
X108758Y-512569D01*
X108915Y-513409D01*
Y-514249D01*
X108758Y-515089D01*
X108445Y-515824D01*
X107975Y-516454D01*
X107427Y-516874D01*
X106800Y-516979D01*
G01X113100D02*
Y-514144D01*
X111533Y-510679D01*
G01X114667D02*
X113100Y-514144D01*
G01X117677Y-510679D02*
Y-515194D01*
X117990Y-516139D01*
X118617Y-516769D01*
X119400Y-516979D01*
X120183Y-516769D01*
X120810Y-516139D01*
X121123Y-515194D01*
Y-510679D01*
G01X123742Y-516979D02*
X125700Y-510679D01*
X127658Y-516979D01*
G01X126953Y-514774D02*
X124447D01*
G01X130198Y-516979D02*
Y-510679D01*
X133802Y-516979D01*
Y-510679D01*
G01X4198Y-506979D02*
Y-500679D01*
X7802Y-506979D01*
Y-500679D01*
G01X12300Y-506979D02*
X11673Y-506874D01*
X11125Y-506454D01*
X10655Y-505824D01*
X10342Y-505089D01*
X10185Y-504249D01*
Y-503409D01*
X10342Y-502569D01*
X10655Y-501834D01*
X11125Y-501204D01*
X11673Y-500784D01*
X12300Y-500679D01*
X12927Y-500784D01*
X13475Y-501204D01*
X13945Y-501834D01*
X14258Y-502569D01*
X14415Y-503409D01*
Y-504249D01*
X14258Y-505089D01*
X13945Y-505824D01*
X13475Y-506454D01*
X12927Y-506874D01*
X12300Y-506979D01*
G01X18600Y-507189D02*
X18443Y-507084D01*
Y-506874D01*
X18600Y-506769D01*
X18757Y-506874D01*
Y-507084D01*
X18600Y-507189D01*
G01X23412Y-501729D02*
X23882Y-501099D01*
X24430Y-500784D01*
X25057Y-500679D01*
X25840Y-500889D01*
X26388Y-501414D01*
X26545Y-502044D01*
X26467Y-502674D01*
X26153Y-503199D01*
X24587Y-504249D01*
X23882Y-504984D01*
X23412Y-506034D01*
X23255Y-506979D01*
X26545D01*
G01X31200D02*
Y-500679D01*
X30260Y-501939D01*
G01Y-506979D02*
X32140D01*
G01X37500D02*
Y-500679D01*
X36560Y-501939D01*
G01Y-506979D02*
X38440D01*
G01X43643Y-508134D02*
X43957Y-506769D01*
G01X47750Y-500679D02*
X48847Y-506979D01*
X50100Y-500679D01*
X51353Y-506979D01*
X52450Y-500679D01*
G01X57967Y-506979D02*
X54833D01*
Y-500679D01*
X57967D01*
G01X56713Y-503724D02*
X54833D01*
G01X60898Y-506979D02*
Y-500679D01*
X64502Y-506979D01*
Y-500679D01*
G01X67355Y-506979D02*
Y-500679D01*
G01X70645D02*
Y-506979D01*
G01Y-503829D02*
X67355D01*
G01X73577Y-500679D02*
Y-505194D01*
X73890Y-506139D01*
X74517Y-506769D01*
X75300Y-506979D01*
X76083Y-506769D01*
X76710Y-506139D01*
X77023Y-505194D01*
Y-500679D01*
G01X79642Y-506979D02*
X81600Y-500679D01*
X83558Y-506979D01*
G01X82853Y-504774D02*
X80347D01*
G01X92712Y-501729D02*
X93182Y-501099D01*
X93730Y-500784D01*
X94357Y-500679D01*
X95140Y-500889D01*
X95688Y-501414D01*
X95845Y-502044D01*
X95767Y-502674D01*
X95453Y-503199D01*
X93887Y-504249D01*
X93182Y-504984D01*
X92712Y-506034D01*
X92555Y-506979D01*
X95845D01*
G01X98698D02*
Y-500679D01*
X102302Y-506979D01*
Y-500679D01*
G01X105077Y-506979D02*
Y-500679D01*
X106643D01*
X107270Y-500994D01*
X107740Y-501414D01*
X108132Y-502044D01*
X108445Y-502779D01*
X108523Y-503829D01*
X108445Y-504879D01*
X108132Y-505614D01*
X107740Y-506244D01*
X107270Y-506664D01*
X106643Y-506979D01*
X105077D01*
G01X117833D02*
Y-500679D01*
X119792D01*
X120418Y-500994D01*
X120810Y-501414D01*
X120967Y-502254D01*
X120810Y-503094D01*
X120340Y-503619D01*
X119792Y-503934D01*
X117833D01*
G01X119792D02*
X120967Y-506979D01*
G01X123977D02*
Y-500679D01*
X125543D01*
X126170Y-500994D01*
X126640Y-501414D01*
X127032Y-502044D01*
X127345Y-502779D01*
X127423Y-503829D01*
X127345Y-504879D01*
X127032Y-505614D01*
X126640Y-506244D01*
X126170Y-506664D01*
X125543Y-506979D01*
X123977D01*
G01X132000Y-507189D02*
X131843Y-507084D01*
Y-506874D01*
X132000Y-506769D01*
X132157Y-506874D01*
Y-507084D01*
X132000Y-507189D01*
G01X28300Y-494279D02*
X25780Y-493862D01*
X23575Y-492196D01*
X21685Y-489696D01*
X20425Y-486779D01*
X19795Y-483446D01*
Y-480112D01*
X20425Y-476779D01*
X21685Y-473862D01*
X23575Y-471363D01*
X25780Y-469696D01*
X28300Y-469279D01*
X30820Y-469696D01*
X33025Y-471363D01*
X34915Y-473862D01*
X36175Y-476779D01*
X36805Y-480112D01*
Y-483446D01*
X36175Y-486779D01*
X34915Y-489696D01*
X33025Y-492196D01*
X30820Y-493862D01*
X28300Y-494279D01*
G01X30820Y-487612D02*
X34600Y-494279D01*
G01X48145Y-477613D02*
Y-489279D01*
X49405Y-492196D01*
X51295Y-493862D01*
X53500Y-494279D01*
X55705Y-493862D01*
X57595Y-492196D01*
X58855Y-489279D01*
G01Y-494279D02*
Y-477613D01*
G01X84370Y-494279D02*
Y-477613D01*
G01Y-480529D02*
X83110Y-478863D01*
X81220Y-478029D01*
X79015Y-477613D01*
X76810Y-478446D01*
X74920Y-480112D01*
X73660Y-482613D01*
X73030Y-485946D01*
X73660Y-489279D01*
X74920Y-491780D01*
X76810Y-493446D01*
X79015Y-494279D01*
X81220Y-493862D01*
X83110Y-492613D01*
X84370Y-490946D01*
G01X98545Y-494279D02*
Y-477613D01*
G01Y-481779D02*
X99805Y-479696D01*
X101695Y-478029D01*
X104215Y-477613D01*
X106420Y-478029D01*
X108310Y-479696D01*
X109255Y-482613D01*
Y-494279D01*
G01X129100Y-469279D02*
Y-494279D01*
G01X124690Y-477613D02*
X133510D01*
G01X159970Y-494279D02*
Y-477613D01*
G01Y-480529D02*
X158710Y-478863D01*
X156820Y-478029D01*
X154615Y-477613D01*
X152410Y-478446D01*
X150520Y-480112D01*
X149260Y-482613D01*
X148630Y-485946D01*
X149260Y-489279D01*
X150520Y-491780D01*
X152410Y-493446D01*
X154615Y-494279D01*
X156820Y-493862D01*
X158710Y-492613D01*
X159970Y-490946D01*
G01X104972Y658375D02*
Y659844D01*
X105760Y660632D01*
G01X125070Y486736D02*
X121077Y490729D01*
Y497264D01*
X119138Y499203D01*
Y500919D01*
G01X125013Y491829D02*
X127175Y493991D01*
Y495387D01*
X130162Y498374D01*
Y500919D01*
G01X124124Y495883D02*
X125379Y497138D01*
X126570D01*
X128587Y499155D01*
Y500919D01*
G01X164000Y1408862D02*
X164666Y1407545D01*
Y1403338D01*
G01X199650Y-473979D02*
Y-481979D01*
X203650D01*
G01X211450D02*
Y-476646D01*
G01Y-477579D02*
X211050Y-477046D01*
X210450Y-476779D01*
X209750Y-476646D01*
X209050Y-476912D01*
X208450Y-477446D01*
X208050Y-478246D01*
X207850Y-479312D01*
X208050Y-480379D01*
X208450Y-481179D01*
X209050Y-481712D01*
X209750Y-481979D01*
X210450Y-481846D01*
X211050Y-481446D01*
X211450Y-480913D01*
G01X215550Y-484379D02*
X216150Y-484646D01*
X216950Y-484379D01*
X217450Y-483846D01*
X217850Y-483179D01*
X218450Y-481046D01*
X219750Y-476646D01*
G01X216550D02*
X218450Y-481046D01*
G01X224150Y-478379D02*
X227350D01*
X227050Y-477446D01*
X226550Y-476912D01*
X225850Y-476646D01*
X225150Y-476779D01*
X224550Y-477179D01*
X224150Y-478112D01*
X223950Y-478913D01*
Y-479712D01*
X224150Y-480512D01*
X224650Y-481312D01*
X225250Y-481846D01*
X225950Y-481979D01*
X226650Y-481712D01*
X227350Y-480913D01*
G01X232250Y-481979D02*
Y-476646D01*
G01Y-477712D02*
X232750Y-477179D01*
X233250Y-476779D01*
X233950Y-476646D01*
X234450Y-476779D01*
X235050Y-477179D01*
G01X194196Y687061D02*
X194787Y687652D01*
X196850Y688507D01*
X199866D01*
G01X200797Y1409605D02*
X201798Y1408603D01*
X202809Y1406163D01*
Y1403338D01*
G01X223350Y-531979D02*
Y-523979D01*
X227950Y-531979D01*
Y-523979D01*
G01X233650Y-526646D02*
Y-531979D01*
G01Y-524512D02*
X233450Y-524379D01*
Y-524112D01*
X233650Y-523979D01*
X233850Y-524112D01*
Y-524379D01*
X233650Y-524512D01*
G01X239950Y-531979D02*
Y-526646D01*
G01Y-527979D02*
X240350Y-527312D01*
X240950Y-526779D01*
X241750Y-526646D01*
X242450Y-526779D01*
X243050Y-527312D01*
X243350Y-528246D01*
Y-531979D01*
G01X251450D02*
Y-526646D01*
G01Y-527579D02*
X251050Y-527046D01*
X250450Y-526779D01*
X249750Y-526646D01*
X249050Y-526912D01*
X248450Y-527446D01*
X248050Y-528246D01*
X247850Y-529312D01*
X248050Y-530379D01*
X248450Y-531179D01*
X249050Y-531712D01*
X249750Y-531979D01*
X250450Y-531846D01*
X251050Y-531446D01*
X251450Y-530913D01*
G01X226679Y-500436D02*
Y-508436D01*
G01X224379Y-500436D02*
X228979D01*
G01X234679Y-508436D02*
X233879Y-508303D01*
X233179Y-507769D01*
X232579Y-506969D01*
X232179Y-506036D01*
X231979Y-504969D01*
Y-503903D01*
X232179Y-502836D01*
X232579Y-501903D01*
X233179Y-501103D01*
X233879Y-500569D01*
X234679Y-500436D01*
X235479Y-500569D01*
X236179Y-501103D01*
X236779Y-501903D01*
X237179Y-502836D01*
X237379Y-503903D01*
Y-504969D01*
X237179Y-506036D01*
X236779Y-506969D01*
X236179Y-507769D01*
X235479Y-508303D01*
X234679Y-508436D01*
G01X240679D02*
Y-500436D01*
X243079D01*
X243879Y-500836D01*
X244479Y-501769D01*
X244679Y-502836D01*
X244479Y-503903D01*
X243979Y-504703D01*
X243079Y-505103D01*
X240679D01*
G01X328876Y865299D02*
X326376Y862799D01*
Y848510D01*
X329584Y845302D01*
Y842907D01*
X329764Y842727D01*
Y842652D01*
G01X328168Y866007D02*
X325376Y863215D01*
Y848095D01*
X328584Y844887D01*
Y842762D01*
X328474Y842652D01*
G01X330441Y908158D02*
X328752D01*
X314316Y893722D01*
Y885299D01*
X307996Y878979D01*
Y855051D01*
X306992Y852624D01*
X305880Y851512D01*
Y851306D01*
X305774Y851200D01*
G01X330441Y909158D02*
X328337D01*
X313316Y894137D01*
Y885714D01*
X306996Y879394D01*
Y855250D01*
X306143Y853191D01*
X305169Y852217D01*
X304967Y852218D01*
X304861Y852112D01*
G01X328624Y927012D02*
X325588D01*
X303781Y905205D01*
X302173Y904539D01*
X300820D01*
X300419Y904544D01*
X300273Y904400D01*
X300123D01*
G01X328624Y928012D02*
X325173D01*
X303214Y906054D01*
X301974Y905539D01*
X300827D01*
X300429Y905544D01*
X300287Y905690D01*
X300137D01*
G01X326524Y945470D02*
X319119D01*
X318974Y945325D01*
X318824D01*
G01Y946615D02*
X318974D01*
X319119Y946470D01*
X326524D01*
G01X325726Y1034088D02*
X324175D01*
X302420Y1055843D01*
X300132D01*
X297582Y1058393D01*
X297378D01*
X297272Y1058499D01*
G01X325726Y1035088D02*
X324590D01*
X302835Y1056843D01*
X300548D01*
X298291Y1059100D01*
Y1059306D01*
X298185Y1059412D01*
G01X326481Y1059708D02*
X305597Y1080592D01*
X300530Y1090071D01*
X297973Y1102925D01*
Y1102927D01*
X295775Y1108711D01*
X294638Y1109848D01*
X294434D01*
X294328Y1109954D01*
G01X327189Y1060416D02*
X306408Y1081197D01*
X301482Y1090412D01*
X298938Y1103203D01*
X296634Y1109267D01*
X295347Y1110554D01*
Y1110761D01*
X295241Y1110867D01*
G01X328523Y1079849D02*
X318038Y1090334D01*
X315448Y1095184D01*
X312728Y1108785D01*
Y1145029D01*
X312074Y1145683D01*
X311870D01*
X311764Y1145789D01*
G01X329231Y1080557D02*
X318851Y1090937D01*
X316400Y1095525D01*
X313728Y1108885D01*
Y1145444D01*
X312783Y1146389D01*
Y1146596D01*
X312677Y1146702D01*
G01X331507Y1099832D02*
X330272Y1101067D01*
X328128Y1111787D01*
Y1165984D01*
X327285Y1170221D01*
X327283Y1170227D01*
X326441Y1172292D01*
X325163Y1173570D01*
X324958D01*
X324852Y1173676D01*
G01X325765Y1174589D02*
X325871Y1174483D01*
Y1174277D01*
X327291Y1172857D01*
X328246Y1170521D01*
X329128Y1166083D01*
Y1111887D01*
X331194Y1101561D01*
X332215Y1100540D01*
G01X246679Y-483436D02*
Y-475436D01*
X245479Y-477036D01*
G01Y-483436D02*
X247879D01*
G01X330571Y865003D02*
X327776Y862208D01*
Y849096D01*
X332430Y844442D01*
Y842947D01*
X332285Y842802D01*
Y842652D01*
G01X333575D02*
Y842802D01*
X333430Y842947D01*
Y844857D01*
X328776Y849511D01*
Y861792D01*
X331279Y864295D01*
G01X330441Y906741D02*
X329315D01*
X315716Y893142D01*
Y884719D01*
X309396Y878399D01*
Y854197D01*
X308949Y853118D01*
Y849912D01*
X308798Y849761D01*
X308214Y849178D01*
X308008D01*
X307902Y849072D01*
G01X308815Y848160D02*
X308921Y848266D01*
X308920Y848468D01*
X309949Y849497D01*
Y852919D01*
X310396Y853998D01*
Y877984D01*
X316716Y884304D01*
Y892727D01*
X329730Y905741D01*
X330441D01*
G01X328624Y925488D02*
X326044D01*
X301798Y901242D01*
X300418D01*
X300273Y901387D01*
X300123D01*
G01Y900097D02*
X300273D01*
X300418Y900242D01*
X302213D01*
X326459Y924488D01*
X328624D01*
G01X318824Y941000D02*
X318974D01*
X319119Y941145D01*
X326695D01*
X328040Y942490D01*
G01X327333Y943198D02*
X326280Y942145D01*
X319119D01*
X318974Y942290D01*
X318824D01*
G01X294224Y1055452D02*
X294330Y1055346D01*
X294532D01*
X295705Y1054174D01*
X296528Y1053351D01*
X301516D01*
X323346Y1031521D01*
X327026D01*
G01Y1032521D02*
X323761D01*
X301931Y1054351D01*
X296944D01*
X295243Y1056052D01*
Y1056258D01*
X295137Y1056364D01*
G01X328306Y1055903D02*
X304460Y1079749D01*
X299220Y1089423D01*
X296528Y1102237D01*
X295335Y1104446D01*
X293387Y1106393D01*
Y1106600D01*
X293281Y1106706D01*
G01X327598Y1055195D02*
X303649Y1079144D01*
X298271Y1089075D01*
X295579Y1101889D01*
X294525Y1103840D01*
X292676Y1105688D01*
X292474D01*
X292368Y1105794D01*
G01X328916Y1077475D02*
X316901Y1089490D01*
X314116Y1094692D01*
X311328Y1108633D01*
Y1140947D01*
X310751Y1142338D01*
X309742Y1143347D01*
Y1143555D01*
X309636Y1143661D01*
G01X308723Y1142749D02*
X308829Y1142643D01*
X309031D01*
X309903Y1141771D01*
X310328Y1140747D01*
Y1108533D01*
X313164Y1094351D01*
X316088Y1088887D01*
X328208Y1076767D01*
G01X331090Y1096816D02*
X328049Y1099857D01*
Y1099858D01*
X325728Y1111529D01*
Y1164911D01*
X324084Y1168892D01*
X323360Y1169975D01*
X322463Y1170872D01*
X322259D01*
X322153Y1170978D01*
G01X323066Y1171891D02*
X323172Y1171785D01*
Y1171579D01*
X324138Y1170613D01*
X324971Y1169365D01*
X326728Y1165110D01*
Y1111628D01*
X328971Y1100351D01*
X331798Y1097524D01*
G01X326250Y-525312D02*
X326850Y-524512D01*
X327550Y-524112D01*
X328350Y-523979D01*
X329350Y-524246D01*
X330050Y-524912D01*
X330250Y-525712D01*
X330150Y-526513D01*
X329750Y-527179D01*
X327750Y-528512D01*
X326850Y-529446D01*
X326250Y-530779D01*
X326050Y-531979D01*
X330250D01*
G01X336150Y-523979D02*
X335350Y-524246D01*
X334750Y-524912D01*
X334350Y-525712D01*
X334050Y-526779D01*
X333950Y-527979D01*
X334050Y-529179D01*
X334350Y-530246D01*
X334750Y-531046D01*
X335350Y-531712D01*
X336150Y-531979D01*
X336950Y-531712D01*
X337550Y-531046D01*
X337950Y-530246D01*
X338250Y-529179D01*
X338350Y-527979D01*
X338250Y-526779D01*
X337950Y-525712D01*
X337550Y-524912D01*
X336950Y-524246D01*
X336150Y-523979D01*
G01X342250Y-525312D02*
X342850Y-524512D01*
X343550Y-524112D01*
X344350Y-523979D01*
X345350Y-524246D01*
X346050Y-524912D01*
X346250Y-525712D01*
X346150Y-526513D01*
X345750Y-527179D01*
X343750Y-528512D01*
X342850Y-529446D01*
X342250Y-530779D01*
X342050Y-531979D01*
X346250D01*
G01X349950Y-530379D02*
X350550Y-531312D01*
X351350Y-531846D01*
X352250Y-531979D01*
X353050Y-531846D01*
X353850Y-531179D01*
X354350Y-530379D01*
X354450Y-529579D01*
X354250Y-528646D01*
X353550Y-527979D01*
X352850Y-527712D01*
X351950D01*
G01X352850D02*
X353450Y-527312D01*
X353950Y-526646D01*
X354150Y-525846D01*
X353950Y-525046D01*
X353450Y-524379D01*
X352550Y-523979D01*
X351650Y-524112D01*
X350750Y-524646D01*
G01X358350Y-532246D02*
X361950Y-523979D01*
G01X368150D02*
X367350Y-524246D01*
X366750Y-524912D01*
X366350Y-525712D01*
X366050Y-526779D01*
X365950Y-527979D01*
X366050Y-529179D01*
X366350Y-530246D01*
X366750Y-531046D01*
X367350Y-531712D01*
X368150Y-531979D01*
X368950Y-531712D01*
X369550Y-531046D01*
X369950Y-530246D01*
X370250Y-529179D01*
X370350Y-527979D01*
X370250Y-526779D01*
X369950Y-525712D01*
X369550Y-524912D01*
X368950Y-524246D01*
X368150Y-523979D01*
G01X373950Y-530379D02*
X374550Y-531312D01*
X375350Y-531846D01*
X376250Y-531979D01*
X377050Y-531846D01*
X377850Y-531179D01*
X378350Y-530379D01*
X378450Y-529579D01*
X378250Y-528646D01*
X377550Y-527979D01*
X376850Y-527712D01*
X375950D01*
G01X376850D02*
X377450Y-527312D01*
X377950Y-526646D01*
X378150Y-525846D01*
X377950Y-525046D01*
X377450Y-524379D01*
X376550Y-523979D01*
X375650Y-524112D01*
X374750Y-524646D01*
G01X382350Y-532246D02*
X385950Y-523979D01*
G01X390250Y-525312D02*
X390850Y-524512D01*
X391550Y-524112D01*
X392350Y-523979D01*
X393350Y-524246D01*
X394050Y-524912D01*
X394250Y-525712D01*
X394150Y-526513D01*
X393750Y-527179D01*
X391750Y-528512D01*
X390850Y-529446D01*
X390250Y-530779D01*
X390050Y-531979D01*
X394250D01*
G01X401350D02*
Y-523979D01*
X397650Y-529712D01*
X402650D01*
G01X325950Y-506979D02*
Y-498979D01*
X327950D01*
X328750Y-499379D01*
X329350Y-499912D01*
X329850Y-500712D01*
X330250Y-501646D01*
X330350Y-502979D01*
X330250Y-504312D01*
X329850Y-505246D01*
X329350Y-506046D01*
X328750Y-506579D01*
X327950Y-506979D01*
X325950D01*
G01X333650D02*
X336150Y-498979D01*
X338650Y-506979D01*
G01X337750Y-504179D02*
X334550D01*
G01X344150Y-498979D02*
X343350Y-499246D01*
X342750Y-499912D01*
X342350Y-500712D01*
X342050Y-501779D01*
X341950Y-502979D01*
X342050Y-504179D01*
X342350Y-505246D01*
X342750Y-506046D01*
X343350Y-506712D01*
X344150Y-506979D01*
X344950Y-506712D01*
X345550Y-506046D01*
X345950Y-505246D01*
X346250Y-504179D01*
X346350Y-502979D01*
X346250Y-501779D01*
X345950Y-500712D01*
X345550Y-499912D01*
X344950Y-499246D01*
X344150Y-498979D01*
G01X350250Y-506979D02*
Y-498979D01*
X354050D01*
G01X352650Y-502846D02*
X350250D01*
G01X360150Y-498979D02*
X359350Y-499246D01*
X358750Y-499912D01*
X358350Y-500712D01*
X358050Y-501779D01*
X357950Y-502979D01*
X358050Y-504179D01*
X358350Y-505246D01*
X358750Y-506046D01*
X359350Y-506712D01*
X360150Y-506979D01*
X360950Y-506712D01*
X361550Y-506046D01*
X361950Y-505246D01*
X362250Y-504179D01*
X362350Y-502979D01*
X362250Y-501779D01*
X361950Y-500712D01*
X361550Y-499912D01*
X360950Y-499246D01*
X360150Y-498979D01*
G01X368150D02*
Y-506979D01*
G01X365850Y-498979D02*
X370450D01*
G01X373550Y-506979D02*
Y-498979D01*
X376150Y-505646D01*
X378750Y-498979D01*
Y-506979D01*
G01X384950Y-502712D02*
X385350Y-502312D01*
X385650Y-501646D01*
X385850Y-500712D01*
X385650Y-499912D01*
X385250Y-499379D01*
X384550Y-498979D01*
X381850D01*
Y-506979D01*
X385150D01*
X385850Y-506446D01*
X386250Y-505646D01*
X386450Y-504712D01*
X386250Y-503779D01*
X385650Y-502979D01*
X384950Y-502712D01*
X381850D01*
G01X390950Y-498979D02*
X393350D01*
G01X392150D02*
Y-506979D01*
G01X390950D02*
X393350D01*
G01X398150Y-505379D02*
X398650Y-506179D01*
X399250Y-506712D01*
X399950Y-506979D01*
X400750Y-506712D01*
X401350Y-506179D01*
X401950Y-505379D01*
X402150Y-504312D01*
Y-498979D01*
G01X408150D02*
X407350Y-499246D01*
X406750Y-499912D01*
X406350Y-500712D01*
X406050Y-501779D01*
X405950Y-502979D01*
X406050Y-504179D01*
X406350Y-505246D01*
X406750Y-506046D01*
X407350Y-506712D01*
X408150Y-506979D01*
X408950Y-506712D01*
X409550Y-506046D01*
X409950Y-505246D01*
X410250Y-504179D01*
X410350Y-502979D01*
X410250Y-501779D01*
X409950Y-500712D01*
X409550Y-499912D01*
X408950Y-499246D01*
X408150Y-498979D01*
G01X343750Y-481979D02*
Y-473979D01*
X347550D01*
G01X346150Y-477846D02*
X343750D01*
G01X353650Y-473979D02*
X352850Y-474246D01*
X352250Y-474912D01*
X351850Y-475712D01*
X351550Y-476779D01*
X351450Y-477979D01*
X351550Y-479179D01*
X351850Y-480246D01*
X352250Y-481046D01*
X352850Y-481712D01*
X353650Y-481979D01*
X354450Y-481712D01*
X355050Y-481046D01*
X355450Y-480246D01*
X355750Y-479179D01*
X355850Y-477979D01*
X355750Y-476779D01*
X355450Y-475712D01*
X355050Y-474912D01*
X354450Y-474246D01*
X353650Y-473979D01*
G01X361650D02*
Y-481979D01*
G01X359350Y-473979D02*
X363950D01*
G01X366650Y-484646D02*
X372650D01*
G01X375050Y-481979D02*
Y-473979D01*
X377650Y-480646D01*
X380250Y-473979D01*
Y-481979D01*
G01X386450Y-477712D02*
X386850Y-477312D01*
X387150Y-476646D01*
X387350Y-475712D01*
X387150Y-474912D01*
X386750Y-474379D01*
X386050Y-473979D01*
X383350D01*
Y-481979D01*
X386650D01*
X387350Y-481446D01*
X387750Y-480646D01*
X387950Y-479712D01*
X387750Y-478779D01*
X387150Y-477979D01*
X386450Y-477712D01*
X383350D01*
G01X390650Y-484646D02*
X396650D01*
G01X403650Y-481979D02*
X399650D01*
Y-473979D01*
X403650D01*
G01X402050Y-477846D02*
X399650D01*
G01X407050Y-481979D02*
Y-473979D01*
X409650Y-480646D01*
X412250Y-473979D01*
Y-481979D01*
G01X417650D02*
X418350Y-481846D01*
X419150Y-481446D01*
X419650Y-480779D01*
X419850Y-479846D01*
X419650Y-478913D01*
X419050Y-478112D01*
X418150Y-477712D01*
X417150D01*
X416550Y-477446D01*
X416050Y-476779D01*
X415850Y-475846D01*
X416150Y-474912D01*
X416850Y-474246D01*
X417650Y-473979D01*
X418450Y-474246D01*
X419150Y-474912D01*
X419450Y-475846D01*
X419250Y-476779D01*
X418750Y-477446D01*
X418150Y-477712D01*
X417150D01*
X416250Y-478112D01*
X415650Y-478913D01*
X415450Y-479846D01*
X415650Y-480779D01*
X416150Y-481446D01*
X416950Y-481846D01*
X417650Y-481979D01*
G01X423950Y-481046D02*
X424650Y-481712D01*
X425450Y-481979D01*
X426250Y-481712D01*
X426950Y-480913D01*
X427450Y-479712D01*
X427650Y-478512D01*
Y-477046D01*
X427450Y-475846D01*
X426950Y-474779D01*
X426350Y-474246D01*
X425650Y-473979D01*
X424850Y-474246D01*
X424250Y-474779D01*
X423850Y-475579D01*
X423650Y-476646D01*
X423850Y-477579D01*
X424350Y-478512D01*
X424950Y-479046D01*
X425650Y-479179D01*
X426450Y-478913D01*
X427050Y-478246D01*
X427650Y-477046D01*
G01X433650Y-473979D02*
X432850Y-474246D01*
X432250Y-474912D01*
X431850Y-475712D01*
X431550Y-476779D01*
X431450Y-477979D01*
X431550Y-479179D01*
X431850Y-480246D01*
X432250Y-481046D01*
X432850Y-481712D01*
X433650Y-481979D01*
X434450Y-481712D01*
X435050Y-481046D01*
X435450Y-480246D01*
X435750Y-479179D01*
X435850Y-477979D01*
X435750Y-476779D01*
X435450Y-475712D01*
X435050Y-474912D01*
X434450Y-474246D01*
X433650Y-473979D01*
G01X439450Y-481979D02*
Y-473979D01*
G01X443250D02*
X439450Y-478913D01*
G01X443850Y-481979D02*
X441150Y-476646D01*
G01X414650Y-534979D02*
Y-526979D01*
X413450Y-528579D01*
G01Y-534979D02*
X415850D01*
G01X420750Y-531646D02*
X421450Y-530712D01*
X422050Y-530179D01*
X422850Y-529912D01*
X423550Y-530179D01*
X424050Y-530712D01*
X424450Y-531512D01*
X424550Y-532446D01*
X424450Y-533246D01*
X424050Y-534046D01*
X423450Y-534712D01*
X422750Y-534979D01*
X421950Y-534712D01*
X421250Y-533913D01*
X420850Y-532712D01*
X420750Y-531379D01*
X420950Y-529646D01*
X421250Y-528712D01*
X421750Y-527779D01*
X422450Y-527112D01*
X423150Y-526979D01*
X423850Y-527246D01*
X424350Y-527912D01*
G01X430650Y-535246D02*
X430450Y-535112D01*
Y-534846D01*
X430650Y-534712D01*
X430850Y-534846D01*
Y-535112D01*
X430650Y-535246D01*
G01X436750Y-531646D02*
X437450Y-530712D01*
X438050Y-530179D01*
X438850Y-529912D01*
X439550Y-530179D01*
X440050Y-530712D01*
X440450Y-531512D01*
X440550Y-532446D01*
X440450Y-533246D01*
X440050Y-534046D01*
X439450Y-534712D01*
X438750Y-534979D01*
X437950Y-534712D01*
X437250Y-533913D01*
X436850Y-532712D01*
X436750Y-531379D01*
X436950Y-529646D01*
X437250Y-528712D01*
X437750Y-527779D01*
X438450Y-527112D01*
X439150Y-526979D01*
X439850Y-527246D01*
X440350Y-527912D01*
G01X459650Y-534979D02*
Y-526979D01*
X458450Y-528579D01*
G01Y-534979D02*
X460850D01*
G01X467450D02*
X467650Y-533246D01*
X467950Y-531779D01*
X468350Y-530446D01*
X468850Y-528979D01*
X469650Y-526979D01*
X465650D01*
G01X475650Y-535246D02*
X475450Y-535112D01*
Y-534846D01*
X475650Y-534712D01*
X475850Y-534846D01*
Y-535112D01*
X475650Y-535246D01*
G01X481750Y-528312D02*
X482350Y-527512D01*
X483050Y-527112D01*
X483850Y-526979D01*
X484850Y-527246D01*
X485550Y-527912D01*
X485750Y-528712D01*
X485650Y-529513D01*
X485250Y-530179D01*
X483250Y-531512D01*
X482350Y-532446D01*
X481750Y-533779D01*
X481550Y-534979D01*
X485750D01*
G01X479650Y-508379D02*
X480150Y-509179D01*
X480750Y-509712D01*
X481450Y-509979D01*
X482250Y-509712D01*
X482850Y-509179D01*
X483450Y-508379D01*
X483650Y-507312D01*
Y-501979D01*
G01X568122Y1002971D02*
X567918D01*
X565873Y1000926D01*
X561116Y997021D01*
X554429Y994252D01*
X542830Y991946D01*
X539466Y991615D01*
X536291Y990807D01*
X534978Y990325D01*
X528723Y987270D01*
X526509Y985908D01*
X526494Y985896D01*
X526479Y985885D01*
Y984866D01*
G01X573058Y1001773D02*
X570119Y1000931D01*
X563481Y996788D01*
X562282Y995988D01*
X554338Y992695D01*
X542832Y990408D01*
X541549Y990281D01*
X536490Y989276D01*
X535612Y988916D01*
X534816Y988383D01*
X533287Y987251D01*
X533286Y987249D01*
X533284Y987248D01*
X531192Y985697D01*
X530179Y984866D01*
G01X567209Y1003883D02*
Y1003678D01*
X565200Y1001669D01*
X560596Y997889D01*
X554137Y995214D01*
X542683Y992937D01*
X539293Y992603D01*
X535994Y991764D01*
X534585Y991246D01*
X528240Y988148D01*
X525943Y986734D01*
X525877Y986684D01*
X524658Y985872D01*
X522779Y984866D01*
G01X552943Y897068D02*
X557328Y892683D01*
Y839325D01*
X556493Y835119D01*
X556455Y835027D01*
Y830474D01*
X556310Y830329D01*
Y830178D01*
G01X552590Y895409D02*
X555928Y892071D01*
Y841397D01*
X555141Y837427D01*
X553139Y832598D01*
Y831584D01*
X553284Y831439D01*
Y831289D01*
G01X553651Y897776D02*
X558328Y893099D01*
Y839226D01*
X557455Y834829D01*
Y830474D01*
X557600Y830329D01*
Y830178D01*
G01X551882Y894702D02*
X554928Y891656D01*
Y841496D01*
X554179Y837719D01*
X552139Y832798D01*
Y831583D01*
X551994Y831438D01*
Y831288D01*
G01X552701Y918538D02*
X553340D01*
X572728Y899150D01*
Y854443D01*
X573271Y853900D01*
Y853899D01*
X574042Y853128D01*
X574041Y852926D01*
X574147Y852820D01*
G01X553736Y916160D02*
X571328Y898568D01*
Y851050D01*
X572818Y849560D01*
X573022D01*
X573128Y849454D01*
G01X553028Y915453D02*
X570328Y898153D01*
Y850635D01*
X572109Y848854D01*
Y848647D01*
X572215Y848541D01*
G01X552701Y919538D02*
X553755D01*
X573728Y899565D01*
Y854858D01*
X574747Y853839D01*
X574953D01*
X575059Y853733D01*
G01X554172Y934009D02*
X559868D01*
X588128Y905749D01*
Y902315D01*
X591239Y899204D01*
Y899000D01*
X591345Y898894D01*
G01X555724Y932609D02*
X559287D01*
X586728Y905168D01*
Y899940D01*
X588447Y895789D01*
X589746Y894490D01*
X589953D01*
X590059Y894384D01*
G01X554172Y935009D02*
X560283D01*
X589128Y906164D01*
Y902731D01*
X591946Y899913D01*
X592152D01*
X592258Y899807D01*
G01X555724Y931609D02*
X558872D01*
X585728Y904753D01*
Y899741D01*
X587597Y895224D01*
X589040Y893781D01*
Y893577D01*
X589146Y893471D01*
G01X558824Y948010D02*
X565889D01*
X580426Y933473D01*
X582229D01*
X582374Y933618D01*
X582524D01*
G01Y936621D02*
X582374D01*
X582229Y936766D01*
X579114D01*
X578529Y937351D01*
X578528D01*
Y937352D01*
X566466Y949414D01*
X558183D01*
X553687Y953910D01*
G01X558824Y947010D02*
X565474D01*
X580011Y932473D01*
X582229D01*
X582374Y932328D01*
X582524D01*
G01X554394Y954618D02*
X558598Y950414D01*
X566881D01*
X579529Y937766D01*
X582229D01*
X582374Y937911D01*
X582524D01*
G01X577286Y1000492D02*
X577142Y1000636D01*
X576440D01*
X576304Y1000772D01*
X573197D01*
X570535Y1000010D01*
X563402Y995532D01*
X562756Y995101D01*
X554630Y991733D01*
X542986Y989418D01*
X541695Y989290D01*
X536777Y988314D01*
X536085Y988029D01*
X535392Y987565D01*
X534074Y986589D01*
X533879Y986201D01*
Y984866D01*
G01X555800Y1030210D02*
X593983Y1068393D01*
X596347Y1080205D01*
X596664Y1081347D01*
X597408Y1082091D01*
X599532D01*
X599677Y1081946D01*
X599827D01*
G01X559224Y1031653D02*
X595342Y1067771D01*
X596800Y1075069D01*
X598355Y1077391D01*
X600565Y1078572D01*
X603331D01*
X603476Y1078717D01*
X603626D01*
G01X555092Y1030918D02*
X593061Y1068887D01*
X595380Y1080474D01*
X595771Y1081869D01*
X596993Y1083091D01*
X599532D01*
X599677Y1083236D01*
X599827D01*
G01X559940Y1030953D02*
X577995Y1049008D01*
X577994D01*
X596264Y1067278D01*
X597742Y1074678D01*
X599047Y1076626D01*
X600816Y1077572D01*
X603331D01*
X603476Y1077427D01*
X603626D01*
G01X553526Y1049749D02*
X579426Y1075649D01*
X585849Y1107756D01*
X587574Y1109481D01*
Y1109480D01*
X587577Y1109483D01*
X587780D01*
X587886Y1109589D01*
G01X554439Y1048536D02*
X580691Y1074788D01*
X586175Y1102208D01*
X587914Y1105460D01*
X588954Y1106861D01*
X589577Y1107484D01*
Y1107689D01*
X589681Y1107793D01*
G01X552818Y1050457D02*
X578504Y1076143D01*
X584927Y1108250D01*
X586867Y1110189D01*
Y1110395D01*
X586973Y1110501D01*
G01X555147Y1047828D02*
X581613Y1074294D01*
X587127Y1101867D01*
X588761Y1104923D01*
X589714Y1106205D01*
X590285Y1106776D01*
X590489D01*
X590594Y1106881D01*
G01X550578Y1068808D02*
X565166Y1083396D01*
X569225Y1103687D01*
Y1138938D01*
X570069Y1139783D01*
X570275D01*
G01X552013Y1068262D02*
X566494Y1082743D01*
X570640Y1103430D01*
Y1136373D01*
X571396Y1137129D01*
Y1137334D01*
X571502Y1137440D01*
G01X552721Y1067554D02*
X567416Y1082249D01*
X571640Y1103330D01*
Y1135958D01*
X572103Y1136421D01*
X572309D01*
X572415Y1136527D01*
G01X549890Y1069536D02*
X564244Y1083890D01*
X568225Y1103787D01*
Y1139353D01*
X569264Y1140392D01*
Y1140598D01*
X569370Y1140704D01*
G01X549248Y1091164D02*
X550880Y1092796D01*
X553644Y1104791D01*
Y1155762D01*
X555693Y1166053D01*
X556256Y1167106D01*
X557104Y1167954D01*
X557310D01*
X557416Y1168060D01*
G01X550532Y1089489D02*
X552399Y1091356D01*
X555064Y1104672D01*
Y1146709D01*
X555203Y1148020D01*
X557733Y1163030D01*
X558617Y1165465D01*
X559106Y1165954D01*
Y1166160D01*
X559212Y1166266D01*
G01X548540Y1091872D02*
X549969Y1093301D01*
X552644Y1104905D01*
Y1155861D01*
X554741Y1166394D01*
X555445Y1167711D01*
X556397Y1168663D01*
Y1168867D01*
X556503Y1168973D01*
G01X551240Y1088781D02*
X553320Y1090861D01*
X556064Y1104571D01*
Y1146656D01*
X556195Y1147884D01*
X558704Y1162774D01*
X559482Y1164914D01*
X559813Y1165246D01*
X560017D01*
X560124Y1165353D01*
G01X677619Y1408887D02*
X678285Y1407279D01*
Y1403363D01*
G01X707717Y1563733D02*
X710962Y1566978D01*
Y1569443D01*
X712222Y1570703D01*
G01X707687Y1567683D02*
Y1571683D01*
G01X723087Y1576712D02*
Y1576078D01*
X719042Y1572033D01*
X713552D01*
X712222Y1570703D01*
G01X707687Y1575683D02*
X711102D01*
G01X719199Y1581092D02*
X717741D01*
X713882Y1577233D01*
X712652D01*
X711102Y1575683D01*
G01X714162Y1574333D02*
X713192Y1573363D01*
X709367D01*
X707687Y1571683D01*
G01Y1579683D02*
X713052D01*
G01X707687Y1591683D02*
Y1595683D01*
G01X719199Y1589950D02*
X717955D01*
X715449Y1592456D01*
X713086D01*
X711350Y1590720D01*
G01D02*
Y1592020D01*
X707687Y1595683D01*
G01X715762Y1408887D02*
X716428Y1407279D01*
Y1403363D01*
G01X729827Y1569493D02*
Y1566917D01*
X726998Y1564088D01*
X723520D01*
G01D02*
Y1561604D01*
G01X724712Y1569882D02*
X726630Y1574513D01*
Y1576712D01*
G01X728977Y1574453D02*
X728402Y1575028D01*
Y1576712D01*
G01X728977Y1574453D02*
Y1573609D01*
X726677Y1571309D01*
Y1569493D01*
G01X719199Y1579320D02*
X718269D01*
X714162Y1575213D01*
Y1574333D01*
G01X717402Y1574433D02*
X719036D01*
X721315Y1576712D01*
G01X719199Y1582864D02*
X719018Y1582683D01*
X717482D01*
X714482Y1579683D01*
X713052D01*
G01X724858Y1576712D02*
Y1575039D01*
X723942Y1574123D01*
G01X714380Y1589960D02*
X716007Y1588333D01*
X719044D01*
X719199Y1588178D01*
G01X712512Y1596338D02*
X713886D01*
X718502Y1591722D01*
X719199D01*
G01X725552Y1602518D02*
X728402Y1599668D01*
Y1594330D01*
G01X725552Y1602518D02*
X729052D01*
G01X727677Y1609893D02*
X728280Y1609290D01*
Y1605706D01*
X729312Y1604674D01*
Y1602778D01*
X729052Y1602518D01*
G01X749612Y1579023D02*
X749611Y1579617D01*
X746361Y1582864D01*
X744691D01*
G01Y1586407D02*
X749652D01*
G01X749662Y1590733D02*
X747107Y1588178D01*
X744691D01*
G01X749612Y1594683D02*
Y1594093D01*
X745469Y1589950D01*
X744691D01*
G01X749612Y1583023D02*
X748000Y1584635D01*
X744691D01*
G01X757687Y1579183D02*
X760112D01*
G01X754537D02*
X754377Y1579023D01*
X749612D01*
G01X757687Y1583183D02*
X760152D01*
G01X754537D02*
X749772D01*
X749612Y1583023D01*
G01X749652Y1586407D02*
X750428Y1587183D01*
X754537D01*
G01Y1592183D02*
X753707D01*
X751207Y1594683D01*
X749612D01*
G01X774152Y1576893D02*
X777861Y1580602D01*
X779270D01*
G01X768727Y1577893D02*
X773152D01*
X774152Y1576893D01*
G01X773952Y1580493D02*
X776029Y1582570D01*
X779270D01*
G01X768727Y1581893D02*
X769852D01*
X771252Y1580493D01*
X773952D01*
G01X768714Y1573793D02*
Y1571203D01*
G01D02*
X773462D01*
X777152Y1574893D01*
Y1577393D01*
X778392Y1578633D01*
X779220D01*
G01X765577Y1594893D02*
X763152D01*
G01X768727D02*
X774152D01*
G01D02*
X776632Y1592413D01*
X779220D01*
G01X774052Y1590293D02*
X775869Y1588476D01*
X779270D01*
G01X768727Y1590893D02*
X771735D01*
X772335Y1590293D01*
X774052D01*
G01X779270Y1590444D02*
X776922D01*
G01X807077Y1577793D02*
X802252D01*
X801652Y1578393D01*
G01D02*
Y1579393D01*
X798475Y1582570D01*
X796888D01*
G01Y1586507D02*
X799152D01*
G01X801653Y1598793D02*
Y1592577D01*
X797552Y1588476D01*
X796888D01*
G01X807077Y1601793D02*
X804653D01*
X801653Y1598793D01*
G01X801652Y1604293D02*
X798787Y1601428D01*
Y1593374D01*
X797826Y1592413D01*
X796938D01*
G01X801652Y1584539D02*
Y1590506D01*
X804939Y1593793D01*
X807077D01*
G01X796888Y1584539D02*
X801652D01*
G01X807077Y1605793D02*
X803152D01*
X801652Y1604293D01*
G01X807077Y1609793D02*
X804652D01*
G01X821270Y1580602D02*
X819364D01*
X817405Y1578643D01*
X815902D01*
G01D02*
X814502D01*
X811352Y1581793D01*
X810227D01*
G01Y1577793D02*
X812652D01*
G01X821270Y1582570D02*
X815652D01*
G01D02*
X813974D01*
X810751Y1585793D01*
X810227D01*
G01X815652Y1573793D02*
X820492Y1578633D01*
X821220D01*
G01X810227Y1573793D02*
X815652D01*
G01X815509Y1600536D02*
X819152Y1596893D01*
Y1593793D01*
X820532Y1592413D01*
X821220D01*
G01X810227Y1597793D02*
X811941D01*
X815551Y1594183D01*
Y1593793D01*
G01D02*
Y1590693D01*
X817768Y1588476D01*
X821270D01*
G01Y1590444D02*
X818652D01*
G01X810227Y1601793D02*
X812652D01*
G01X810227Y1609793D02*
X813000D01*
X815509Y1607284D01*
Y1600536D01*
G01X843652Y1578393D02*
Y1579393D01*
X840475Y1582570D01*
X838888D01*
G01Y1586507D02*
X841152D01*
G01X843653Y1598793D02*
Y1592577D01*
X839552Y1588476D01*
X838888D01*
G01X843652Y1604293D02*
X840787Y1601428D01*
Y1593374D01*
X839826Y1592413D01*
X838938D01*
G01X843652Y1584539D02*
X838888D01*
G01X849077Y1577793D02*
X844252D01*
X843652Y1578393D01*
G01X852227Y1577793D02*
X854652D01*
G01X857652Y1582570D02*
X856276D01*
X853053Y1585793D01*
X852227D01*
G01X863270Y1582570D02*
X857652D01*
G01X852227Y1573793D02*
X857652D01*
G01D02*
X857760D01*
X862600Y1578633D01*
X863220D01*
G01X857902Y1578643D02*
X854752Y1581793D01*
X852227D01*
G01X863270Y1580602D02*
X861364D01*
X859405Y1578643D01*
X857902D01*
G01X849077Y1601793D02*
X846653D01*
X843653Y1598793D01*
G01X849077Y1593793D02*
X846939D01*
X843652Y1590506D01*
Y1584539D01*
G01X852227Y1597793D02*
X853941D01*
X857551Y1594183D01*
Y1593793D01*
G01D02*
X857552Y1593792D01*
Y1590692D01*
X859768Y1588476D01*
X863270D01*
G01X857509Y1600536D02*
X861152Y1596893D01*
Y1593793D01*
X862532Y1592413D01*
X863220D01*
G01X852227Y1601793D02*
X854652D01*
G01X849077Y1605793D02*
X845152D01*
X843652Y1604293D01*
G01X849077Y1609793D02*
X846652D01*
G01X852227D02*
X855000D01*
X857509Y1607284D01*
Y1600536D01*
G01X863270Y1590444D02*
X860652D01*
G01X891077Y1577793D02*
X886252D01*
X885652Y1578393D01*
G01D02*
Y1579393D01*
X882475Y1582570D01*
X880888D01*
G01Y1586507D02*
X883152D01*
G01X885652Y1584539D02*
Y1590506D01*
X888939Y1593793D01*
X891077D01*
G01X880888Y1584539D02*
X885652D01*
G01X885653Y1598793D02*
Y1592577D01*
X881552Y1588476D01*
X880888D01*
G01X891077Y1601793D02*
X888653D01*
X885653Y1598793D01*
G01X885652Y1604293D02*
X882787Y1601428D01*
Y1593374D01*
X881826Y1592413D01*
X880938D01*
G01X891077Y1609793D02*
X888652D01*
G01X891077Y1605793D02*
X887152D01*
X885652Y1604293D01*
G01X894227Y1577793D02*
X896652D01*
G01X899652Y1582570D02*
X898276D01*
X895053Y1585793D01*
X894227D01*
G01X905270Y1582570D02*
X899652D01*
G01X894227Y1573793D02*
X899652D01*
G01D02*
X899760D01*
X904600Y1578633D01*
X905220D01*
G01X899902Y1578643D02*
X896752Y1581793D01*
X894227D01*
G01X905270Y1580602D02*
X903364D01*
X901405Y1578643D01*
X899902D01*
G01X894227Y1597793D02*
X895941D01*
X899551Y1594183D01*
Y1593793D01*
G01D02*
X899552Y1593792D01*
Y1590692D01*
X901768Y1588476D01*
X905270D01*
G01Y1590444D02*
X902652D01*
G01X899509Y1600536D02*
X903152Y1596893D01*
Y1593793D01*
X904532Y1592413D01*
X905220D01*
G01X894227Y1601793D02*
X896652D01*
G01X894227Y1609793D02*
X897000D01*
X899509Y1607284D01*
Y1600536D01*
G01X928152Y1579393D02*
X924975Y1582570D01*
X922888D01*
G01Y1586507D02*
X925152D01*
G01X922888Y1584539D02*
X928152D01*
G01Y1589893D02*
X926735Y1588476D01*
X922888D01*
G01X928152Y1594893D02*
X925672Y1592413D01*
X922938D01*
G01X936227Y1581393D02*
X938652D01*
G01X933077D02*
X930152D01*
X928152Y1579393D01*
G01X936227Y1589393D02*
X938652D01*
G01X928152Y1584539D02*
X929006Y1585393D01*
X933077D01*
G01Y1589393D02*
X928652D01*
X928152Y1589893D01*
G01X933077Y1593393D02*
X929652D01*
X928152Y1594893D01*
G01X1084457Y1663950D02*
X1090507Y1657900D01*
X1092116D01*
X1092617Y1658401D01*
Y1661265D01*
G01X1079532Y1663950D02*
X1084457D01*
G01X1092617Y1661265D02*
Y1665613D01*
X1088215Y1670015D01*
Y1670963D01*
G01X1108320Y1680200D02*
X1104850Y1683670D01*
X1092760D01*
X1088215Y1679125D01*
Y1670963D01*
G01X1108320Y1680200D02*
X1113140Y1675380D01*
Y1673066D01*
G01X1137311Y1445191D02*
X1137977Y1443582D01*
Y1439667D01*
G01X1175454Y1445191D02*
X1176120Y1443583D01*
Y1439667D01*
G01X1305018Y865299D02*
X1302518Y862799D01*
Y848510D01*
X1305726Y845302D01*
Y842907D01*
X1305906Y842727D01*
Y842652D01*
G01X1304310Y866007D02*
X1301518Y863215D01*
Y848095D01*
X1304726Y844887D01*
Y842762D01*
X1304616Y842652D01*
G01X1306583Y908158D02*
X1304894D01*
X1290458Y893722D01*
Y885299D01*
X1284138Y878979D01*
Y855051D01*
X1283134Y852624D01*
X1282022Y851512D01*
Y851306D01*
X1281916Y851200D01*
G01X1306583Y909158D02*
X1304479D01*
X1289458Y894137D01*
Y885714D01*
X1283138Y879394D01*
Y855250D01*
X1282285Y853191D01*
X1281311Y852217D01*
X1281109Y852218D01*
X1281003Y852112D01*
G01X1304766Y927012D02*
X1301730D01*
X1279923Y905205D01*
X1278315Y904539D01*
X1276962D01*
X1276561Y904544D01*
X1276415Y904400D01*
X1276265D01*
G01X1304766Y928012D02*
X1301315D01*
X1279356Y906054D01*
X1278116Y905539D01*
X1276969D01*
X1276571Y905544D01*
X1276429Y905690D01*
X1276279D01*
G01X1302666Y945470D02*
X1295261D01*
X1295116Y945325D01*
X1294966D01*
G01Y946615D02*
X1295116D01*
X1295261Y946470D01*
X1302666D01*
G01X1301868Y1034088D02*
X1300317D01*
X1278562Y1055843D01*
X1276274D01*
X1273724Y1058393D01*
X1273520D01*
X1273414Y1058499D01*
G01X1301868Y1035088D02*
X1300732D01*
X1278977Y1056843D01*
X1276690D01*
X1274433Y1059100D01*
Y1059306D01*
X1274327Y1059412D01*
G01X1302623Y1059708D02*
X1281739Y1080592D01*
X1276672Y1090071D01*
X1274115Y1102925D01*
Y1102927D01*
X1271917Y1108711D01*
X1270780Y1109848D01*
X1270576D01*
X1270470Y1109954D01*
G01X1303331Y1060416D02*
X1282550Y1081197D01*
X1277624Y1090412D01*
X1275080Y1103203D01*
X1272776Y1109267D01*
X1271489Y1110554D01*
Y1110761D01*
X1271383Y1110867D01*
G01X1304665Y1079849D02*
X1294180Y1090334D01*
X1291590Y1095184D01*
X1288870Y1108785D01*
Y1145029D01*
X1288216Y1145683D01*
X1288012D01*
X1287906Y1145789D01*
G01X1305373Y1080557D02*
X1294993Y1090937D01*
X1292542Y1095525D01*
X1289870Y1108885D01*
Y1145444D01*
X1288925Y1146389D01*
Y1146596D01*
X1288819Y1146702D01*
G01X1307649Y1099832D02*
X1306414Y1101067D01*
X1304270Y1111787D01*
Y1165984D01*
X1303427Y1170221D01*
X1303425Y1170227D01*
X1302583Y1172292D01*
X1301305Y1173570D01*
X1301100D01*
X1300994Y1173676D01*
G01X1301907Y1174589D02*
X1302013Y1174483D01*
Y1174277D01*
X1303433Y1172857D01*
X1304388Y1170521D01*
X1305270Y1166083D01*
Y1111887D01*
X1307336Y1101561D01*
X1308357Y1100540D01*
G01X1306713Y865003D02*
X1303918Y862208D01*
Y849096D01*
X1308572Y844442D01*
Y842947D01*
X1308427Y842802D01*
Y842652D01*
G01X1309717D02*
Y842802D01*
X1309572Y842947D01*
Y844857D01*
X1304918Y849511D01*
Y861792D01*
X1307421Y864295D01*
G01X1306583Y906741D02*
X1305457D01*
X1291858Y893142D01*
Y884719D01*
X1285538Y878399D01*
Y854197D01*
X1285091Y853118D01*
Y849912D01*
X1284940Y849761D01*
X1284356Y849178D01*
X1284150D01*
X1284044Y849072D01*
G01X1284957Y848160D02*
X1285063Y848266D01*
X1285062Y848468D01*
X1286091Y849497D01*
Y852919D01*
X1286538Y853998D01*
Y877984D01*
X1292858Y884304D01*
Y892727D01*
X1305872Y905741D01*
X1306583D01*
G01X1304766Y925488D02*
X1302186D01*
X1277940Y901242D01*
X1276560D01*
X1276415Y901387D01*
X1276265D01*
G01Y900097D02*
X1276415D01*
X1276560Y900242D01*
X1278355D01*
X1302601Y924488D01*
X1304766D01*
G01X1294966Y941000D02*
X1295116D01*
X1295261Y941145D01*
X1302837D01*
X1304182Y942490D01*
G01X1303475Y943198D02*
X1302422Y942145D01*
X1295261D01*
X1295116Y942290D01*
X1294966D01*
G01X1270366Y1055452D02*
X1270472Y1055346D01*
X1270674D01*
X1271847Y1054174D01*
X1272670Y1053351D01*
X1277658D01*
X1299488Y1031521D01*
X1303168D01*
G01Y1032521D02*
X1299903D01*
X1278073Y1054351D01*
X1273086D01*
X1271385Y1056052D01*
Y1056258D01*
X1271279Y1056364D01*
G01X1304448Y1055903D02*
X1280602Y1079749D01*
X1275362Y1089423D01*
X1272670Y1102237D01*
X1271477Y1104446D01*
X1269529Y1106393D01*
Y1106600D01*
X1269423Y1106706D01*
G01X1303740Y1055195D02*
X1279791Y1079144D01*
X1274413Y1089075D01*
X1271721Y1101889D01*
X1270667Y1103840D01*
X1268818Y1105688D01*
X1268616D01*
X1268510Y1105794D01*
G01X1305058Y1077475D02*
X1293043Y1089490D01*
X1290258Y1094692D01*
X1287470Y1108633D01*
Y1140947D01*
X1286893Y1142338D01*
X1285884Y1143347D01*
Y1143555D01*
X1285778Y1143661D01*
G01X1284865Y1142749D02*
X1284971Y1142643D01*
X1285173D01*
X1286045Y1141771D01*
X1286470Y1140747D01*
Y1108533D01*
X1289306Y1094351D01*
X1292230Y1088887D01*
X1304350Y1076767D01*
G01X1307232Y1096816D02*
X1304191Y1099857D01*
Y1099858D01*
X1301870Y1111529D01*
Y1164911D01*
X1300226Y1168892D01*
X1299502Y1169975D01*
X1298605Y1170872D01*
X1298401D01*
X1298295Y1170978D01*
G01X1299208Y1171891D02*
X1299314Y1171785D01*
Y1171579D01*
X1300280Y1170613D01*
X1301113Y1169365D01*
X1302870Y1165110D01*
Y1111628D01*
X1305113Y1100351D01*
X1307940Y1097524D01*
G01X1370405Y186938D02*
X1370193Y187150D01*
X1368493D01*
X1368153Y186810D01*
X1365353D01*
G01X1502621Y984866D02*
Y985885D01*
X1502636Y985896D01*
X1502651Y985908D01*
X1504865Y987270D01*
X1511120Y990325D01*
X1512433Y990807D01*
X1515608Y991615D01*
X1518972Y991946D01*
X1530571Y994252D01*
X1537258Y997021D01*
X1542015Y1000926D01*
X1544060Y1002971D01*
X1544264D01*
G01X1506321Y984866D02*
X1507334Y985697D01*
X1509426Y987248D01*
X1509428Y987249D01*
X1509429Y987251D01*
X1510958Y988383D01*
X1511754Y988916D01*
X1512632Y989276D01*
X1517691Y990281D01*
X1518974Y990408D01*
X1530480Y992695D01*
X1538424Y995988D01*
X1539623Y996788D01*
X1546261Y1000931D01*
X1549200Y1001773D01*
G01X1498921Y984866D02*
X1500800Y985872D01*
X1502019Y986684D01*
X1502085Y986734D01*
X1504382Y988148D01*
X1510727Y991246D01*
X1512136Y991764D01*
X1515435Y992603D01*
X1518825Y992937D01*
X1530279Y995214D01*
X1536738Y997889D01*
X1541342Y1001669D01*
X1543351Y1003678D01*
Y1003883D01*
G01X1529085Y897068D02*
X1533470Y892683D01*
Y839325D01*
X1532635Y835119D01*
X1532597Y835027D01*
Y830474D01*
X1532452Y830329D01*
Y830178D01*
G01X1528732Y895409D02*
X1532070Y892071D01*
Y841397D01*
X1531283Y837427D01*
X1529281Y832598D01*
Y831584D01*
X1529426Y831439D01*
Y831289D01*
G01X1529793Y897776D02*
X1534470Y893099D01*
Y839226D01*
X1533597Y834829D01*
Y830474D01*
X1533742Y830329D01*
Y830178D01*
G01X1528024Y894702D02*
X1531070Y891656D01*
Y841496D01*
X1530321Y837719D01*
X1528281Y832798D01*
Y831583D01*
X1528136Y831438D01*
Y831288D01*
G01X1528843Y918538D02*
X1529482D01*
X1548870Y899150D01*
Y854443D01*
X1549413Y853900D01*
Y853899D01*
X1550184Y853128D01*
X1550183Y852926D01*
X1550289Y852820D01*
G01X1529878Y916160D02*
X1547470Y898568D01*
Y851050D01*
X1548960Y849560D01*
X1549164D01*
X1549270Y849454D01*
G01X1529170Y915453D02*
X1546470Y898153D01*
Y850635D01*
X1548251Y848854D01*
Y848647D01*
X1548357Y848541D01*
G01X1528843Y919538D02*
X1529897D01*
X1549870Y899565D01*
Y854858D01*
X1550889Y853839D01*
X1551095D01*
X1551201Y853733D01*
G01X1530314Y934009D02*
X1536010D01*
X1564270Y905749D01*
Y902315D01*
X1567381Y899204D01*
Y899000D01*
X1567487Y898894D01*
G01X1531866Y932609D02*
X1535429D01*
X1562870Y905168D01*
Y899940D01*
X1564589Y895789D01*
X1565888Y894490D01*
X1566095D01*
X1566201Y894384D01*
G01X1530314Y935009D02*
X1536425D01*
X1565270Y906164D01*
Y902731D01*
X1568088Y899913D01*
X1568294D01*
X1568400Y899807D01*
G01X1531866Y931609D02*
X1535014D01*
X1561870Y904753D01*
Y899741D01*
X1563739Y895224D01*
X1565182Y893781D01*
Y893577D01*
X1565288Y893471D01*
G01X1534966Y948010D02*
X1542031D01*
X1556568Y933473D01*
X1558371D01*
X1558516Y933618D01*
X1558666D01*
G01X1529829Y953910D02*
X1534325Y949414D01*
X1542608D01*
X1554670Y937352D01*
Y937351D01*
X1554671D01*
X1555256Y936766D01*
X1558371D01*
X1558516Y936621D01*
X1558666D01*
G01X1534966Y947010D02*
X1541616D01*
X1556153Y932473D01*
X1558371D01*
X1558516Y932328D01*
X1558666D01*
G01X1530536Y954618D02*
X1534740Y950414D01*
X1543023D01*
X1555671Y937766D01*
X1558371D01*
X1558516Y937911D01*
X1558666D01*
G01X1510021Y984866D02*
Y986201D01*
X1510216Y986589D01*
X1511534Y987565D01*
X1512227Y988029D01*
X1512919Y988314D01*
X1517837Y989290D01*
X1519128Y989418D01*
X1530772Y991733D01*
X1538898Y995101D01*
X1539544Y995532D01*
X1546677Y1000010D01*
X1549339Y1000772D01*
X1552446D01*
X1552582Y1000636D01*
X1553284D01*
X1553428Y1000492D01*
G01X1531942Y1030210D02*
X1570125Y1068393D01*
X1572489Y1080205D01*
X1572806Y1081347D01*
X1573550Y1082091D01*
X1575674D01*
X1575819Y1081946D01*
X1575969D01*
G01X1535366Y1031653D02*
X1571484Y1067771D01*
X1572942Y1075069D01*
X1574497Y1077391D01*
X1576707Y1078572D01*
X1579473D01*
X1579618Y1078717D01*
X1579768D01*
G01X1531234Y1030918D02*
X1569203Y1068887D01*
X1571522Y1080474D01*
X1571913Y1081869D01*
X1573135Y1083091D01*
X1575674D01*
X1575819Y1083236D01*
X1575969D01*
G01X1536082Y1030953D02*
X1554137Y1049008D01*
X1554136D01*
X1572406Y1067278D01*
X1573884Y1074678D01*
X1575189Y1076626D01*
X1576958Y1077572D01*
X1579473D01*
X1579618Y1077427D01*
X1579768D01*
G01X1529668Y1049749D02*
X1555568Y1075649D01*
X1561991Y1107756D01*
X1563716Y1109481D01*
Y1109480D01*
X1563719Y1109483D01*
X1563922D01*
X1564028Y1109589D01*
G01X1530581Y1048536D02*
X1556833Y1074788D01*
X1562317Y1102208D01*
X1564056Y1105460D01*
X1565096Y1106861D01*
X1565719Y1107484D01*
Y1107689D01*
X1565823Y1107793D01*
G01X1528960Y1050457D02*
X1554646Y1076143D01*
X1561069Y1108250D01*
X1563009Y1110189D01*
Y1110395D01*
X1563115Y1110501D01*
G01X1531289Y1047828D02*
X1557755Y1074294D01*
X1563269Y1101867D01*
X1564903Y1104923D01*
X1565856Y1106205D01*
X1566427Y1106776D01*
X1566631D01*
X1566736Y1106881D01*
G01X1526720Y1068808D02*
X1541308Y1083396D01*
X1545367Y1103687D01*
Y1138938D01*
X1546151Y1139722D01*
X1546356D01*
G01X1528155Y1068262D02*
X1542636Y1082743D01*
X1546782Y1103430D01*
Y1136373D01*
X1547538Y1137129D01*
Y1137334D01*
X1547644Y1137440D01*
G01X1528863Y1067554D02*
X1543558Y1082249D01*
X1547782Y1103330D01*
Y1135958D01*
X1548245Y1136421D01*
X1548451D01*
X1548557Y1136527D01*
G01X1526032Y1069536D02*
X1540386Y1083890D01*
X1544367Y1103787D01*
Y1139353D01*
X1545406Y1140392D01*
Y1140598D01*
X1545512Y1140704D01*
G01X1525390Y1091164D02*
X1527022Y1092796D01*
X1529786Y1104791D01*
Y1155762D01*
X1531835Y1166053D01*
X1532398Y1167106D01*
X1533246Y1167954D01*
X1533452D01*
X1533558Y1168060D01*
G01X1526674Y1089489D02*
X1528541Y1091356D01*
X1531206Y1104672D01*
Y1146709D01*
X1531345Y1148020D01*
X1533875Y1163030D01*
X1534759Y1165465D01*
X1535248Y1165954D01*
Y1166160D01*
X1535354Y1166266D01*
G01X1524682Y1091872D02*
X1526111Y1093301D01*
X1528786Y1104905D01*
Y1155861D01*
X1530883Y1166394D01*
X1531587Y1167711D01*
X1532539Y1168663D01*
Y1168867D01*
X1532645Y1168973D01*
G01X1527382Y1088781D02*
X1529462Y1090861D01*
X1532206Y1104571D01*
Y1146656D01*
X1532337Y1147884D01*
X1534846Y1162774D01*
X1535624Y1164914D01*
X1535955Y1165246D01*
X1536159D01*
X1536266Y1165353D01*
G01X1638785Y1442483D02*
X1639451Y1440875D01*
Y1436959D01*
G01X1675664Y513802D02*
X1670980Y518486D01*
Y524061D01*
X1668917Y526124D01*
Y527616D01*
G01X1664197Y602191D02*
X1663206Y601200D01*
X1660491Y600075D01*
X1657107D01*
G01X1683702Y514687D02*
Y519100D01*
X1679941Y522861D01*
Y527616D01*
G01X1676600Y523902D02*
Y524272D01*
X1678366Y526038D01*
Y527616D01*
G01X1676928Y1442483D02*
X1677594Y1440875D01*
Y1436959D01*
G01X1702127Y468719D02*
X1706697Y473289D01*
Y474758D01*
G01X1756127Y296368D02*
Y297214D01*
X1755645Y297696D01*
Y301136D01*
X1756204Y301695D01*
G01D02*
X1754963Y302936D01*
Y304842D01*
G54D134*
X269181Y224782D03*
X1653051Y414202D03*
G54D251*
X999456Y189090D03*
G54D206*
X717110Y-11500D03*
X834070Y18500D03*
X1026502Y-21511D03*
Y-1511D03*
Y18489D03*
X1335821Y-21511D03*
Y-1511D03*
Y18489D03*
G54D242*
X929196Y1546760D03*
G54D143*
G01X152684Y1403451D02*
X154193Y1401942D01*
Y1400878D01*
G01X162257Y1406594D02*
X162894Y1405037D01*
Y1403338D01*
G01X190827Y1403451D02*
X192336Y1401942D01*
Y1400878D01*
G01X193950Y1403338D02*
Y1403763D01*
X190949Y1406764D01*
Y1408384D01*
G01X210391Y567981D02*
X207966D01*
G01X204610Y571097D02*
X206119Y572606D01*
X207183D01*
G01X201622Y581009D02*
X201920Y581307D01*
X204723D01*
G01X210391Y601981D02*
X207966D01*
G01X207183Y606606D02*
X206119D01*
X204610Y605097D01*
G01X204723Y615307D02*
X201920D01*
X201622Y615009D01*
G01X210391Y635981D02*
X207966D01*
G01X207183Y640606D02*
X206119D01*
X204610Y639097D01*
G01X204723Y649307D02*
X201920D01*
X201622Y649009D01*
G01X193941Y1407029D02*
X195722Y1405248D01*
Y1403338D01*
G01X200492Y1406686D02*
X201037Y1405495D01*
Y1403338D01*
G01X215316Y567981D02*
Y568341D01*
X212498Y571159D01*
Y572606D01*
G01Y606606D02*
Y605133D01*
X215316Y602315D01*
Y601981D01*
G01X212498Y640606D02*
Y639159D01*
X215316Y636341D01*
Y635981D01*
G01X296478Y151703D02*
X296331Y151850D01*
X291765D01*
G01Y153819D02*
X294553D01*
G01X296478Y156203D02*
X293482D01*
X293066Y155787D01*
X291765D01*
G01X308176Y1353709D02*
X306877D01*
X304059Y1350891D01*
X303551D01*
G01X308176Y1355480D02*
X306883D01*
X304085Y1358278D01*
X303573D01*
G01X316877Y1361484D02*
Y1364287D01*
X316579Y1364585D01*
G01X335679Y1335972D02*
X335673Y1335978D01*
G01X348707Y1341787D02*
X349005Y1341489D01*
Y1338686D01*
G01X380835Y1328361D02*
X381133Y1328063D01*
Y1325260D01*
G01X412963Y1328361D02*
X413261Y1328063D01*
Y1325260D01*
G01X445091Y1328361D02*
X445389Y1328063D01*
Y1325260D01*
G01X477219Y1328361D02*
X477517Y1328063D01*
Y1325260D01*
G01X509347Y1341787D02*
X509645Y1341489D01*
Y1338686D01*
G01X541475Y1364585D02*
X541773Y1364287D01*
Y1361484D01*
G01X606668Y204994D02*
X609456D01*
G01X606668Y206962D02*
X610965D01*
X611381Y207378D01*
G01X606668Y203025D02*
X611234D01*
X611381Y202878D01*
G01X663187Y1397720D02*
Y1400120D01*
G01X675876Y1406619D02*
X676513Y1405103D01*
Y1403363D01*
G01X666303Y1403476D02*
X667812Y1401967D01*
Y1400903D01*
G01X707620Y1406694D02*
X709341Y1404973D01*
Y1403363D01*
G01X704446Y1403476D02*
X705955Y1401967D01*
Y1400903D01*
G01X704568Y1408409D02*
Y1406789D01*
X707569Y1403788D01*
Y1403363D01*
G01X714019Y1406619D02*
X714656Y1405057D01*
Y1403363D01*
G01X824498Y142410D02*
Y145198D01*
G01X826467Y142410D02*
Y146976D01*
X826614Y147123D01*
G01X1122879Y1434024D02*
Y1436424D01*
G01X1125995Y1439780D02*
X1127504Y1438271D01*
Y1437207D01*
G01X1135568Y1442923D02*
X1136205Y1442286D01*
Y1439667D01*
G01X1164138Y1439780D02*
X1165647Y1438271D01*
Y1437207D01*
G01X1167312Y1442998D02*
X1169033Y1441277D01*
Y1439667D01*
G01X1164260Y1444713D02*
Y1443093D01*
X1167261Y1440092D01*
Y1439667D01*
G01X1173711Y1442923D02*
X1174348Y1442286D01*
Y1439667D01*
G01X1180193Y1626204D02*
X1182408D01*
G01X1279812Y1351127D02*
X1280176D01*
X1282994Y1353945D01*
X1284437D01*
G01X1279334Y1356089D02*
Y1358014D01*
X1279834Y1358514D01*
G01X1284437Y1355716D02*
X1282508D01*
X1279834Y1358390D01*
Y1358514D01*
G01X1292840Y1364821D02*
X1293138Y1364523D01*
Y1361720D01*
G01X1324848Y1341787D02*
X1325146Y1341489D01*
Y1338686D01*
G01X1347397Y1325320D02*
X1348573Y1324144D01*
Y1322800D01*
G01X1356976Y1328361D02*
X1357274Y1328063D01*
Y1325260D01*
G01X1366170Y1329843D02*
X1364582Y1328255D01*
X1364027D01*
X1362589Y1326817D01*
Y1325260D01*
G01X1379192Y1325373D02*
X1380701Y1323864D01*
Y1322800D01*
G01X1389104Y1328361D02*
X1389402Y1328063D01*
Y1325260D01*
G01X1411320Y1325373D02*
X1412829Y1323864D01*
Y1322800D01*
G01X1421232Y1328361D02*
X1421530Y1328063D01*
Y1325260D01*
G01X1443448Y1325373D02*
X1444957Y1323864D01*
Y1322800D01*
G01X1453360Y1328361D02*
X1453658Y1328063D01*
Y1325260D01*
G01X1475576Y1338799D02*
X1477085Y1337290D01*
Y1336226D01*
G01X1485488Y1341787D02*
X1485786Y1341489D01*
Y1338686D01*
G01X1507704Y1361597D02*
X1509213Y1360088D01*
Y1359024D01*
G01X1517616Y1364585D02*
X1517914Y1364287D01*
Y1361484D01*
G01X1638657Y652601D02*
Y652241D01*
X1641475Y649423D01*
Y647976D01*
G01X1638657Y686601D02*
Y686241D01*
X1641475Y683423D01*
Y681976D01*
G01X1638657Y720601D02*
Y720241D01*
X1641475Y717423D01*
Y715976D01*
G01X1624353Y1431316D02*
Y1433716D01*
G01X1637042Y1440215D02*
X1637679Y1438599D01*
Y1436959D01*
G01X1627469Y1437072D02*
X1628978Y1435563D01*
Y1434499D01*
G01X1652351Y639573D02*
X1652053Y639275D01*
X1649250D01*
G01X1643582Y652601D02*
X1646007D01*
G01X1649363Y649485D02*
X1647854Y647976D01*
X1646790D01*
G01X1652351Y673573D02*
X1652053Y673275D01*
X1649250D01*
G01X1643582Y686601D02*
X1646007D01*
G01X1649363Y683485D02*
X1647854Y681976D01*
X1646790D01*
G01X1652351Y707573D02*
X1652053Y707275D01*
X1649250D01*
G01X1643582Y720601D02*
X1646007D01*
G01X1649363Y717485D02*
X1647854Y715976D01*
X1646790D01*
G01X1668786Y1440290D02*
X1670507Y1438569D01*
Y1436959D01*
G01X1665612Y1437072D02*
X1667121Y1435563D01*
Y1434499D01*
G01X1665734Y1442005D02*
Y1440385D01*
X1668735Y1437384D01*
Y1436959D01*
G01X1675185Y1440215D02*
X1675822Y1438622D01*
Y1436959D01*
X318333Y78520D03*
X316364D03*
X314395D03*
X312427D03*
X310459D03*
X308490D03*
X306521D03*
X318333Y80489D03*
X316364D03*
X314395D03*
X312427D03*
X310459D03*
X308490D03*
X306521D03*
X318333Y82457D03*
X316364D03*
X314395D03*
X312427D03*
X310459D03*
X308490D03*
X306521D03*
X318333Y84426D03*
X316364D03*
X314395D03*
X312427D03*
X310459D03*
X308490D03*
X306521D03*
X325002Y212333D03*
Y214302D03*
Y216271D03*
X326971Y212333D03*
Y214302D03*
Y216271D03*
X328939Y212333D03*
Y214302D03*
Y216271D03*
X330908Y212333D03*
Y214302D03*
Y216271D03*
X325002Y218239D03*
Y220207D03*
Y222176D03*
Y224145D03*
X326971Y218239D03*
Y220207D03*
Y222176D03*
Y224145D03*
X328939Y218239D03*
Y220207D03*
Y222176D03*
Y224145D03*
X330908Y218239D03*
Y220207D03*
Y222176D03*
Y224145D03*
X745035Y98005D03*
X743066D03*
X741097D03*
X745035Y99974D03*
X743066D03*
X741097D03*
X745035Y101942D03*
X743066D03*
X741097D03*
X745035Y103911D03*
X743066D03*
X741097D03*
X752909Y98005D03*
X750940D03*
X748971D03*
X747003D03*
X752909Y99974D03*
X750940D03*
X748971D03*
X747003D03*
X752909Y101942D03*
X750940D03*
X748971D03*
X747003D03*
X752909Y103911D03*
X750940D03*
X748971D03*
X747003D03*
X873313Y276064D03*
X871345D03*
X869376D03*
X867407D03*
X873313Y278033D03*
X871345D03*
X869376D03*
X867407D03*
X873313Y280001D03*
X871345D03*
X869376D03*
X867407D03*
X873313Y281970D03*
X871345D03*
X869376D03*
X867407D03*
X879219Y276064D03*
X877250D03*
X875281D03*
X879219Y278033D03*
X877250D03*
X875281D03*
X879219Y280001D03*
X877250D03*
X875281D03*
X879219Y281970D03*
X877250D03*
X875281D03*
X914362Y494165D03*
X916331D03*
X914362Y492196D03*
X916331D03*
X914362Y490228D03*
X916331D03*
X918299D03*
X920268D03*
X922236D03*
X914362Y488259D03*
X916331D03*
X918299D03*
X920268D03*
X922236D03*
X914362Y509913D03*
X916331D03*
X918299D03*
X920268D03*
X922236D03*
X914362Y507944D03*
X916331D03*
X918299D03*
X920268D03*
X922236D03*
X914362Y505976D03*
X916331D03*
X914362Y504007D03*
X916331D03*
X914362Y502039D03*
X916331D03*
X914362Y500070D03*
X916331D03*
X914362Y498102D03*
X916331D03*
X914362Y496133D03*
X916331D03*
X934047Y494165D03*
X936016D03*
X934047Y492196D03*
X936016D03*
X924205Y490228D03*
X926173D03*
X928142D03*
X930110D03*
X932079D03*
X934047D03*
X936016D03*
X924205Y488259D03*
X926173D03*
X928142D03*
X930110D03*
X932079D03*
X934047D03*
X936016D03*
X924205Y509913D03*
X926173D03*
X928142D03*
X930110D03*
X932079D03*
X934047D03*
X936016D03*
X924205Y507944D03*
X926173D03*
X928142D03*
X930110D03*
X932079D03*
X934047D03*
X936016D03*
X934047Y505976D03*
X936016D03*
X934047Y504007D03*
X936016D03*
X934047Y502039D03*
X936016D03*
X934047Y500070D03*
X936016D03*
X934047Y498102D03*
X936016D03*
X934047Y496133D03*
X936016D03*
X992452Y155667D03*
Y157636D03*
Y159605D03*
Y161573D03*
Y163541D03*
Y165510D03*
Y167479D03*
X994421Y155667D03*
Y157636D03*
Y159605D03*
Y161573D03*
Y163541D03*
Y165510D03*
Y167479D03*
X996389Y155667D03*
Y157636D03*
Y159605D03*
Y161573D03*
Y163541D03*
Y165510D03*
Y167479D03*
X998358Y155667D03*
Y157636D03*
Y159605D03*
Y161573D03*
Y163541D03*
Y165510D03*
Y167479D03*
X1697161Y408769D03*
Y410738D03*
Y412707D03*
X1699130Y408769D03*
Y410738D03*
Y412707D03*
X1701098Y408769D03*
Y410738D03*
Y412707D03*
X1703067Y408769D03*
Y410738D03*
Y412707D03*
X1697161Y414675D03*
Y416643D03*
Y418612D03*
Y420581D03*
X1699130Y414675D03*
Y416643D03*
Y418612D03*
Y420581D03*
X1701098Y414675D03*
Y416643D03*
Y418612D03*
Y420581D03*
X1703067Y414675D03*
Y416643D03*
Y418612D03*
Y420581D03*
X1783454Y79644D03*
X1781485D03*
X1779516D03*
X1777548D03*
X1775580D03*
X1773611D03*
X1771642D03*
X1783454Y81613D03*
X1781485D03*
X1779516D03*
X1777548D03*
X1775580D03*
X1773611D03*
X1771642D03*
X1783454Y83581D03*
X1781485D03*
X1779516D03*
X1777548D03*
X1775580D03*
X1773611D03*
X1771642D03*
X1783454Y85550D03*
X1781485D03*
X1779516D03*
X1777548D03*
X1775580D03*
X1773611D03*
X1771642D03*
G54D233*
X841240Y1420330D03*
X1016240D03*
G54D41*
X65933Y32756D03*
X68295D03*
X70657D03*
X73020D03*
X75382D03*
X77744D03*
X65933Y44370D03*
X68295D03*
X70657D03*
X73020D03*
X75382D03*
X77744D03*
X80106Y32756D03*
X82468D03*
X84831D03*
X87193D03*
X89555D03*
X91917D03*
X94279D03*
X80106Y44370D03*
X82468D03*
X84831D03*
X87193D03*
X89555D03*
X91917D03*
X94279D03*
X96642Y32756D03*
X99004D03*
X101366D03*
X103728D03*
X106090D03*
X108453D03*
X110815D03*
X96642Y44370D03*
X99004D03*
X101366D03*
X103728D03*
X106090D03*
X108453D03*
X110815D03*
X113177Y32756D03*
X115539D03*
X117902D03*
X120264D03*
X122626D03*
X124988D03*
X127350D03*
X113177Y44370D03*
X115539D03*
X117902D03*
X120264D03*
X122626D03*
X124988D03*
X127350D03*
X129713Y32756D03*
Y44370D03*
X149043Y32756D03*
X151405D03*
X153768D03*
X156130D03*
X158492D03*
X149043Y44370D03*
X151405D03*
X153768D03*
X156130D03*
X158492D03*
X160854Y32756D03*
X163216D03*
X165579D03*
X167941D03*
X170303D03*
X172665D03*
X175028D03*
X160854Y44370D03*
X163216D03*
X165579D03*
X167941D03*
X170303D03*
X172665D03*
X175028D03*
X177390Y32756D03*
X179752D03*
X177390Y44370D03*
X179752D03*
X195539Y32756D03*
X197902D03*
X200264D03*
X202626D03*
X204988D03*
X207350D03*
X195539Y44370D03*
X197902D03*
X200264D03*
X202626D03*
X204988D03*
X207350D03*
X209713Y32756D03*
X212075D03*
X214437D03*
X216799D03*
X219161D03*
X221524D03*
X223886D03*
X209713Y44370D03*
X212075D03*
X214437D03*
X216799D03*
X219161D03*
X221524D03*
X223886D03*
X226248Y32756D03*
X228610D03*
X230972D03*
X233335D03*
X235697D03*
X238059D03*
X240421D03*
X226248Y44370D03*
X228610D03*
X230972D03*
X233335D03*
X235697D03*
X238059D03*
X240421D03*
X242783Y32756D03*
X245146D03*
X247508D03*
X249870D03*
X252232D03*
X254594D03*
X256957D03*
X242783Y44370D03*
X245146D03*
X247508D03*
X249870D03*
X252232D03*
X254594D03*
X256957D03*
X259319Y32756D03*
Y44370D03*
X276622Y32756D03*
X278984D03*
X281346D03*
X283709D03*
X286071D03*
X288433D03*
X276622Y44370D03*
X278984D03*
X281346D03*
X283709D03*
X286071D03*
X288433D03*
X290795Y32756D03*
X293157D03*
X295520D03*
X297882D03*
X300244D03*
X302606D03*
X304968D03*
X290795Y44370D03*
X293157D03*
X295520D03*
X297882D03*
X300244D03*
X302606D03*
X304968D03*
X307331Y32756D03*
Y44370D03*
X510815Y53544D03*
X513177D03*
X515539D03*
X510815Y65158D03*
X513177D03*
X515539D03*
X517902Y53544D03*
X520264D03*
X522626D03*
X524988D03*
X527350D03*
X529713D03*
X532075D03*
X517902Y65158D03*
X520264D03*
X522626D03*
X524988D03*
X527350D03*
X529713D03*
X532075D03*
X534437Y53544D03*
X536799D03*
X539161D03*
X541524D03*
X543886D03*
X546248D03*
X548610D03*
X534437Y65158D03*
X536799D03*
X539161D03*
X541524D03*
X543886D03*
X546248D03*
X548610D03*
X550972Y53544D03*
X553335D03*
X555697D03*
X558059D03*
X560421D03*
X562784D03*
X565146D03*
X550972Y65158D03*
X553335D03*
X555697D03*
X558059D03*
X560421D03*
X562784D03*
X565146D03*
X567508Y53544D03*
X569870D03*
X572232D03*
X574595D03*
X567508Y65158D03*
X569870D03*
X572232D03*
X574595D03*
X593925Y53544D03*
X596287D03*
X598650D03*
X593925Y65158D03*
X596287D03*
X598650D03*
X601012Y53544D03*
X603374D03*
X605736D03*
X608098D03*
X610461D03*
X612823D03*
X615185D03*
X601012Y65158D03*
X603374D03*
X605736D03*
X608098D03*
X610461D03*
X612823D03*
X615185D03*
X617547Y53544D03*
X619910D03*
X622272D03*
X624634D03*
X617547Y65158D03*
X619910D03*
X622272D03*
X624634D03*
X640421Y53544D03*
X642784D03*
X645146D03*
X647508D03*
X640421Y65158D03*
X642784D03*
X645146D03*
X647508D03*
X649870Y53544D03*
X652232D03*
X654595D03*
X656957D03*
X659319D03*
X661681D03*
X664043D03*
X649870Y65158D03*
X652232D03*
X654595D03*
X656957D03*
X659319D03*
X661681D03*
X664043D03*
X666406Y53544D03*
X668768D03*
X671130D03*
X673492D03*
X675854D03*
X678217D03*
X666406Y65158D03*
X668768D03*
X671130D03*
X673492D03*
X675854D03*
X678217D03*
X680579Y53544D03*
X682941D03*
X685303D03*
X687665D03*
X690028D03*
X692390D03*
X694752D03*
X680579Y65158D03*
X682941D03*
X685303D03*
X687665D03*
X690028D03*
X692390D03*
X694752D03*
X697114Y53544D03*
X699476D03*
X701839D03*
X704201D03*
X697114Y65158D03*
X699476D03*
X701839D03*
X704201D03*
X721504Y53544D03*
X723866D03*
X726228D03*
X728591D03*
X721504Y65158D03*
X723866D03*
X726228D03*
X728591D03*
X730953Y53544D03*
X733315D03*
X735677D03*
X738039D03*
X740402D03*
X742764D03*
X745126D03*
X730953Y65158D03*
X733315D03*
X735677D03*
X738039D03*
X740402D03*
X742764D03*
X745126D03*
X747488Y53544D03*
X749850D03*
X752213D03*
X747488Y65158D03*
X749850D03*
X752213D03*
X1540342Y32756D03*
Y44370D03*
X1542704Y32756D03*
X1545066D03*
X1547429D03*
X1549791D03*
X1552153D03*
X1554515D03*
X1556877D03*
X1542704Y44370D03*
X1545066D03*
X1547429D03*
X1549791D03*
X1552153D03*
X1554515D03*
X1556877D03*
X1559240Y32756D03*
X1561602D03*
X1563964D03*
X1566326D03*
X1568688D03*
X1571051D03*
X1573413D03*
X1559240Y44370D03*
X1561602D03*
X1563964D03*
X1566326D03*
X1568688D03*
X1571051D03*
X1573413D03*
X1575775Y32756D03*
X1578137D03*
X1580499D03*
X1582862D03*
X1585224D03*
X1587586D03*
X1589948D03*
X1575775Y44370D03*
X1578137D03*
X1580499D03*
X1582862D03*
X1585224D03*
X1587586D03*
X1589948D03*
X1592311Y32756D03*
X1594673D03*
X1597035D03*
X1599397D03*
X1601759D03*
X1604122D03*
X1592311Y44370D03*
X1594673D03*
X1597035D03*
X1599397D03*
X1601759D03*
X1604122D03*
X1623452Y32756D03*
Y44370D03*
X1625814Y32756D03*
X1628177D03*
X1630539D03*
X1632901D03*
X1635263D03*
X1637625D03*
X1639988D03*
X1625814Y44370D03*
X1628177D03*
X1630539D03*
X1632901D03*
X1635263D03*
X1637625D03*
X1639988D03*
X1642350Y32756D03*
X1644712D03*
X1647074D03*
X1649437D03*
X1651799D03*
X1654161D03*
X1642350Y44370D03*
X1644712D03*
X1647074D03*
X1649437D03*
X1651799D03*
X1654161D03*
X1669948Y32756D03*
X1672311D03*
X1669948Y44370D03*
X1672311D03*
X1674673Y32756D03*
X1677035D03*
X1679397D03*
X1681759D03*
X1684122D03*
X1686484D03*
X1688846D03*
X1674673Y44370D03*
X1677035D03*
X1679397D03*
X1681759D03*
X1684122D03*
X1686484D03*
X1688846D03*
X1691208Y32756D03*
X1693570D03*
X1695933D03*
X1698295D03*
X1700657D03*
X1703019D03*
X1691208Y44370D03*
X1693570D03*
X1695933D03*
X1698295D03*
X1700657D03*
X1703019D03*
X1705381Y32756D03*
X1707744D03*
X1710106D03*
X1712468D03*
X1714830D03*
X1717192D03*
X1719555D03*
X1705381Y44370D03*
X1707744D03*
X1710106D03*
X1712468D03*
X1714830D03*
X1717192D03*
X1719555D03*
X1721917Y32756D03*
X1724279D03*
X1726641D03*
X1729003D03*
X1731366D03*
X1733728D03*
X1721917Y44370D03*
X1724279D03*
X1726641D03*
X1729003D03*
X1731366D03*
X1733728D03*
X1751031Y32756D03*
X1753393D03*
X1751031Y44370D03*
X1753393D03*
X1755755Y32756D03*
X1758118D03*
X1760480D03*
X1762842D03*
X1765204D03*
X1767566D03*
X1769929D03*
X1755755Y44370D03*
X1758118D03*
X1760480D03*
X1762842D03*
X1765204D03*
X1767566D03*
X1769929D03*
X1772291Y32756D03*
X1774653D03*
X1777015D03*
X1779377D03*
X1781740D03*
X1772291Y44370D03*
X1774653D03*
X1777015D03*
X1779377D03*
X1781740D03*
G54D107*
X169744Y1396960D03*
X207887D03*
X323727Y1355106D03*
X355855Y1332308D03*
X387983Y1318882D03*
X420111D03*
X452239D03*
X484367D03*
X516495Y1332308D03*
X548623Y1355106D03*
X683363Y1396985D03*
X721506D03*
X1143055Y1433289D03*
X1181198D03*
X1299988Y1355342D03*
X1331996Y1332308D03*
X1364124Y1318882D03*
X1396252D03*
X1428380D03*
X1460508D03*
X1492636Y1332308D03*
X1524764Y1355106D03*
X1644529Y1430581D03*
X1682672D03*
G54D260*
X1025215Y282445D03*
X1035451Y280083D03*
Y282445D03*
X1797432Y1517261D03*
Y1514899D03*
X1807668D03*
G54D14*
X19685Y-29134D03*
Y1803261D03*
X49280Y337402D03*
X41870Y1511291D03*
X441043Y1672205D03*
Y1718465D03*
X1416437Y1672204D03*
Y1718464D03*
X1808192Y1569255D03*
X1812980Y502472D03*
X1837795Y-29134D03*
Y1803261D03*
X2081889Y-29134D03*
Y1803261D03*
G54D50*
X81899Y637060D03*
X138469Y534003D03*
X397819Y1403108D03*
Y1408908D03*
X455434Y1404469D03*
X651490Y220802D03*
Y226602D03*
X656926Y220797D03*
Y226597D03*
X982385Y213233D03*
Y207433D03*
X987285D03*
Y213233D03*
X1047371Y367937D03*
Y373737D03*
X1133220Y1612190D03*
Y1606390D03*
X1431575Y1404469D03*
X1542018Y298126D03*
Y303926D03*
X1690028Y560700D03*
X1750847Y280163D03*
X1745000Y290962D03*
Y296762D03*
X1750500Y296962D03*
X1750847Y285963D03*
X1750500Y302762D03*
X1830852Y1503991D03*
Y1509791D03*
G54D215*
X765160Y270763D03*
G54D116*
X217124Y576051D03*
Y610051D03*
Y644051D03*
X1636849Y644531D03*
Y678531D03*
Y712531D03*
G54D152*
X335728Y872716D03*
X337579Y869511D03*
X333879Y875920D03*
Y882329D03*
Y888737D03*
Y895146D03*
Y901555D03*
Y907963D03*
Y914372D03*
Y920780D03*
Y927189D03*
Y933598D03*
Y940006D03*
Y946414D03*
Y952823D03*
Y959232D03*
Y965640D03*
Y972049D03*
Y978457D03*
X334312Y1007187D03*
Y1013595D03*
Y1020004D03*
Y1026413D03*
Y1032821D03*
Y1039230D03*
Y1045639D03*
Y1052047D03*
X336161Y1055251D03*
Y1061660D03*
Y1068068D03*
Y1074477D03*
Y1080885D03*
Y1087294D03*
Y1093703D03*
Y1100111D03*
Y1106520D03*
X547028Y879124D03*
Y885533D03*
Y891942D03*
Y898350D03*
Y904759D03*
Y911167D03*
Y917576D03*
Y923985D03*
Y930393D03*
Y936801D03*
Y943210D03*
Y949619D03*
Y956027D03*
Y962436D03*
X543329Y981662D03*
X545179Y978457D03*
X547028Y968845D03*
Y975253D03*
X541479Y984866D03*
X543761Y997574D03*
X545612Y1000778D03*
X547461Y1003983D03*
Y1010391D03*
Y1016800D03*
Y1023208D03*
Y1029617D03*
X545612Y1045639D03*
X547461Y1036026D03*
Y1042434D03*
X545612Y1052047D03*
Y1058455D03*
Y1064864D03*
Y1071273D03*
Y1077681D03*
Y1084090D03*
Y1090498D03*
Y1096907D03*
Y1103316D03*
X1311870Y872716D03*
X1313721Y869511D03*
X1310021Y875920D03*
Y882329D03*
Y888737D03*
Y895146D03*
Y901555D03*
Y907963D03*
Y914372D03*
Y920780D03*
Y927189D03*
Y933598D03*
Y940006D03*
Y946414D03*
Y952823D03*
Y959232D03*
Y965640D03*
Y972049D03*
Y978457D03*
X1310454Y1007187D03*
Y1013595D03*
Y1020004D03*
Y1026413D03*
Y1032821D03*
Y1039230D03*
Y1045639D03*
Y1052047D03*
X1312303Y1055251D03*
Y1061660D03*
Y1068068D03*
Y1074477D03*
Y1080885D03*
Y1087294D03*
Y1093703D03*
Y1100111D03*
Y1106520D03*
X1523170Y879124D03*
Y885533D03*
Y891942D03*
Y898350D03*
Y904759D03*
Y911167D03*
Y917576D03*
Y923985D03*
Y930393D03*
Y936801D03*
Y943210D03*
Y949619D03*
Y956027D03*
Y962436D03*
X1519471Y981662D03*
X1521321Y978457D03*
X1523170Y968845D03*
Y975253D03*
X1517621Y984866D03*
X1519903Y997574D03*
X1521754Y1000778D03*
X1523603Y1003983D03*
Y1010391D03*
Y1016800D03*
Y1023208D03*
Y1029617D03*
X1521754Y1045639D03*
X1523603Y1036026D03*
Y1042434D03*
X1521754Y1052047D03*
Y1058455D03*
Y1064864D03*
Y1071273D03*
Y1077681D03*
Y1084090D03*
Y1090498D03*
Y1096907D03*
Y1103316D03*
G54D305*
X1726412Y217580D03*
G54D314*
X1756177Y288494D03*
Y290463D03*
Y292431D03*
Y294400D03*
Y286526D03*
X1774681Y294400D03*
Y292431D03*
Y290463D03*
G54D224*
X779270Y1580602D03*
Y1582570D03*
Y1584539D03*
Y1586507D03*
Y1588476D03*
Y1590444D03*
X796888Y1582570D03*
Y1580602D03*
Y1590444D03*
Y1588476D03*
Y1586507D03*
Y1584539D03*
X821270Y1580602D03*
Y1582570D03*
Y1584539D03*
Y1586507D03*
Y1588476D03*
Y1590444D03*
X838888Y1582570D03*
Y1580602D03*
Y1590444D03*
Y1588476D03*
Y1586507D03*
Y1584539D03*
X863270Y1580602D03*
Y1582570D03*
Y1584539D03*
Y1586507D03*
Y1588476D03*
Y1590444D03*
X880888Y1582570D03*
Y1580602D03*
Y1590444D03*
Y1588476D03*
Y1586507D03*
Y1584539D03*
X905270Y1580602D03*
Y1582570D03*
Y1584539D03*
Y1586507D03*
Y1588476D03*
Y1590444D03*
X922888Y1582570D03*
Y1580602D03*
Y1590444D03*
Y1588476D03*
Y1586507D03*
Y1584539D03*
G54D23*
X42809Y363429D03*
X39008D03*
X36524Y392288D03*
X54620Y58834D03*
X50308D03*
X59322Y363429D03*
X51114D03*
X56163Y414020D03*
X59833Y1615851D03*
Y1606851D03*
X50333Y1615851D03*
X54333D03*
X47333Y1656851D03*
X53700Y1674717D03*
X63429Y363429D03*
X67681D03*
X69523Y414020D03*
X77588Y656669D03*
X75274Y1546611D03*
X74100Y1615817D03*
X78000D03*
X73833Y1683751D03*
X77833Y1683651D03*
X69833D03*
X86302Y637122D03*
X89461Y660648D03*
X85565Y660656D03*
X93547Y685662D03*
X82311Y709866D03*
X84048Y1571478D03*
X88048D03*
X92251D03*
X81900Y1615817D03*
X85800D03*
X81833Y1683651D03*
X110987Y541732D03*
X97549Y685582D03*
X100931Y702294D03*
X100914Y709264D03*
X107170Y1517259D03*
X96251Y1571478D03*
X104900Y1608917D03*
X124170Y480330D03*
X120060D03*
X115060Y541739D03*
X127377Y541972D03*
X123257Y541902D03*
X119087Y541812D03*
X114021Y663874D03*
X118021D03*
X135006Y490632D03*
X130006D03*
X141103Y480330D03*
X145213D03*
X149568Y1400187D03*
X155098Y1563182D03*
X159107Y1563110D03*
X158118Y1708534D03*
X166631Y1409462D03*
X191267Y699543D03*
X187711Y1400187D03*
X176793Y1579491D03*
X195888Y575488D03*
X199941Y597590D03*
X195888Y609488D03*
X199941Y631590D03*
X195888Y643488D03*
X193461Y666660D03*
X195467Y699543D03*
X204174Y1408762D03*
X200720Y1710379D03*
X222907Y318773D03*
X247487Y104777D03*
X243487D03*
X254297Y124060D03*
X250297D03*
X246297D03*
X242297D03*
X254756Y156819D03*
X271797Y124060D03*
X261297D03*
X268297Y127560D03*
X259933Y143819D03*
X260100Y153979D03*
X263240Y239299D03*
X289357Y116020D03*
X277240Y239299D03*
X303573Y1358370D03*
X313995Y232266D03*
X306956Y559884D03*
X320614Y1366708D03*
X325617Y81260D03*
X332700Y138879D03*
X328700D03*
X338249Y224026D03*
X328965Y231756D03*
X332465D03*
X324106Y599390D03*
X328106D03*
X335673Y1336070D03*
X339811Y123194D03*
X342285Y210626D03*
X346203Y210644D03*
X346249Y224026D03*
X342249D03*
X352742Y1343910D03*
X367807Y1322109D03*
X386004Y1329935D03*
X385123Y1643266D03*
X378547Y1643272D03*
X374391Y1650968D03*
X374509Y1682676D03*
X399935Y1322109D03*
X391563Y1642736D03*
X414595Y944490D03*
X418595D03*
X410795D03*
X414616Y936165D03*
X414626Y959273D03*
X410826D03*
X418626D03*
X418671Y973774D03*
X414626D03*
X410871D03*
X410800Y988185D03*
X414600D03*
X418600D03*
X414550Y1002667D03*
X410838D03*
X418550D03*
X418591Y1017127D03*
X410816D03*
X414591D03*
X417104Y1329935D03*
X407125Y1419520D03*
X407557Y1655402D03*
X422395Y944490D03*
X422426Y959273D03*
X422471Y973774D03*
X422400Y988185D03*
X422350Y1002667D03*
X422391Y1017127D03*
X432063Y1322109D03*
X429383Y1597171D03*
X433383D03*
X437840Y122288D03*
X452071Y261006D03*
X445720Y399279D03*
X451720Y408279D03*
X451520Y479354D03*
X442520D03*
X437520D03*
X447520D03*
X448873Y1329935D03*
X446258Y1436148D03*
X449778D03*
X438020Y1564954D03*
X450020D03*
X437990Y1644294D03*
X441990D03*
X468323Y261088D03*
X455720Y408279D03*
X462720Y399279D03*
X466520Y470354D03*
X456520Y479354D03*
X461520D03*
X462704Y944490D03*
X466704Y936165D03*
X462704D03*
X458904D03*
X466704Y944490D03*
X458904D03*
X466704Y959273D03*
X458904D03*
X462704D03*
X466704Y973774D03*
X458904D03*
X462704D03*
X466704Y988185D03*
X462704D03*
X458904D03*
X466704Y1002667D03*
X458904D03*
X462704D03*
X466704Y1017127D03*
X458904D03*
X462704D03*
X464191Y1322109D03*
X468620Y1404479D03*
X459520Y1549454D03*
X456020Y1574954D03*
X464020D03*
X457220Y1586512D03*
X464930Y1651749D03*
X473500Y234879D03*
X475252Y261027D03*
X481500Y293879D03*
X478720Y363379D03*
X482720D03*
X479169Y479213D03*
X474169D03*
X484169D03*
X470504Y936165D03*
Y944490D03*
Y959273D03*
Y973774D03*
Y988185D03*
Y1002667D03*
Y1017127D03*
X481254Y1329927D03*
X477368Y1404487D03*
X472701D03*
X481468D03*
X476281Y1416010D03*
X480252D03*
X499096Y261731D03*
X492936Y261774D03*
X485500Y293879D03*
X494720Y363379D03*
X488169Y479213D03*
X498169D03*
X493169D03*
X496319Y1335535D03*
X485712Y1421994D03*
X517020Y83379D03*
X512220D03*
X515804Y261980D03*
X509496Y262056D03*
X514720Y363379D03*
X510720D03*
X502720D03*
X504040Y378419D03*
X513720Y392879D03*
X509720D03*
X503169Y470213D03*
X513382Y1343910D03*
X525720Y290879D03*
X527720Y363379D03*
X520830Y380899D03*
X529720Y392879D03*
X525720D03*
X528447Y1358333D03*
X535720Y363379D03*
X545510Y1366708D03*
X552720Y164879D03*
X559300Y417274D03*
X552000Y1456879D03*
X569300Y408424D03*
X589330Y88037D03*
X593240D03*
X597220Y88379D03*
X598724Y150388D03*
X593220Y179379D03*
Y187379D03*
X596800Y502049D03*
X614384Y121909D03*
X610104D03*
X602278D03*
X599720Y179379D03*
Y187379D03*
X614095Y275147D03*
X608895D03*
X611609Y320937D03*
X603822Y320887D03*
X622000Y88379D03*
X630951Y121909D03*
X626699D03*
X622592D03*
X627064Y253219D03*
X619496Y320987D03*
X627236Y320968D03*
X647725Y1646211D03*
X643725D03*
X653820Y84279D03*
X655000Y91879D03*
X661865Y508571D03*
X654927Y525197D03*
X659039Y518108D03*
X663187Y1400212D03*
X650225Y1702711D03*
X676643Y108902D03*
X680623D03*
X670220Y498379D03*
X675220D03*
X680220D03*
X675220Y511379D03*
X680250Y1408587D03*
X694453Y128185D03*
X687453D03*
X683453D03*
X688290Y382439D03*
X690220Y511379D03*
X685220D03*
X704000Y76379D03*
X704953Y128185D03*
X700963Y128245D03*
X713220Y380879D03*
X711220Y511379D03*
X705220D03*
X701330Y1400212D03*
X711780Y1617447D03*
X723933Y135505D03*
X727000Y368242D03*
X722500D03*
X718393Y1408587D03*
X725552Y1602610D03*
X719612Y1602700D03*
X722630Y1649987D03*
X726720Y1644457D03*
X735800Y368242D03*
X731400D03*
X745220Y498379D03*
Y524879D03*
X730680Y1644457D03*
X760193Y100745D03*
X758220Y441879D03*
X751220Y524879D03*
X761700Y511979D03*
X759859Y1689112D03*
X765160Y281339D03*
X776000Y363879D03*
X764000D03*
X771960Y363999D03*
X767960D03*
X777220Y445379D03*
X772952Y1584210D03*
X763359Y1723612D03*
X789720Y425379D03*
X787520Y516999D03*
X798400Y363217D03*
X806000D03*
X796546Y413143D03*
X819114Y117715D03*
X827114D03*
X823114D03*
X826614Y147215D03*
X813800Y383117D03*
X818000D03*
X824220Y425379D03*
X816670Y502439D03*
X812810Y516899D03*
X815252Y1585110D03*
X839360Y117599D03*
X831114Y117715D03*
X840220Y184879D03*
Y197879D03*
X836300Y421417D03*
X844935Y90268D03*
X844220Y184879D03*
Y197879D03*
X856190Y187127D03*
X845505Y284508D03*
Y294794D03*
X849000Y438217D03*
X857252Y1585110D03*
X886503Y278804D03*
X891747Y867871D03*
X887897D03*
X881372Y914972D03*
X899252Y1585110D03*
X921757Y964704D03*
X916974D03*
X926823Y964669D03*
X957027Y195914D03*
X947348Y985594D03*
X961137Y195866D03*
X981445Y175600D03*
X977195Y203940D03*
X981789Y360977D03*
X987139Y424473D03*
X1005699Y167360D03*
X996415Y175090D03*
X999915D03*
X1005395Y214440D03*
X991140Y424473D03*
X1009735Y153960D03*
X1015275Y153966D03*
X1016506Y424321D03*
X1012506D03*
X1023220Y182116D03*
X1034835Y296227D03*
X1031025D03*
X1025958Y362681D03*
X1029922Y362686D03*
X1043424Y283015D03*
X1038606Y296227D03*
X1091457Y1641367D03*
X1103457D03*
X1113140Y1670008D03*
X1105457Y1669967D03*
X1122879Y1436516D03*
X1124862Y1617767D03*
X1124762Y1625427D03*
X1139942Y1444891D03*
X1152720Y183379D03*
X1156720D03*
X1161022Y1436516D03*
X1164830Y1657632D03*
X1159930D03*
X1173374Y170148D03*
X1178085Y1444891D03*
X1181930Y1657632D03*
X1175830D03*
X1170930D03*
X1191206Y136066D03*
X1185030Y1627478D03*
X1192500Y1657942D03*
X1197400D03*
X1186830Y1657632D03*
X1197240Y1703422D03*
X1192340D03*
X1211720Y207379D03*
X1207220D03*
X1215720D03*
X1212610Y219169D03*
X1207530Y219069D03*
X1216610Y219169D03*
X1209900Y244090D03*
X1216656D03*
X1203267Y1653002D03*
X1208010Y1703467D03*
X1203110D03*
X1213910Y1703732D03*
X1218810D03*
X1263150Y300033D03*
X1251150D03*
X1281940Y87789D03*
X1267322Y103681D03*
X1274864Y107229D03*
X1267150Y300033D03*
X1279834Y1358606D03*
X1286013Y79416D03*
X1297342Y287924D03*
X1293398D03*
X1290437Y749482D03*
X1296875Y1366944D03*
X1313788Y62317D03*
X1303264Y74807D03*
X1307542Y298334D03*
X1303542D03*
X1311820Y1335535D03*
X1328883Y1343910D03*
X1343948Y1322109D03*
X1362145Y1329935D03*
X1366369Y86587D03*
X1366001Y95612D03*
X1376076Y1322109D03*
X1394736Y944489D03*
X1390736D03*
X1390719Y936155D03*
X1386936Y944489D03*
X1386967Y959272D03*
X1390767D03*
X1394767D03*
X1390812Y973773D03*
X1394812D03*
X1387012D03*
X1394741Y988184D03*
X1390741D03*
X1386941D03*
X1390691Y1002666D03*
X1394691D03*
X1386891D03*
X1394732Y1017126D03*
X1386869D03*
X1390732D03*
X1393245Y1329935D03*
X1382347Y1394120D03*
X1385066Y1419520D03*
X1398536Y944489D03*
X1398567Y959272D03*
X1398612Y973773D03*
X1398541Y988184D03*
X1398491Y1002666D03*
X1398532Y1017126D03*
X1408204Y1322109D03*
X1402680Y1600289D03*
X1425014Y1329935D03*
X1427349Y1436658D03*
X1423519Y1436668D03*
X1422680Y1584917D03*
X1438845Y944489D03*
X1435045D03*
X1438845Y936164D03*
X1442845Y944489D03*
Y936164D03*
X1435045D03*
X1442845Y959272D03*
X1438845D03*
X1435045D03*
X1438845Y973773D03*
X1442845D03*
X1435045D03*
X1442845Y988184D03*
X1438845D03*
X1435045D03*
X1438845Y1002666D03*
X1435045D03*
X1442845D03*
X1438845Y1017126D03*
X1442845D03*
X1435045D03*
X1440332Y1322109D03*
X1444720Y1404479D03*
X1438547Y1640852D03*
X1443617Y1640832D03*
X1455600Y291217D03*
X1447800D03*
X1458300Y364479D03*
X1449777Y364513D03*
X1453777D03*
X1451780Y407439D03*
X1456777Y421088D03*
X1446645Y936164D03*
Y944489D03*
Y959272D03*
Y973773D03*
Y988184D03*
Y1002666D03*
Y1017126D03*
X1457395Y1329927D03*
X1453509Y1404487D03*
X1448842D03*
X1457609D03*
X1452422Y1416010D03*
X1456393D03*
X1454167Y1640932D03*
X1459127D03*
X1448507Y1640842D03*
X1463000Y155879D03*
X1466777Y364513D03*
X1470777D03*
X1472460Y1335535D03*
X1461803Y1422024D03*
X1472565Y1628119D03*
X1463767Y1640932D03*
X1493384Y413805D03*
X1481384D03*
X1489523Y1343910D03*
X1504602Y295274D03*
X1504278Y284972D03*
X1504602Y307273D03*
X1498184Y364215D03*
X1497384Y413805D03*
X1504588Y1358333D03*
X1524654Y54632D03*
X1517263Y193354D03*
X1521828Y299292D03*
X1521651Y1366708D03*
X1528654Y54632D03*
X1537746Y1303435D03*
X1547697Y121295D03*
X1543720Y584379D03*
X1548720D03*
X1557287Y628952D03*
X1563994Y581234D03*
X1567994D03*
X1624353Y1433808D03*
X1644360Y202757D03*
X1648400Y202747D03*
X1652610Y397219D03*
X1647110Y428719D03*
X1649291Y549252D03*
X1649220Y615179D03*
X1653220D03*
X1641416Y1442183D03*
X1661110Y428719D03*
X1664040Y564169D03*
X1672040D03*
X1668040D03*
X1657220Y615179D03*
X1662496Y1433808D03*
X1673872Y428162D03*
X1686154Y428702D03*
X1676040Y564169D03*
X1680040D03*
X1679559Y1442183D03*
X1703932Y226536D03*
X1704624Y428192D03*
X1701124D03*
X1703720Y503879D03*
X1698720D03*
X1702320Y536489D03*
X1695443Y713362D03*
X1718608Y105901D03*
X1717418Y125184D03*
X1721418D03*
X1715044Y407062D03*
X1718931Y407054D03*
X1710408Y420462D03*
X1708977Y465321D03*
X1713977D03*
X1708030Y688269D03*
X1713159Y688292D03*
X1714320Y704779D03*
X1714298Y711632D03*
X1709107Y722302D03*
X1722608Y105901D03*
X1736418Y125184D03*
X1729418D03*
X1725418D03*
X1725500Y377879D03*
X1722500Y368879D03*
X1733780Y393287D03*
X1729810D03*
X1737660D03*
X1730290Y417357D03*
X1734290D03*
X1736611Y490784D03*
X1746918Y125184D03*
X1743418Y128684D03*
X1746366Y283549D03*
X1743170Y405317D03*
X1764478Y117144D03*
X1769230Y304934D03*
X1758563D03*
X1765663D03*
X1762163D03*
X1754963D03*
X1772863D03*
X1778810Y452157D03*
X1790738Y82384D03*
X1819461Y150818D03*
X1813700Y1497304D03*
X1826075Y1504858D03*
X1843166Y238863D03*
G54D323*
X1879155Y354948D03*
Y458898D03*
Y478898D03*
Y582848D03*
Y602848D03*
Y706798D03*
Y726798D03*
Y830748D03*
X1900275Y-9342D03*
X1889155Y354948D03*
Y458898D03*
Y478898D03*
X1900275Y582858D03*
X1889155Y582848D03*
Y602848D03*
Y706798D03*
X1900275Y726808D03*
X1889155Y726798D03*
X1900275Y830758D03*
X1889155Y830748D03*
X1900275Y850758D03*
Y954708D03*
X1910275Y-9342D03*
Y582858D03*
Y726808D03*
Y830758D03*
Y850758D03*
Y954708D03*
X1921395Y-9332D03*
X1931395D03*
Y582868D03*
X1921395D03*
X1931395Y602868D03*
X1921395D03*
Y1195068D03*
X1931395D03*
X1942395Y-9152D03*
Y583048D03*
Y603048D03*
Y1195248D03*
X1963362Y-9190D03*
X1952395Y-9152D03*
X1963362Y583010D03*
X1952395Y583048D03*
X1963362Y603010D03*
X1952395Y603048D03*
X1963362Y1195210D03*
X1952395Y1195248D03*
X1973362Y-9190D03*
Y583010D03*
Y603010D03*
Y1195210D03*
X1994482Y-9180D03*
X1984482D03*
Y583020D03*
X1994482D03*
X1984482Y603020D03*
X1994482D03*
Y1195220D03*
X1984482D03*
X2005452Y-9180D03*
X2015452D03*
Y583020D03*
X2005452D03*
X2015452Y603020D03*
X2005452D03*
Y1195220D03*
X2015452D03*
X2026452Y-9000D03*
Y583200D03*
Y603200D03*
Y1195400D03*
X2047419Y-9038D03*
X2036452Y-9000D03*
X2047419Y583162D03*
X2036452Y583200D03*
X2047419Y603162D03*
X2036452Y603200D03*
X2047419Y1195362D03*
X2036452Y1195400D03*
X2057419Y-9038D03*
Y583162D03*
Y603162D03*
Y1195362D03*
X2068539Y603172D03*
X2078539D03*
Y1195372D03*
X2068539D03*
G54D125*
X236435Y582055D03*
Y616055D03*
Y650055D03*
X254545Y582055D03*
Y616055D03*
Y650055D03*
X1599428Y638527D03*
Y672527D03*
Y706527D03*
X1617538Y638527D03*
Y672527D03*
Y706527D03*
G54D32*
X57646Y12480D03*
X137272D03*
X186622D03*
X266858D03*
X315598D03*
X502528Y33268D03*
X582154D03*
X631504D03*
X711740D03*
X760480D03*
X1532055Y12480D03*
X1611681D03*
X1661031D03*
X1741267D03*
X1790007D03*
G54D161*
X384600Y1595100D03*
X411162Y1414126D03*
X710486Y77695D03*
X919488Y1660733D03*
X956800Y1663725D03*
X1132187Y1582738D03*
G54D170*
X416155Y1404128D03*
Y1405702D03*
Y1407277D03*
Y1408852D03*
Y1410427D03*
Y1412002D03*
Y1413576D03*
Y1415151D03*
Y1416726D03*
Y1418301D03*
Y1419876D03*
Y1421450D03*
X438793Y1404128D03*
Y1421450D03*
Y1419876D03*
Y1418301D03*
Y1416726D03*
Y1415151D03*
Y1413576D03*
Y1412002D03*
Y1410427D03*
Y1408852D03*
Y1407277D03*
Y1405702D03*
X1392296Y1404128D03*
Y1405702D03*
Y1407277D03*
Y1408852D03*
Y1410427D03*
Y1412002D03*
Y1413576D03*
Y1415151D03*
Y1416726D03*
Y1418301D03*
Y1419876D03*
Y1421450D03*
X1414934Y1404128D03*
Y1421450D03*
Y1419876D03*
Y1418301D03*
Y1416726D03*
Y1415151D03*
Y1413576D03*
Y1412002D03*
Y1410427D03*
Y1408852D03*
Y1407277D03*
Y1405702D03*
G54D342*
G01X154193Y1393791D02*
X152905D01*
X151352Y1392238D01*
Y1390404D01*
G01X149568Y1403245D02*
X151277Y1401536D01*
Y1400675D01*
X152846Y1399106D01*
X154193D01*
G01X145692Y1392745D02*
X149568D01*
G01X145692D02*
Y1396275D01*
G01X154193Y1395563D02*
X152732D01*
X149914Y1392745D01*
X149568D01*
G01Y1395145D02*
X148286D01*
X147156Y1396275D01*
X145692D01*
G01X149568Y1397695D02*
Y1400095D01*
G01D02*
X149856D01*
X152617Y1397334D01*
X154193D01*
G01X166631Y1409370D02*
X166437Y1409176D01*
Y1403338D01*
G01X170673Y1409370D02*
X168209Y1406906D01*
Y1403338D01*
G01X170673Y1412520D02*
X166631D01*
G01X192336Y1393791D02*
X191048D01*
X189495Y1392238D01*
Y1390404D01*
G01X187711Y1403245D02*
X189589Y1401367D01*
Y1400463D01*
X190946Y1399106D01*
X192336D01*
G01X187711Y1395170D02*
Y1392745D01*
G01X192336Y1395563D02*
X190875D01*
X188057Y1392745D01*
X187711D01*
G01Y1400095D02*
X188047D01*
X190808Y1397334D01*
X192336D01*
G01X187711Y1397670D02*
Y1400095D01*
G01X204816Y567981D02*
X206694Y569859D01*
X207595D01*
X208955Y571219D01*
Y572606D01*
G01X207966Y567981D02*
Y568317D01*
X210727Y571078D01*
Y572606D01*
G01X200140Y584791D02*
X200199Y584850D01*
X204723D01*
G01X196998Y588879D02*
X196990Y588871D01*
Y584791D01*
G01X200148Y588879D02*
X200229D01*
X202486Y586622D01*
X204723D01*
G01X208955Y606606D02*
Y605219D01*
X207595Y603859D01*
X206694D01*
X204816Y601981D01*
G01X210727Y606606D02*
Y605078D01*
X207966Y602317D01*
Y601981D01*
G01X204723Y618850D02*
X200199D01*
X200140Y618791D01*
G01X196998Y622879D02*
X196990Y622871D01*
Y618791D01*
G01X204723Y620622D02*
X202486D01*
X200229Y622879D01*
X200148D01*
G01X208955Y640606D02*
Y639219D01*
X207595Y637859D01*
X206694D01*
X204816Y635981D01*
G01X210727Y640606D02*
Y639078D01*
X207966Y636317D01*
Y635981D01*
G01X204723Y652850D02*
X201999D01*
X201940Y652791D01*
X200140D01*
G01X196990D02*
Y656871D01*
X196998Y656879D01*
G01X204723Y654622D02*
X202405D01*
X200148Y656879D01*
G01X204174Y1408670D02*
X204580Y1408264D01*
Y1403338D01*
G01X207716Y1408670D02*
X206352Y1407306D01*
Y1403338D01*
G01X204174Y1411820D02*
X207716D01*
G01X214270Y572606D02*
Y571450D01*
X216058Y569662D01*
X219050D01*
G01X214270Y606606D02*
Y605272D01*
X215777Y603765D01*
X218253D01*
G01X214270Y640606D02*
Y639362D01*
X215370Y638262D01*
X218570D01*
G01X308176Y1351937D02*
X307024D01*
X305335Y1350248D01*
Y1348550D01*
G01X303723Y1353316D02*
Y1351063D01*
X303551Y1350891D01*
G01X303723Y1355853D02*
Y1358128D01*
X303573Y1358278D01*
G01X320420Y1361484D02*
Y1364698D01*
X320614Y1364892D01*
Y1366616D01*
G01X324656Y1369766D02*
X320614D01*
G01X322192Y1361484D02*
Y1364152D01*
X324656Y1366616D01*
G01X337779Y856694D02*
Y854585D01*
X337778Y854584D01*
G01X335928Y859899D02*
X335924Y859895D01*
Y857789D01*
G01X334079Y875920D02*
X332228Y877014D01*
G01X334079Y895146D02*
X334078Y893036D01*
G01X335928Y898350D02*
Y896240D01*
G01X334079Y901555D02*
X332229Y902649D01*
G01X334079Y914372D02*
X332228Y915466D01*
G01X335928D02*
Y917576D01*
G01X334079Y920780D02*
X332229Y921875D01*
G01X334079Y933598D02*
X332228Y934692D01*
G01X337779Y965640D02*
X339607Y966694D01*
X339629Y966716D01*
Y966735D01*
G01X334079Y959232D02*
Y957122D01*
G01Y972049D02*
X332229Y973143D01*
G01X335928Y975253D02*
X334079Y976347D01*
G01X337779Y984866D02*
X336706Y985939D01*
X335349D01*
G01X340061Y997574D02*
X338210Y996480D01*
G01X333834Y1062790D02*
X333907Y1062751D01*
X333908Y1062749D01*
X335961Y1061660D01*
X336361D01*
G01X338211Y1077681D02*
X340062Y1076587D01*
G01X329632Y1092168D02*
X334506Y1087294D01*
X336361D01*
G01X338211Y1084090D02*
X336360Y1082995D01*
G01X338211Y1109724D02*
Y1111834D01*
G01Y1103316D02*
Y1105426D01*
G01X335344Y1097289D02*
X335726Y1096907D01*
X338211D01*
G01Y1124651D02*
Y1122541D01*
G01X336361Y1112929D02*
Y1115039D01*
G01Y1127856D02*
Y1125746D01*
G01X340304Y1329139D02*
X339148D01*
X337463Y1327454D01*
Y1325752D01*
G01X335679Y1330518D02*
Y1328093D01*
G01X340304Y1330911D02*
X338857D01*
X336039Y1328093D01*
X335679D01*
G01X340304Y1332682D02*
X338544D01*
X335679Y1335547D01*
Y1335972D01*
G01X334973Y1333353D02*
Y1335266D01*
X335679Y1335972D01*
G01X345179Y850286D02*
Y848177D01*
X345178Y848176D01*
G01X350728Y847081D02*
Y844972D01*
X350727Y844971D01*
G01X347029Y853490D02*
Y851382D01*
X347027Y851380D01*
G01X343328Y853490D02*
Y851381D01*
X343327Y851380D01*
G01X341479Y856694D02*
Y854585D01*
X341478Y854584D01*
G01X339629Y859899D02*
Y857790D01*
X339628Y857789D01*
G01X347029Y859899D02*
Y857789D01*
G01X348879Y856694D02*
Y854585D01*
X348878Y854584D01*
G01X345179Y863103D02*
Y860993D01*
G01X343328Y859899D02*
Y857790D01*
X343327Y857789D01*
G01X352579Y856694D02*
Y854584D01*
G01X348879Y869511D02*
Y867401D01*
G01X352579Y869511D02*
Y867401D01*
G01X339629Y879124D02*
Y877014D01*
G01Y872716D02*
X341479Y873810D01*
G01X343328Y879124D02*
Y877015D01*
X343329Y877014D01*
G01X352579Y901555D02*
Y899446D01*
X352578Y899445D01*
G01X339629Y898350D02*
Y896240D01*
G01Y891942D02*
Y889832D01*
G01X348879Y888737D02*
Y886627D01*
G01X352579Y895146D02*
X352578Y895145D01*
Y893036D01*
G01X352579Y888737D02*
Y886628D01*
X352578Y886627D01*
G01X348879Y907963D02*
X348878Y907962D01*
Y905853D01*
G01X352579Y907963D02*
X352578Y907962D01*
Y905853D01*
G01X339629Y911167D02*
X341479Y912262D01*
G01X339629Y904759D02*
X341478Y905853D01*
G01X347029Y902649D02*
Y904759D01*
G01X352579Y914372D02*
X352578Y914371D01*
Y912262D01*
G01X339629Y915466D02*
Y917576D01*
G01X348879Y927189D02*
X348878Y927188D01*
Y925079D01*
G01X352579Y927189D02*
X352578Y927188D01*
Y925079D01*
G01X352579Y920780D02*
X352578Y920779D01*
Y918670D01*
G01X339629Y923985D02*
X341478Y925079D01*
G01X339629Y930393D02*
X341479Y931488D01*
G01X348879Y946414D02*
X348878Y946413D01*
Y944304D01*
G01X352579Y946414D02*
X352578Y946413D01*
Y944304D01*
G01X352579Y952823D02*
X352578Y952822D01*
Y950713D01*
G01X352579Y959232D02*
X352578Y959231D01*
Y957122D01*
G01X348879Y965640D02*
X348878Y965639D01*
Y963530D01*
G01X352579Y965640D02*
X352578Y965639D01*
Y963530D01*
G01X347029Y962436D02*
Y960326D01*
G01X339629Y956027D02*
Y953917D01*
G01X345179Y959232D02*
Y957122D01*
G01X350728Y975253D02*
Y973144D01*
X350729Y973143D01*
G01X352579Y972049D02*
X352578Y972048D01*
Y969939D01*
G01X343328Y975253D02*
Y973144D01*
X343329Y973143D01*
G01X354428Y975253D02*
Y973143D01*
G01X339629D02*
Y975253D01*
G01X345179Y978457D02*
Y976347D01*
G01Y972049D02*
Y969939D01*
G01X347029Y979552D02*
Y981662D01*
G01X352579Y978457D02*
Y976347D01*
G01X339629Y981662D02*
Y979552D01*
G01Y968845D02*
Y966735D01*
G01X347029D02*
Y968845D01*
G01X348879Y984866D02*
X348878Y984865D01*
Y982756D01*
G01X352579Y984866D02*
X352578Y984865D01*
Y982756D01*
G01X347461Y997574D02*
Y999684D01*
G01X351161Y1003983D02*
X351162Y1006093D01*
G01X353011Y1007187D02*
Y1009297D01*
G01Y1000778D02*
Y1002888D01*
G01X347461Y1012501D02*
Y1010391D01*
G01X353011Y1013595D02*
Y1015705D01*
G01X349312Y1013595D02*
Y1015704D01*
X349311Y1015705D01*
G01X353011Y1026413D02*
Y1028523D01*
G01X347461Y1016800D02*
Y1018910D01*
G01X353011Y1020004D02*
Y1022114D01*
G01X347461Y1031727D02*
Y1029617D01*
G01X353011Y1032821D02*
Y1034931D01*
G01X349312Y1032821D02*
Y1034930D01*
X349311Y1034931D01*
G01X343761Y1042434D02*
Y1044544D01*
G01X353011Y1039230D02*
Y1041340D01*
G01X349312Y1052047D02*
Y1054156D01*
X349311Y1054157D01*
G01X353011Y1058455D02*
Y1060565D01*
G01Y1052047D02*
Y1054157D01*
G01X340061Y1055251D02*
X343761Y1057361D01*
G01X340061Y1048842D02*
X343761Y1050952D01*
G01X347461Y1048842D02*
Y1050952D01*
G01Y1055251D02*
Y1057361D01*
G01X353011Y1071273D02*
Y1073383D01*
G01X340061Y1074477D02*
X343761Y1076587D01*
G01X340061Y1068068D02*
X343761Y1070178D01*
G01X347461Y1074477D02*
Y1076587D01*
G01Y1068068D02*
Y1070178D01*
G01X349312Y1071273D02*
Y1073383D01*
G01X353011Y1064864D02*
Y1066974D01*
G01X345611Y1077681D02*
Y1079791D01*
G01X343761Y1080885D02*
X341911Y1079791D01*
G01X353011Y1077681D02*
Y1079791D01*
G01Y1084090D02*
Y1086200D01*
G01X341912Y1084090D02*
X340060Y1082995D01*
G01X353011Y1092608D02*
Y1090498D01*
G01Y1096907D02*
X353010Y1099015D01*
X353011Y1099016D01*
Y1099017D01*
G01X340061Y1106520D02*
Y1108630D01*
G01Y1100111D02*
Y1102221D01*
G01X349312Y1096907D02*
X349311Y1099017D01*
G01X347461Y1100111D02*
Y1102221D01*
G01X343761Y1100111D02*
Y1102221D01*
G01X340061Y1112929D02*
Y1115039D01*
G01X349312Y1122541D02*
X349311Y1124651D01*
G01X343761Y1112929D02*
Y1115039D01*
G01X341912Y1122541D02*
Y1124650D01*
X341911Y1124651D01*
G01X351161Y1119337D02*
Y1121447D01*
G01Y1112929D02*
Y1115039D01*
G01X345611Y1135359D02*
Y1137469D01*
G01Y1131060D02*
Y1128950D01*
G01X343761Y1132154D02*
Y1134264D01*
G01X352742Y1343818D02*
Y1341800D01*
X352548Y1341606D01*
Y1338686D01*
G01X356784Y1343818D02*
Y1343387D01*
X354320Y1340923D01*
Y1338686D01*
G01X352742Y1346968D02*
X356784D01*
G01X359979Y856694D02*
Y854584D01*
G01X367379Y856694D02*
Y854584D01*
G01X359979Y869511D02*
Y867401D01*
G01X367379Y869511D02*
Y867401D01*
G01X359979Y880219D02*
Y882329D01*
G01X367379D02*
Y880219D01*
G01X356279Y888737D02*
Y886628D01*
X356278Y886627D01*
G01X365528Y898350D02*
X365529Y898349D01*
Y896240D01*
G01X361828Y898350D02*
Y896240D01*
G01X359979Y895146D02*
Y893036D01*
G01X369228Y898350D02*
X369229Y898349D01*
Y896240D01*
G01X359979Y899445D02*
Y901555D01*
G01X363679Y888737D02*
Y886628D01*
X363678Y886627D01*
G01X365528Y911167D02*
X365529Y911166D01*
Y909057D01*
G01X365528Y904759D02*
X365529Y904758D01*
Y902649D01*
G01X359979Y914372D02*
X359978Y914371D01*
Y912262D01*
G01X358128Y909057D02*
Y911167D01*
G01Y904759D02*
X358129Y904758D01*
Y902649D01*
G01X361828Y917576D02*
Y915466D01*
G01X356279Y927189D02*
Y925079D01*
G01X365528Y930393D02*
X365529Y930392D01*
Y928283D01*
G01X359979Y920780D02*
Y918670D01*
G01X358128Y930393D02*
Y928283D01*
G01X359979Y933598D02*
X359978Y933597D01*
Y931488D01*
G01X365528Y943210D02*
X365529Y943209D01*
Y941100D01*
G01X365528Y949619D02*
X365529Y949618D01*
Y947509D01*
G01X358128Y949619D02*
Y947509D01*
G01Y943210D02*
X358129Y941100D01*
G01X356279Y946414D02*
Y944304D01*
G01X359979Y937896D02*
Y940006D01*
G01X358128Y962436D02*
X358129Y962435D01*
Y960326D01*
G01X359979Y952823D02*
X359978Y952822D01*
Y950713D01*
G01X361828Y956027D02*
Y953918D01*
X361829Y953917D01*
G01X365528Y956027D02*
Y953918D01*
X365529Y953917D01*
G01X365528Y962436D02*
X365529Y962435D01*
Y960326D01*
G01X369228Y956027D02*
Y953918D01*
X369229Y953917D01*
G01X367379Y965640D02*
X367378Y965639D01*
Y963530D01*
G01X356279Y965640D02*
Y963530D01*
G01X359979Y957122D02*
Y959232D01*
G01X363679Y965640D02*
Y963530D01*
G01X358128Y981662D02*
X358129Y981661D01*
Y979552D01*
G01X359979Y972049D02*
X359978Y972048D01*
Y969939D01*
G01X365528Y975253D02*
Y973144D01*
X365529Y973143D01*
G01X365528Y981662D02*
X365529Y981661D01*
Y979552D01*
G01X369228Y975253D02*
Y973144D01*
X369229Y973143D01*
G01X359979Y978457D02*
Y976347D01*
G01X361828Y975253D02*
Y973143D01*
G01X365528Y968845D02*
Y966735D01*
G01X358128Y968845D02*
Y966735D01*
G01X356279Y984866D02*
Y982756D01*
G01X365961Y997574D02*
Y999683D01*
X365962Y999684D01*
G01X358561Y997574D02*
Y999683D01*
X358562Y999684D01*
G01X354861Y1003983D02*
Y1006093D01*
G01X365961Y1003983D02*
Y1006092D01*
X365962Y1006093D01*
G01X362261Y1003983D02*
Y1006093D01*
G01X360412Y1007187D02*
Y1009296D01*
X360411Y1009297D01*
G01X360412Y1000778D02*
Y1002888D01*
G01X369661Y1003983D02*
Y1006092D01*
X369662Y1006093D01*
G01X365961Y1012501D02*
Y1010391D01*
G01X358561Y1012501D02*
Y1010391D01*
G01X356712Y1013595D02*
Y1015705D01*
G01X364112Y1013595D02*
Y1015705D01*
G01X367812Y1013595D02*
Y1015704D01*
X367811Y1015705D01*
G01X365961Y1023208D02*
G02X365962Y1025318I2226050J0D01*
G01X365961Y1016800D02*
G02X365962Y1018910I2226050J0D01*
G01X360412Y1026413D02*
Y1028522D01*
X360411Y1028523D01*
G01X362261Y1023208D02*
Y1025318D01*
G01X360412Y1020004D02*
Y1022114D01*
G01X358561Y1016800D02*
G02X358562Y1018910I2226050J0D01*
G01X369661Y1023208D02*
G02X369662Y1025318I2226050J0D01*
G01X365961Y1029617D02*
G02X365962Y1031727I2226050J0D01*
G01X358561Y1029617D02*
Y1031727D01*
G01X356712Y1032821D02*
Y1034931D01*
G01X365961Y1042434D02*
Y1044543D01*
X365962Y1044544D01*
G01X365961Y1036026D02*
Y1038135D01*
X365962Y1038136D01*
G01X362261Y1042434D02*
Y1044544D01*
G01X360412Y1039230D02*
Y1041340D01*
G01X358561Y1036026D02*
Y1038135D01*
X358562Y1038136D01*
G01X369661Y1042434D02*
Y1044543D01*
X369662Y1044544D01*
G01X356712Y1052047D02*
Y1054157D01*
G01X365961Y1055251D02*
X365962Y1055252D01*
Y1057361D01*
G01X365961Y1048842D02*
X365962Y1048843D01*
Y1050952D01*
G01X360412Y1058455D02*
Y1060565D01*
G01X358561Y1055251D02*
X358562Y1055252D01*
Y1057361D01*
G01X358561Y1050952D02*
Y1048842D01*
G01X365961Y1061660D02*
X365962Y1061661D01*
Y1063770D01*
G01X362261Y1061660D02*
Y1063770D01*
G01X369661Y1061660D02*
X369662Y1061661D01*
Y1063770D01*
G01X356712Y1071273D02*
Y1073383D01*
G01X365961Y1068068D02*
X365962Y1068069D01*
Y1070178D01*
G01X365961Y1074477D02*
Y1076586D01*
X365962Y1076587D01*
G01X360412Y1064864D02*
Y1066973D01*
X360411Y1066974D01*
G01X358561Y1068068D02*
Y1070178D01*
G01Y1074477D02*
Y1076586D01*
X358562Y1076587D01*
G01X360412Y1077681D02*
Y1079791D01*
G01X365961Y1087294D02*
Y1089403D01*
X365962Y1089404D01*
G01X365961Y1080885D02*
G02X365962Y1082995I2226050J0D01*
G01X362261Y1080885D02*
Y1082995D01*
G01X360412Y1084090D02*
Y1086199D01*
X360411Y1086200D01*
G01X358561Y1087294D02*
Y1089404D01*
G01X356712Y1090498D02*
Y1092608D01*
G01X369661Y1080885D02*
G02X369662Y1082995I2226050J0D01*
G01X365961Y1093703D02*
Y1095812D01*
X365962Y1095813D01*
G01X358561Y1093703D02*
Y1095813D01*
G01X354861Y1106520D02*
Y1108630D01*
G01X360412Y1096907D02*
X360411Y1099017D01*
G01X356712Y1096907D02*
X356711Y1099017D01*
G01X354861Y1112929D02*
Y1115039D01*
G01X362261Y1112929D02*
Y1115039D01*
G01X365961Y1125746D02*
Y1127855D01*
X365962Y1127856D01*
G01X358561Y1125746D02*
Y1127856D01*
G01X365961Y1138563D02*
Y1140973D01*
G01X358561Y1138563D02*
Y1140973D01*
G01X372432Y1315713D02*
X371231D01*
X369640Y1314122D01*
Y1312302D01*
G01X367694Y1317092D02*
X367717Y1317069D01*
Y1314667D01*
G01X372432Y1317485D02*
X370797D01*
X367979Y1314667D01*
X367717D01*
G01X367807Y1319592D02*
Y1322017D01*
G01X372432Y1319256D02*
X370840D01*
X368079Y1322017D01*
X367807D01*
G01X382179Y856694D02*
Y854584D01*
G01X374779Y856694D02*
Y854584D01*
G01X382179Y869511D02*
Y867401D01*
G01X374779Y869511D02*
Y867401D01*
G01X382179Y882329D02*
Y880219D01*
G01X374779Y882329D02*
Y880219D01*
G01X371079Y901555D02*
X371078Y901554D01*
Y899445D01*
G01X378479Y895146D02*
Y893036D01*
G01Y901555D02*
X378478Y901554D01*
Y899445D01*
G01X385879D02*
Y901555D01*
G01X371079Y914372D02*
Y912262D01*
G01X382179Y907963D02*
Y905853D01*
G01X378479Y914372D02*
X378478Y914371D01*
Y912262D01*
G01X378479Y907963D02*
X378478Y907962D01*
Y905853D01*
G01X374779Y907963D02*
X374778Y907962D01*
Y905853D01*
G01X372928Y911167D02*
X372929Y911166D01*
Y909057D01*
G01X372928Y904759D02*
Y902649D01*
G01X385879Y914372D02*
X385878Y914371D01*
Y912262D01*
G01X384028Y909057D02*
Y911167D01*
G01Y904759D02*
X384029Y904758D01*
Y902649D01*
G01X371079Y920780D02*
X371078Y920779D01*
Y918670D01*
G01X371079Y933598D02*
Y931488D01*
G01X382179Y927189D02*
Y925079D01*
G01X378479Y927189D02*
X378478Y927188D01*
Y925079D01*
G01X378479Y920780D02*
X378478Y920779D01*
Y918670D01*
G01X374779Y927189D02*
X374778Y927188D01*
Y925079D01*
G01X372928Y930393D02*
X372929Y930392D01*
Y928283D01*
G01X372928Y923985D02*
Y921875D01*
G01X385879Y920780D02*
Y918670D01*
G01X384028Y930393D02*
Y928283D01*
G01X378479Y933598D02*
X378478Y933597D01*
Y931488D01*
G01X385879Y933598D02*
X385878Y933597D01*
Y931488D01*
G01X378479Y946414D02*
X378478Y946413D01*
Y944304D01*
G01X384028Y943210D02*
X384029Y943209D01*
Y941100D01*
G01X372928Y949619D02*
X372929Y949618D01*
Y947509D01*
G01X374779Y946414D02*
X374778Y946413D01*
Y944304D01*
G01X384028Y949619D02*
Y947509D01*
G01X372928Y943210D02*
Y941100D01*
G01X382179Y946414D02*
Y944304D01*
G01X371079Y940006D02*
X371078Y940005D01*
Y937896D01*
G01X378479Y940006D02*
X378478Y940005D01*
Y937896D01*
G01X385879Y940006D02*
Y937896D01*
G01X378479Y952823D02*
X378478Y952822D01*
Y950713D01*
G01X378479Y959232D02*
X378478Y959231D01*
Y957122D01*
G01X384028Y962436D02*
X384029Y962435D01*
Y960326D01*
G01X385879Y952823D02*
X385878Y952822D01*
Y950713D01*
G01X371079Y959232D02*
X371078Y959231D01*
Y957122D01*
G01X378479Y965640D02*
X378478Y965639D01*
Y963530D01*
G01X374779Y965640D02*
X374778Y965639D01*
Y963530D01*
G01X372928Y962436D02*
Y960326D01*
G01X382179Y965640D02*
Y963530D01*
G01X385879Y959232D02*
Y957122D01*
G01X371079Y952823D02*
Y950713D01*
G01X376628Y975253D02*
Y973144D01*
X376629Y973143D01*
G01X378479Y972049D02*
X378478Y972048D01*
Y969939D01*
G01X384028Y981662D02*
X384029Y981661D01*
Y979552D01*
G01X385879Y972049D02*
X385878Y972048D01*
Y969939D01*
G01X371079Y978457D02*
X371078Y978456D01*
Y976347D01*
G01X372928Y968845D02*
X372929Y968844D01*
Y966735D01*
G01X380328Y975253D02*
Y973143D01*
G01X378479Y978457D02*
Y976347D01*
G01X385879Y978457D02*
Y976347D01*
G01X372928Y981662D02*
Y979552D01*
G01X371079Y972049D02*
Y969939D01*
G01X384028Y968845D02*
Y966735D01*
G01X378479Y984866D02*
X378478Y984865D01*
Y982756D01*
G01X374779Y984866D02*
X374778Y984865D01*
Y982756D01*
G01X382179Y984866D02*
Y982756D01*
G01X373361Y997574D02*
X375210Y996480D01*
G01X384461Y997574D02*
Y999683D01*
X384462Y999684D01*
G01X371512Y1007187D02*
Y1009297D01*
G01Y1000778D02*
X373361Y999684D01*
G01X378912Y1007187D02*
G03X378911Y1009297I-2226050J0D01*
G01X378912Y1000778D02*
Y1002886D01*
G03X378911Y1002888I-3J0D01*
G01X386312Y1007187D02*
Y1009296D01*
X386311Y1009297D01*
G01X386312Y1000778D02*
Y1002888D01*
G01X373361Y1010391D02*
G02X373362Y1012501I2226050J0D01*
G01X384461D02*
Y1010391D01*
G01X382612Y1013595D02*
Y1015705D01*
G01X378912Y1013595D02*
G03X378911Y1015705I-2226050J0D01*
G01X375212Y1013595D02*
Y1015704D01*
X375211Y1015705D01*
G01X371512Y1026413D02*
Y1028522D01*
X371511Y1028523D01*
G01X371512Y1020004D02*
G03X371511Y1022114I-2226050J0D01*
G01X378912Y1026413D02*
Y1028522D01*
X378911Y1028523D01*
G01X378912Y1020004D02*
G03X378911Y1022114I-2226050J0D01*
G01X373361Y1016800D02*
Y1018910D01*
G01X386312Y1026413D02*
Y1028522D01*
X386311Y1028523D01*
G01X386312Y1020004D02*
Y1022114D01*
G01X384461Y1016800D02*
Y1018909D01*
X384462Y1018910D01*
G01X373361Y1029617D02*
G02X373362Y1031727I2226050J0D01*
G01X384461Y1029617D02*
Y1031727D01*
G01X382612Y1032821D02*
Y1034931D01*
G01X378912Y1032821D02*
G03X378911Y1034931I-2226050J0D01*
G01X375212Y1032821D02*
G03X375211Y1034931I-2226050J0D01*
G01X373361Y1036026D02*
Y1038136D01*
G01X386312Y1039230D02*
Y1041340D01*
G01X384461Y1036026D02*
G02X384462Y1038136I2226050J0D01*
G01X371512Y1058455D02*
Y1060564D01*
X371511Y1060565D01*
G01X382612Y1052047D02*
Y1054157D01*
G01X378912Y1058455D02*
Y1060564D01*
X378911Y1060565D01*
G01X378912Y1052047D02*
X378911Y1052048D01*
Y1054157D01*
G01X375212Y1052047D02*
X375211Y1052048D01*
Y1054157D01*
G01X373361Y1055251D02*
Y1057361D01*
G01Y1048842D02*
X373362Y1048843D01*
Y1050952D01*
G01X386312Y1058455D02*
Y1060565D01*
G01X384461Y1055251D02*
X384462Y1055252D01*
Y1057361D01*
G01X384461Y1048842D02*
Y1050952D01*
G01X371512Y1064864D02*
Y1066974D01*
G01Y1077681D02*
G03X371511Y1079791I-2226050J0D01*
G01X382612Y1071273D02*
Y1073383D01*
G01X378912Y1071273D02*
Y1073382D01*
X378911Y1073383D01*
G01X378912Y1064864D02*
G03X378911Y1066974I-2226050J0D01*
G01X375212Y1071273D02*
Y1073382D01*
X375211Y1073383D01*
G01X373361Y1074477D02*
Y1076587D01*
G01Y1068068D02*
X373362Y1068069D01*
Y1070178D01*
G01X386312Y1064864D02*
Y1066973D01*
X386311Y1066974D01*
G01X384461Y1074477D02*
G02X384462Y1076587I2226050J0D01*
G01X384461Y1068068D02*
Y1070178D01*
G01X378912Y1077681D02*
G03X378911Y1079791I-2226050J0D01*
G01X386312Y1077681D02*
G03X386311Y1079791I-2226050J0D01*
G01X371512Y1084090D02*
Y1086200D01*
G01X382612Y1090498D02*
G03X382611Y1092608I-2226050J0D01*
G01X378912Y1090498D02*
G03X378911Y1092608I-2226050J0D01*
G01X378912Y1084090D02*
Y1086199D01*
X378911Y1086200D01*
G01X375212Y1090498D02*
G03X375211Y1092608I-2226050J0D01*
G01X373361Y1087294D02*
Y1089403D01*
X373362Y1089404D01*
G01X386312Y1084090D02*
Y1086199D01*
X386311Y1086200D01*
G01X384461Y1087294D02*
Y1089404D01*
G01X373361Y1093703D02*
Y1095812D01*
X373362Y1095813D01*
G01X377061Y1112929D02*
Y1115039D01*
G01X373361Y1112929D02*
Y1115039D01*
G01X384461Y1112929D02*
Y1115039D01*
G01X380761Y1125746D02*
Y1127856D01*
G01X373361Y1125746D02*
Y1127856D01*
G01X380761Y1138563D02*
Y1140973D01*
G01X373361Y1138563D02*
Y1140973D01*
G01X386004Y1329843D02*
X384676Y1328515D01*
Y1325260D01*
G01X390029Y1332993D02*
X386004D01*
G01X390029Y1329843D02*
X388321Y1328135D01*
X387667D01*
X386448Y1326916D01*
Y1325260D01*
G01X393279Y850286D02*
Y848178D01*
X393278Y848177D01*
Y848176D01*
G01X396979Y856694D02*
Y854584D01*
G01X389579Y856694D02*
Y854584D01*
G01X396979Y869511D02*
Y867401D01*
G01X389579Y869511D02*
Y867401D01*
G01X396979Y882329D02*
Y880219D01*
G01X389579Y882329D02*
Y880219D01*
G01X400679Y875920D02*
Y873811D01*
X400678Y873810D01*
G01X387728Y898350D02*
X387729Y898349D01*
Y896240D01*
G01X395128Y898350D02*
X395129Y898349D01*
Y896240D01*
G01X391428Y898350D02*
Y896240D01*
G01X389579Y895146D02*
Y893036D01*
G01X396979Y901555D02*
X396978Y901554D01*
Y899445D01*
G01X387728Y917576D02*
Y915466D01*
G01X398828Y911167D02*
X398829Y911166D01*
Y909057D01*
G01X398828Y904759D02*
Y902649D01*
G01X396979Y914372D02*
Y912262D01*
G01X391428Y911167D02*
X391429Y911166D01*
Y909057D01*
G01X391428Y904759D02*
X391429Y904758D01*
Y902649D01*
G01X398828Y930393D02*
X398829Y930392D01*
Y928283D01*
G01X398828Y923985D02*
Y921875D01*
G01X396979Y920780D02*
X396978Y920779D01*
Y918670D01*
G01X391428Y930393D02*
X391429Y930392D01*
Y928283D01*
G01X400679Y927189D02*
X400678Y925079D01*
G01X396979Y933598D02*
Y931488D01*
G01X398828Y943210D02*
Y941100D01*
G01X396979Y940006D02*
X396978Y940005D01*
Y937896D01*
G01X391428Y943210D02*
X391429Y943209D01*
Y941100D01*
G01X400679Y940006D02*
X400678Y940005D01*
Y937896D01*
G01X391428Y949619D02*
X391429Y949618D01*
Y947509D01*
G01X387728Y956027D02*
Y953918D01*
X387729Y953917D01*
G01X398828Y962436D02*
Y960326D01*
G01X391428Y962436D02*
X391429Y962435D01*
Y960326D01*
G01X391428Y956027D02*
Y953918D01*
X391429Y953917D01*
G01X400679Y965640D02*
X400678Y965639D01*
Y963530D01*
G01X387728Y975253D02*
Y973143D01*
G01X398828Y968845D02*
X398829Y968844D01*
Y966735D01*
G01X391428Y968845D02*
X391429Y968844D01*
Y966735D01*
G01X398828Y981662D02*
Y979552D01*
G01X396979Y978457D02*
X396978Y978456D01*
Y976347D01*
G01X396979Y972049D02*
Y969939D01*
G01X395128Y975253D02*
Y973144D01*
X395129Y973143D01*
G01X391428Y981662D02*
X391429Y981661D01*
Y979552D01*
G01X391428Y975253D02*
Y973144D01*
X391429Y973143D01*
G01X400679Y972049D02*
Y969940D01*
X400678Y969939D01*
G01X400679Y984866D02*
X400678Y984865D01*
Y982756D01*
G01X391861Y997574D02*
Y999683D01*
X391862Y999684D01*
G01X397412Y1007187D02*
Y1009297D01*
G01Y1000778D02*
Y1002886D01*
G03X397411Y1002888I-3J0D01*
G01X395561Y1003983D02*
Y1006092D01*
X395562Y1006093D01*
G01X391861Y1003983D02*
Y1006092D01*
X391862Y1006093D01*
G01X388161Y1003983D02*
Y1006093D01*
G01X401112Y1000778D02*
Y1002886D01*
G03X401111Y1002888I-3J0D01*
G01X399261Y1010391D02*
X399262Y1010392D01*
Y1012501D01*
G01X391861D02*
Y1010391D01*
G01X393712Y1013595D02*
Y1015704D01*
X393711Y1015705D01*
G01X390012Y1013595D02*
Y1015705D01*
G01X391861Y1023208D02*
Y1025317D01*
X391862Y1025318D01*
G01X391861Y1016800D02*
Y1018909D01*
X391862Y1018910D01*
G01X388161Y1023208D02*
Y1025318D01*
G01X391861Y1042434D02*
Y1044543D01*
X391862Y1044544D01*
G01X391861Y1036026D02*
G02X391862Y1038136I2226050J0D01*
G01X388161Y1042434D02*
Y1044544D01*
G01X399261Y1055251D02*
Y1057361D01*
G01X397412Y1058455D02*
X397411Y1058456D01*
Y1060565D01*
G01X391861Y1055251D02*
X391862Y1055252D01*
Y1057361D01*
G01X391861Y1048842D02*
G02X391862Y1050952I2226050J0D01*
G01X395561Y1061660D02*
Y1063769D01*
X395562Y1063770D01*
G01X391861Y1061660D02*
X391862Y1061661D01*
Y1063770D01*
G01X388161Y1061660D02*
Y1063770D01*
G01X399261Y1074477D02*
Y1076587D01*
G01Y1068068D02*
X399262Y1068069D01*
Y1070178D01*
G01X397412Y1064864D02*
Y1066974D01*
G01X391861Y1074477D02*
G02X391862Y1076587I2226050J0D01*
G01X391861Y1068068D02*
X391862Y1068069D01*
Y1070178D01*
G01X401112Y1071273D02*
Y1073382D01*
X401111Y1073383D01*
G01X391861Y1087294D02*
Y1089403D01*
X391862Y1089404D01*
G01X391861Y1080885D02*
G02X391862Y1082995I2226050J0D01*
G01X388161Y1080885D02*
Y1082995D01*
G01X399261Y1093703D02*
Y1095813D01*
G01X391861Y1093703D02*
Y1095812D01*
X391862Y1095813D01*
G01X399261Y1100111D02*
Y1102220D01*
X399262Y1102221D01*
G01X397412Y1096907D02*
Y1099017D01*
G01X401112Y1103316D02*
Y1105425D01*
X401111Y1105426D01*
G01X397412Y1109724D02*
X397411Y1111834D01*
G01X390012Y1109724D02*
X390011Y1111834D01*
G01X388161Y1112929D02*
Y1115039D01*
G01X395561Y1125746D02*
Y1127856D01*
G01X388161Y1125746D02*
Y1127856D01*
G01X402961Y1125746D02*
Y1127856D01*
G01X395561Y1138563D02*
Y1140973D01*
G01X388161Y1138563D02*
Y1140973D01*
G01X402961Y1138563D02*
Y1140973D01*
G01X401719Y1312326D02*
X400910Y1311517D01*
X399935D01*
G01X404560Y1315713D02*
X403404D01*
X401719Y1314028D01*
Y1312326D01*
G01X399935Y1317092D02*
Y1314667D01*
G01X404560Y1317485D02*
X403113D01*
X400295Y1314667D01*
X399935D01*
G01Y1319592D02*
Y1322017D01*
G01X404560Y1319256D02*
X403032D01*
X400271Y1322017D01*
X399935D01*
G01X404379Y856694D02*
Y854584D01*
G01X411779Y856694D02*
Y854584D01*
G01X419179Y856694D02*
Y854584D01*
G01X404379Y869511D02*
Y867401D01*
G01X411779Y869511D02*
Y867401D01*
G01X419179Y869511D02*
Y867401D01*
G01X404379Y882329D02*
Y880219D01*
G01X411779Y882329D02*
Y880219D01*
G01X409928Y872716D02*
Y870607D01*
X409929Y870606D01*
G01X419179Y882329D02*
Y880219D01*
G01X408079Y875920D02*
Y873811D01*
X408078Y873810D01*
G01X419179Y895146D02*
Y893036D01*
G01X413628Y904759D02*
X413629Y904758D01*
Y902649D01*
G01X409928Y911167D02*
X409929Y911166D01*
Y909057D01*
G01X409928Y904759D02*
X409929Y904758D01*
Y902649D01*
G01X404379Y907963D02*
X404378Y907962D01*
Y905853D01*
G01X419179Y907963D02*
Y905853D01*
G01X417328Y904759D02*
X417329Y904758D01*
Y902649D01*
G01X411779Y907963D02*
X411778Y907962D01*
Y905853D01*
G01X408079Y907963D02*
X408078Y907962D01*
Y905853D01*
G01X404379Y920780D02*
X404378Y920779D01*
Y918670D01*
G01X419179Y920780D02*
X419178Y920779D01*
Y918670D01*
G01X404812Y1058455D02*
X404811Y1058456D01*
Y1060565D01*
G01X410361Y1074477D02*
Y1076586D01*
X410362Y1076587D01*
G01X410361Y1068068D02*
X410362Y1068069D01*
Y1070178D01*
G01X406661Y1074477D02*
Y1076587D01*
G01X404812Y1064864D02*
X404811Y1064865D01*
Y1066974D01*
G01X419612Y1071273D02*
Y1073382D01*
X419611Y1073383D01*
G01X412212Y1077681D02*
Y1079790D01*
X412211Y1079791D01*
G01X404812Y1077681D02*
Y1079790D01*
X404811Y1079791D01*
G01X415912Y1090498D02*
Y1092606D01*
X415911Y1092607D01*
Y1092608D01*
G01X415912Y1084090D02*
Y1086200D01*
G01X412212Y1090498D02*
Y1092606D01*
X412211Y1092607D01*
Y1092608D01*
G01X408512Y1084090D02*
Y1086199D01*
X408511Y1086200D01*
G01X417761Y1087294D02*
Y1089404D01*
G01X410361Y1093703D02*
Y1095812D01*
X410362Y1095813D01*
G01X414061Y1106520D02*
X414062Y1108630D01*
G01X412212Y1096907D02*
Y1099016D01*
X412211Y1099017D01*
G01X410361Y1100111D02*
Y1102220D01*
X410362Y1102221D01*
G01X406661Y1106520D02*
Y1108630D01*
G01Y1100111D02*
Y1102221D01*
G01X404812Y1103316D02*
Y1105426D01*
G01Y1109724D02*
Y1111834D01*
G01X410361Y1112929D02*
Y1115039D01*
G01X406661Y1112929D02*
Y1115039D01*
G01X415912Y1122541D02*
Y1124651D01*
G01X419612Y1122541D02*
Y1124651D01*
G01X417761Y1119337D02*
Y1121447D01*
G01Y1125746D02*
Y1127856D01*
G01X414061Y1125746D02*
Y1126675D01*
X414062Y1127856D01*
G01X415912Y1135359D02*
Y1137469D01*
G01Y1128950D02*
Y1131060D01*
G01X414061Y1138563D02*
Y1140973D01*
G01X419612Y1135359D02*
Y1137469D01*
G01Y1128950D02*
Y1131060D01*
G01X417761Y1132154D02*
Y1134264D01*
G01Y1138563D02*
Y1140973D01*
G01X412212Y1135359D02*
Y1137469D01*
G01X417104Y1329843D02*
X416804Y1329543D01*
Y1325260D01*
G01X421224Y1332993D02*
X417104D01*
G01X421224Y1329843D02*
X418576Y1327195D01*
Y1325260D01*
G01X426579Y856694D02*
Y854584D01*
G01X433979Y856694D02*
Y854584D01*
G01X426579Y869511D02*
Y867401D01*
G01X433979Y869511D02*
Y867401D01*
G01X430279Y863103D02*
Y860994D01*
X430278Y860993D01*
G01X426579Y882329D02*
Y880219D01*
G01X433979Y882329D02*
Y880219D01*
G01X426579Y895146D02*
Y893036D01*
G01X433979Y895146D02*
Y893036D01*
G01X422879Y901555D02*
Y899446D01*
X422878Y899445D01*
G01X424728Y904759D02*
X424729Y904758D01*
Y902649D01*
G01X432128Y904759D02*
X432129Y904758D01*
Y902649D01*
G01X428428Y911167D02*
X428429Y911166D01*
Y909057D01*
G01X428428Y904759D02*
X428429Y904758D01*
Y902649D01*
G01X421028Y904759D02*
X421029Y904758D01*
Y902649D01*
G01X435829Y904759D02*
Y902649D01*
G01Y943210D02*
Y941102D01*
X435830Y941101D01*
G01X432128Y949619D02*
Y947511D01*
X432129Y947510D01*
G01X430279Y946414D02*
Y944306D01*
X430280Y944305D01*
G01X432561Y1029617D02*
Y1031727D01*
X432562Y1031728D01*
G01X430711Y1026413D02*
Y1028523D01*
X430712Y1028524D01*
G01X430711Y1039230D02*
Y1041340D01*
G01X434412Y1039230D02*
Y1041340D01*
G01X432561Y1042434D02*
Y1044544D01*
G01Y1036026D02*
X432562Y1036027D01*
Y1038137D01*
G01X430711Y1032821D02*
Y1034931D01*
X430712Y1034932D01*
G01X430711Y1071273D02*
Y1073383D01*
G01X427012Y1071273D02*
Y1073382D01*
X427011Y1073383D01*
G01X427012Y1064864D02*
Y1066973D01*
X427011Y1066974D01*
G01X425161Y1074477D02*
Y1076586D01*
X425162Y1076587D01*
G01X423312Y1064864D02*
Y1066973D01*
X423311Y1066974D01*
G01X427012Y1077681D02*
Y1079791D01*
G01X425161Y1087294D02*
Y1089403D01*
X425162Y1089404D01*
G01X428861Y1106520D02*
Y1108630D01*
G01X427012Y1103316D02*
Y1105426D01*
G01X430711Y1103316D02*
Y1105426D01*
G01Y1096907D02*
Y1099017D01*
G01X428861Y1100111D02*
Y1102221D01*
G01X432561Y1106520D02*
Y1108630D01*
G01Y1100111D02*
Y1102221D01*
G01X430711Y1109724D02*
Y1111834D01*
G01X427012Y1109724D02*
Y1111834D01*
G01X425161Y1106520D02*
Y1108629D01*
X425162Y1108630D01*
G01X430711Y1122541D02*
Y1124651D01*
G01X428861Y1119337D02*
Y1121447D01*
G01X427012Y1122541D02*
Y1124651D01*
G01X421461Y1119337D02*
Y1121447D01*
G01X430711Y1116133D02*
Y1118243D01*
G01X428861Y1112929D02*
Y1115039D01*
G01X427012Y1116133D02*
Y1118243D01*
G01X432561Y1119337D02*
Y1121447D01*
G01Y1112929D02*
Y1115039D01*
G01X428861Y1125746D02*
Y1127856D01*
G01X421461Y1125746D02*
Y1127856D01*
G01X432561Y1125746D02*
Y1127856D01*
G01X425161Y1125746D02*
Y1127855D01*
X425162Y1127856D01*
G01X425161Y1119337D02*
Y1121446D01*
X425162Y1121447D01*
G01X425161Y1112929D02*
Y1115038D01*
X425162Y1115039D01*
G01X427012Y1135359D02*
Y1137569D01*
G01X430711Y1128950D02*
Y1131060D01*
G01X428861Y1132154D02*
Y1134264D01*
G01X427012Y1128950D02*
Y1131060D01*
G01X421461Y1132154D02*
Y1134264D01*
G01X428861Y1138563D02*
Y1140973D01*
G01X425161Y1138563D02*
Y1140973D01*
G01X421461Y1138563D02*
Y1140973D01*
G01X432561Y1132154D02*
Y1134264D01*
G01X425161Y1132154D02*
Y1134263D01*
X425162Y1134264D01*
G01X436688Y1315713D02*
X435532D01*
X433847Y1314028D01*
Y1312326D01*
G01X432063Y1317092D02*
Y1314667D01*
G01D02*
X432423D01*
X435241Y1317485D01*
X436688D01*
G01X432063Y1322017D02*
X432399D01*
X435160Y1319256D01*
X436688D01*
G01X432063Y1319592D02*
Y1322017D01*
G01X432500Y1613822D02*
X435100Y1616422D01*
Y1618242D01*
G01X432640Y1626608D02*
X430015D01*
G01X433670Y1639562D02*
X435100Y1638132D01*
Y1636942D01*
G01X445079Y850286D02*
Y848177D01*
X445078Y848176D01*
G01X441379Y850286D02*
Y848177D01*
X441378Y848176D01*
G01X441379Y856694D02*
Y854584D01*
G01X439528Y859899D02*
Y857789D01*
G01X437679Y863103D02*
Y860994D01*
X437680Y860993D01*
Y860992D01*
G01X448779Y869511D02*
Y867401D01*
G01X441379Y869511D02*
Y867401D01*
G01X448779Y880219D02*
Y882329D01*
G01X441379D02*
Y880219D01*
G01X448779Y895146D02*
Y893036D01*
G01X441379Y895146D02*
Y893036D01*
G01X439528Y898350D02*
X439529Y898349D01*
Y896240D01*
G01X437679Y899445D02*
Y901555D01*
G01X446928Y911167D02*
X446929Y911166D01*
Y909057D01*
G01X446928Y904759D02*
X446929Y904758D01*
Y902649D01*
G01X443228Y904759D02*
X443229Y904758D01*
Y902649D01*
G01X439528Y904759D02*
Y902649D01*
G01X437679Y907963D02*
Y905853D01*
G01X450629Y904759D02*
Y902649D01*
G01X437679Y920780D02*
X437678Y920779D01*
Y918670D01*
G01X445079Y946414D02*
Y944305D01*
G01X450629Y949619D02*
Y947511D01*
X450630Y947510D01*
G01X450629Y943210D02*
Y941102D01*
X450630Y941101D01*
G01X448779Y946414D02*
Y944306D01*
X448780Y944305D01*
G01X443228Y949619D02*
Y947511D01*
X443229Y947510D01*
G01X443228Y943210D02*
Y941103D01*
X443230Y941101D01*
G01X441379Y946414D02*
Y944306D01*
X441380Y944305D01*
G01X439528Y949619D02*
Y947511D01*
X439529Y947510D01*
G01X439528Y943210D02*
Y941103D01*
X439530Y941101D01*
G01X437679Y946414D02*
Y944306D01*
X437680Y944305D01*
G01X445079Y952823D02*
Y950714D01*
G01X448779Y952823D02*
Y950715D01*
X448780Y950714D01*
G01X441379Y952823D02*
Y950715D01*
X441380Y950714D01*
G01X437679Y952823D02*
Y950715D01*
X437680Y950714D01*
G01X445511Y1026413D02*
Y1028524D01*
G01X451061Y1029617D02*
Y1031727D01*
X451062Y1031728D01*
G01X451061Y1023208D02*
Y1025318D01*
X451062Y1025319D01*
G01X449212Y1026413D02*
Y1028523D01*
X449213Y1028524D01*
G01X443661Y1029617D02*
Y1031727D01*
X443662Y1031728D01*
G01X441812Y1026413D02*
Y1028523D01*
X441813Y1028524D01*
G01X439961Y1029617D02*
Y1031727D01*
X439962Y1031728D01*
G01X438112Y1026413D02*
Y1028523D01*
X438113Y1028524D01*
G01X436261Y1029617D02*
Y1031726D01*
X436263Y1031728D01*
G01X445511Y1045639D02*
Y1045638D01*
G01X441812D02*
Y1045639D01*
G01X438112Y1045638D02*
Y1045639D01*
G01X436261Y1042434D02*
Y1044544D01*
G01X438112Y1039230D02*
Y1041340D01*
G01X439961Y1042434D02*
Y1044544D01*
G01X441812Y1039230D02*
Y1041340D01*
G01X443661Y1042434D02*
Y1044544D01*
G01X447361Y1042434D02*
Y1044544D01*
G01X445511Y1039230D02*
Y1041340D01*
G01X441812Y1045639D02*
Y1047749D01*
G01X438112Y1045639D02*
Y1047749D01*
G01X451061Y1036026D02*
X451062Y1036027D01*
Y1038137D01*
G01X449212Y1039230D02*
Y1041339D01*
X449211Y1041340D01*
G01X449212Y1032821D02*
Y1034931D01*
X449213Y1034932D01*
G01X445511Y1045639D02*
Y1047748D01*
X445510Y1047749D01*
G01X445511Y1032821D02*
Y1034931D01*
X445512Y1034932D01*
G01X443661Y1036026D02*
X443662Y1036027D01*
Y1038137D01*
G01X441812Y1032821D02*
Y1034931D01*
X441813Y1034932D01*
G01X439961Y1036026D02*
X439962Y1036027D01*
Y1038137D01*
G01X438112Y1032821D02*
Y1034931D01*
X438113Y1034932D01*
G01X436261Y1036026D02*
X436262Y1036027D01*
Y1038137D01*
G01X438112Y1058455D02*
Y1060565D01*
G01Y1052047D02*
Y1054157D01*
G01X439961Y1055251D02*
Y1057361D01*
G01X441812Y1052047D02*
Y1054157D01*
G01Y1058455D02*
Y1060565D01*
G01X443661Y1055251D02*
Y1057361D01*
G01X445511Y1058455D02*
Y1060565D01*
G01Y1052047D02*
Y1054157D01*
G01X439961Y1048842D02*
Y1050952D01*
G01X443661Y1048842D02*
Y1050952D01*
G01X439961Y1061660D02*
Y1063770D01*
G01X443661Y1061660D02*
Y1063770D01*
G01X436261Y1061660D02*
Y1063769D01*
X436262Y1063770D01*
G01X436261Y1055251D02*
Y1057360D01*
X436262Y1057361D01*
G01X436261Y1048842D02*
Y1050951D01*
X436262Y1050952D01*
G01X449212Y1071273D02*
X449211Y1073383D01*
G01X439961Y1074477D02*
Y1076587D01*
G01Y1068068D02*
Y1070178D01*
G01X441812Y1071273D02*
Y1073383D01*
G01X438112Y1071273D02*
Y1073383D01*
G01X443661Y1068068D02*
Y1070178D01*
G01Y1074477D02*
Y1076587D01*
G01X445511Y1071273D02*
Y1073383D01*
G01X441812Y1064864D02*
Y1066974D01*
G01X438112Y1064864D02*
Y1066974D01*
G01X445511Y1064864D02*
Y1066974D01*
G01X441812Y1077681D02*
Y1079791D01*
G01X438112Y1077681D02*
Y1079791D01*
G01X445511Y1077681D02*
Y1079791D01*
G01X436261Y1074477D02*
Y1076586D01*
X436262Y1076587D01*
G01X436261Y1068068D02*
Y1070177D01*
X436262Y1070178D01*
G01X443661Y1080885D02*
Y1082995D01*
G01X439961Y1080885D02*
Y1082995D01*
G01X441812Y1084090D02*
Y1086200D01*
G01X445511Y1084090D02*
Y1086200D01*
G01X439961Y1087294D02*
Y1089404D01*
G01X441812Y1090498D02*
Y1092608D01*
G01X438112Y1090498D02*
Y1092608D01*
G01X443661Y1087294D02*
Y1089404D01*
G01X445511Y1090498D02*
Y1092608D01*
G01X447361Y1087294D02*
Y1089404D01*
G01X438112Y1084090D02*
Y1086200D01*
G01X439961Y1093703D02*
Y1095813D01*
G01X443661Y1093703D02*
Y1095813D01*
G01X436261Y1093703D02*
Y1095813D01*
G01X449212Y1090498D02*
Y1092607D01*
X449211Y1092608D01*
G01X436261Y1087294D02*
Y1089403D01*
X436262Y1089404D01*
G01X436261Y1080885D02*
Y1082994D01*
X436262Y1082995D01*
G01X441812Y1103316D02*
Y1105426D01*
G01X438112Y1103316D02*
Y1105426D01*
G01X439961Y1106520D02*
Y1108630D01*
G01X443661Y1106520D02*
Y1108630D01*
G01X445511Y1103316D02*
Y1105426D01*
G01X439961Y1100111D02*
Y1102221D01*
G01X441812Y1096907D02*
Y1099017D01*
G01X438112Y1096907D02*
Y1099017D01*
G01X443661Y1100111D02*
Y1102221D01*
G01X445511Y1096907D02*
Y1099017D01*
G01X451061Y1106520D02*
Y1108630D01*
G01X449212Y1103316D02*
Y1105426D01*
G01X451061Y1100111D02*
Y1102221D01*
G01X449212Y1096907D02*
Y1099017D01*
G01X441812Y1109724D02*
Y1111834D01*
G01X438112Y1109724D02*
Y1111834D01*
G01X445511Y1109724D02*
Y1111834D01*
G01X449212Y1109724D02*
Y1111834D01*
G01X436261Y1106520D02*
Y1108629D01*
X436262Y1108630D01*
G01X436261Y1100111D02*
Y1102220D01*
X436262Y1102221D01*
G01X438112Y1122541D02*
Y1124651D01*
G01X439961Y1119337D02*
Y1121447D01*
G01X441812Y1122541D02*
Y1124651D01*
G01X445511Y1122541D02*
Y1124651D01*
G01X443661Y1119337D02*
Y1121447D01*
G01X438112Y1116133D02*
Y1118243D01*
G01X441812Y1116133D02*
Y1118243D01*
G01X439961Y1112929D02*
Y1115039D01*
G01X445511Y1116133D02*
Y1118243D01*
G01X443661Y1112929D02*
Y1115039D01*
G01X451061Y1119337D02*
Y1121447D01*
G01X449212Y1122541D02*
Y1124651D01*
G01Y1116133D02*
Y1118243D01*
G01X451061Y1112929D02*
Y1115039D01*
G01X439961Y1125746D02*
Y1127856D01*
G01X443661Y1125746D02*
Y1127856D01*
G01X451061Y1125746D02*
Y1127856D01*
G01X436261Y1125746D02*
Y1127855D01*
X436262Y1127856D01*
G01X436261Y1119337D02*
Y1121446D01*
X436262Y1121447D01*
G01X436261Y1112929D02*
Y1115038D01*
X436262Y1115039D01*
G01X441812Y1135359D02*
Y1137769D01*
G01X438112Y1135359D02*
Y1137769D01*
G01X445511Y1135359D02*
Y1137769D01*
G01X443661Y1132154D02*
Y1134264D01*
G01X441812Y1128950D02*
Y1131060D01*
G01X439961Y1132154D02*
Y1134264D01*
G01X438112Y1128950D02*
Y1131060D01*
G01X436261Y1132154D02*
Y1134264D01*
G01X445511Y1128950D02*
Y1131060D01*
G01X449212Y1135359D02*
Y1137769D01*
G01Y1128950D02*
Y1131060D01*
G01X451061Y1132154D02*
Y1134264D01*
G01X448873Y1329843D02*
X448932Y1329784D01*
Y1325260D01*
G01X452961Y1332985D02*
X452953Y1332993D01*
X448873D01*
G01X452961Y1329835D02*
Y1329754D01*
X450704Y1327497D01*
Y1325260D01*
G01X442974Y1618242D02*
Y1615615D01*
G01X448181Y1614401D02*
X446911Y1615671D01*
Y1618242D01*
G01X455681Y1622492D02*
X454953D01*
X454774Y1622671D01*
X451340D01*
G01X444940Y1641842D02*
Y1641070D01*
X442974Y1639104D01*
Y1636942D01*
G01X452479Y850286D02*
X452478Y850285D01*
Y848176D01*
G01X456179Y869511D02*
Y867401D01*
G01X463579Y869511D02*
Y867401D01*
G01X456179Y882329D02*
Y880219D01*
G01X463579D02*
Y882329D01*
G01X456179Y895146D02*
Y893036D01*
G01X463579Y895146D02*
Y893036D01*
G01X461728Y904759D02*
X461729Y904758D01*
Y902649D01*
G01X456179Y914372D02*
X456178Y914371D01*
Y912262D01*
G01X454328Y904759D02*
X454329Y904758D01*
Y902649D01*
G01X465428Y911167D02*
X465429Y911166D01*
Y909057D01*
G01X456179Y920780D02*
X456178Y920779D01*
Y918670D01*
G01X460312Y1039230D02*
Y1041338D01*
X460311Y1041339D01*
Y1041340D01*
G01X452912Y1058455D02*
X452911Y1060565D01*
G01X456612Y1052047D02*
X456611Y1054157D01*
G01X462161Y1048842D02*
X462162Y1050952D01*
G01X458461Y1061660D02*
X458462Y1063653D01*
Y1063770D01*
G01X456612Y1071273D02*
X456611Y1073383D01*
G01X454761Y1068068D02*
X454762Y1070178D01*
G01X462161Y1068068D02*
X462162Y1070178D01*
G01X467712Y1071273D02*
X467711Y1073383D01*
G01X456612Y1084090D02*
X456611Y1086200D01*
G01X460312Y1090498D02*
X460311Y1092608D01*
G01X458461Y1106520D02*
Y1108630D01*
G01X456612Y1103316D02*
Y1105426D01*
G01X454761Y1106520D02*
Y1108630D01*
G01X452912Y1103316D02*
Y1105426D01*
G01X454761Y1100111D02*
Y1102221D01*
G01X460312Y1109724D02*
Y1111834D01*
G01X452912Y1109724D02*
Y1111834D01*
G01X456612Y1109724D02*
Y1111833D01*
X456611Y1111834D01*
G01X464012Y1122541D02*
Y1124651D01*
G01X462161Y1119337D02*
Y1121447D01*
G01X460312Y1122541D02*
Y1124651D01*
G01X454761Y1119337D02*
Y1121447D01*
G01X452912Y1122541D02*
Y1124651D01*
G01X462161Y1112929D02*
Y1115039D01*
G01X460312Y1116133D02*
Y1118243D01*
G01X454761Y1112929D02*
Y1115039D01*
G01X452912Y1116133D02*
Y1118243D01*
G01X462161Y1125746D02*
Y1127856D01*
G01X454761Y1125746D02*
Y1127856D01*
G01X465861Y1125746D02*
Y1127856D01*
G01X464012Y1116133D02*
Y1118242D01*
X464011Y1118243D01*
G01X456612Y1122541D02*
Y1124650D01*
X456611Y1124651D01*
G01X456612Y1116133D02*
Y1118242D01*
X456611Y1118243D01*
G01X464012Y1135359D02*
Y1137469D01*
G01X460312Y1135359D02*
Y1137469D01*
G01X456612Y1135359D02*
Y1137469D01*
G01X452912Y1135359D02*
Y1137769D01*
G01X464012Y1128950D02*
Y1131060D01*
G01X462161Y1132154D02*
Y1134264D01*
G01X460312Y1128950D02*
Y1131060D01*
G01X454761Y1132154D02*
Y1134264D01*
G01X452912Y1128950D02*
Y1131060D01*
G01X462161Y1138563D02*
Y1140973D01*
G01X458461Y1138563D02*
Y1140973D01*
G01X454761Y1138563D02*
Y1140973D01*
G01X467712Y1135359D02*
Y1137469D01*
G01X465861Y1132154D02*
Y1134264D01*
G01X467712Y1128950D02*
Y1131060D01*
G01X465861Y1138563D02*
Y1140973D01*
G01X456612Y1128950D02*
Y1131059D01*
X456611Y1131060D01*
G01X468816Y1315713D02*
X467660D01*
X465975Y1314028D01*
Y1312326D01*
G01X464191Y1317092D02*
Y1314667D01*
G01D02*
X464551D01*
X467369Y1317485D01*
X468816D01*
G01X464191Y1322017D02*
X464527D01*
X467288Y1319256D01*
X468816D01*
G01X464191Y1319592D02*
Y1322017D01*
G01X478379Y869511D02*
Y867401D01*
G01X470979Y869511D02*
Y867401D01*
G01X478379Y882329D02*
Y880219D01*
G01X470979Y882329D02*
Y880219D01*
G01X480228Y898350D02*
Y896240D01*
G01X478379Y895146D02*
Y893036D01*
G01X470979Y895146D02*
Y893036D01*
G01X474679Y914372D02*
X474678Y914371D01*
Y912262D01*
G01X483928Y930393D02*
X483929Y930392D01*
Y928283D01*
G01X482079Y933598D02*
Y931488D01*
G01X483928Y943210D02*
Y941100D01*
G01X482079Y940006D02*
X482078Y940005D01*
Y937896D01*
G01X478378Y944304D02*
Y946413D01*
G01D02*
X478379Y946414D01*
G01X483928Y962436D02*
Y960326D01*
G01Y968845D02*
X483929Y968844D01*
Y966735D01*
G01X482079Y972049D02*
Y969939D01*
G01X483928Y981662D02*
Y979552D01*
G01X482079Y978457D02*
X482078Y978456D01*
Y976347D01*
G01X484361Y997574D02*
Y999684D01*
G01X482078Y982756D02*
X482079Y982757D01*
Y984866D01*
G01X482512Y1007187D02*
Y1009297D01*
G01X484361Y1010391D02*
Y1011053D01*
X484362Y1012501D01*
G01X482512Y1026413D02*
Y1028522D01*
X482511Y1028523D01*
G01X484361Y1029617D02*
Y1031727D01*
G01X475112Y1039230D02*
Y1041338D01*
X475111Y1041339D01*
Y1041340D01*
G01X482512Y1039230D02*
Y1041338D01*
X482511Y1041339D01*
Y1041340D01*
G01X482512Y1032821D02*
Y1034931D01*
G01X484361Y1036026D02*
Y1038136D01*
G01X475112Y1064864D02*
X475111Y1066974D01*
G01X473261Y1068068D02*
X473262Y1070178D01*
G01X478812Y1071273D02*
X478811Y1073383D01*
G01X484361Y1074477D02*
Y1076587D01*
G01Y1068068D02*
X484362Y1070178D01*
G01X478812Y1077681D02*
Y1079791D01*
G01X475112Y1077681D02*
X475111Y1079791D01*
G01X482512Y1077681D02*
X482511Y1079791D01*
G01X480661Y1080885D02*
X480662Y1082995D01*
G01X476961Y1087294D02*
X476962Y1089404D01*
G01X469561Y1087294D02*
Y1089404D01*
G01X484361Y1087294D02*
X484362Y1089404D01*
G01X480661Y1093703D02*
Y1095813D01*
G01X484361Y1093703D02*
X484362Y1095813D01*
G01X478812Y1096907D02*
X478811Y1099017D01*
G01X473261Y1106520D02*
X473262Y1108630D01*
G01X482512Y1103316D02*
X482511Y1105426D01*
G01X484361Y1125746D02*
Y1127856D01*
G01X476961Y1138563D02*
Y1140973D01*
G01X484361Y1138563D02*
Y1140973D01*
G01X469561Y1132154D02*
Y1134264D01*
G01X481254Y1329835D02*
Y1328411D01*
X481060Y1328217D01*
Y1325260D01*
G01X485296Y1332985D02*
X481254D01*
G01X485296Y1329835D02*
X482832Y1327371D01*
Y1325260D01*
G01X493179Y869511D02*
Y867401D01*
G01X485779Y869511D02*
Y867401D01*
G01X500579Y869511D02*
Y867401D01*
G01X493179Y882329D02*
Y880219D01*
G01X485779Y882329D02*
Y880219D01*
G01X500579Y882329D02*
Y880219D01*
G01X489479Y895146D02*
Y893036D01*
G01X500579Y895146D02*
Y893036D01*
G01X498728Y898350D02*
X498729Y898349D01*
Y896240D01*
G01X496879Y899445D02*
Y901555D01*
G01Y914372D02*
X496878Y914371D01*
Y912262D01*
G01X495028Y911167D02*
X495029Y911166D01*
Y909057D01*
G01X489479Y907963D02*
Y905854D01*
X489478Y905853D01*
G01X495028Y904759D02*
X495029Y904758D01*
Y902649D01*
G01X493179Y907963D02*
Y905853D01*
G01X498728Y917576D02*
Y915466D01*
G01X495028Y930393D02*
Y928283D01*
G01X493179Y927189D02*
Y925079D01*
G01X489479Y927189D02*
X489478Y927188D01*
Y925079D01*
G01X485779Y927189D02*
X485778Y927188D01*
Y925079D01*
G01X496879Y920780D02*
Y918670D01*
G01X495028Y923985D02*
X495029Y923984D01*
Y921875D01*
G01X496879Y940006D02*
Y937896D01*
G01X495028Y943210D02*
X495029Y943209D01*
Y941100D01*
G01X493179Y946414D02*
Y944304D01*
G01X489479Y946414D02*
X489478Y946413D01*
Y944304D01*
G01X489479Y940006D02*
X489478Y940005D01*
Y937896D01*
G01X485779Y946414D02*
X485778Y946413D01*
Y944304D01*
G01X495028Y949619D02*
Y947509D01*
G01X496879Y959232D02*
Y957122D01*
G01X495028Y962436D02*
X495029Y962435D01*
Y960326D01*
G01X489479Y959232D02*
X489478Y959231D01*
Y957122D01*
G01X489479Y952823D02*
X489478Y952822D01*
Y950713D01*
G01X496879Y952823D02*
X496878Y952822D01*
Y950713D01*
G01X498728Y956027D02*
Y953918D01*
X498729Y953917D01*
G01X493179Y965640D02*
Y963530D01*
G01X485779Y965640D02*
X485778Y965639D01*
Y963530D01*
G01X489479Y965640D02*
X489478Y965639D01*
Y963530D01*
G01X500579Y965640D02*
Y963530D01*
G01X495028Y968845D02*
Y966735D01*
G01X496879Y978457D02*
Y976347D01*
G01Y972049D02*
X496878Y972048D01*
Y969939D01*
G01X489479Y978457D02*
X489478Y978456D01*
Y976347D01*
G01X489479Y972049D02*
X489478Y972048D01*
Y969939D01*
G01X495028Y981662D02*
X495029Y981661D01*
Y979552D01*
G01X498728Y975253D02*
Y973143D01*
G01X493179Y984866D02*
Y982756D01*
G01X489479Y984866D02*
X489478Y984865D01*
Y982756D01*
G01X485779Y984866D02*
X485778Y984865D01*
Y982756D01*
G01X495461Y997574D02*
Y999683D01*
X495462Y999684D01*
G01X497312Y1000778D02*
Y1002888D01*
G01X489912Y1000778D02*
Y1002888D01*
G01X491761Y1003983D02*
Y1006093D01*
G01X488061Y1003983D02*
Y1006092D01*
X488062Y1006093D01*
G01X499161Y1003983D02*
Y1006093D01*
G01X495461Y1012501D02*
Y1010391D01*
G01X489912Y1013595D02*
X489911Y1015705D01*
G01X493612Y1013595D02*
Y1015705D01*
G01X486212Y1013595D02*
X486211Y1015705D01*
G01X497312Y1026413D02*
Y1028522D01*
X497311Y1028523D01*
G01X489912Y1026413D02*
Y1028522D01*
X489911Y1028523D01*
G01X489912Y1020004D02*
Y1020053D01*
X489911Y1022114D01*
G01X497312Y1020004D02*
Y1020053D01*
X497311Y1022114D01*
G01X495461Y1016800D02*
Y1018909D01*
X495462Y1018910D01*
G01X499161Y1023208D02*
Y1025318D01*
G01X495461Y1029617D02*
Y1031727D01*
G01X497312Y1039230D02*
Y1041340D01*
G01X489912Y1039230D02*
Y1041338D01*
X489911Y1041339D01*
Y1041340D01*
G01X495461Y1036026D02*
Y1038135D01*
X495462Y1038136D01*
G01X493612Y1032821D02*
Y1034931D01*
G01X499161Y1042434D02*
Y1044544D01*
G01X497312Y1058455D02*
X497311Y1060565D01*
G01X495461Y1055251D02*
X495462Y1057361D01*
G01X489912Y1052047D02*
X489911Y1054157D01*
G01X495461Y1048842D02*
Y1050952D01*
G01X493612Y1052047D02*
X493611Y1054157D01*
G01X499161Y1061660D02*
X499162Y1063653D01*
Y1063770D01*
G01X495461Y1074477D02*
X495462Y1076587D01*
G01X493612Y1071273D02*
Y1073383D01*
G01X489912Y1064864D02*
X489911Y1066974D01*
G01X486212Y1071273D02*
X486211Y1073383D01*
G01X497312Y1064864D02*
X497311Y1066974D01*
G01X495461Y1068068D02*
Y1070178D01*
G01X489912Y1071273D02*
X489911Y1073383D01*
G01X497312Y1077681D02*
Y1079791D01*
G01Y1084090D02*
X497311Y1086200D01*
G01X493612Y1090498D02*
Y1092608D01*
G01X489912Y1090498D02*
X489911Y1092608D01*
G01X489912Y1084090D02*
X489911Y1086200D01*
G01X486212Y1090498D02*
X486211Y1092608D01*
G01X495461Y1087294D02*
Y1089404D01*
G01X499161Y1080885D02*
Y1082995D01*
G01X495461Y1093703D02*
X495462Y1095813D01*
G01X499161Y1093703D02*
X499162Y1095813D01*
G01X497312Y1103316D02*
Y1105426D01*
G01X493612Y1103316D02*
X493611Y1105426D01*
G01X491761Y1100111D02*
X491762Y1102221D01*
G01X488061Y1100111D02*
Y1102221D01*
G01X486212Y1103316D02*
X486211Y1105426D01*
G01X486212Y1096907D02*
Y1099017D01*
G01X499161Y1106520D02*
Y1108630D01*
G01Y1100111D02*
Y1102221D01*
G01X489912Y1109724D02*
X489911Y1111834D01*
G01X491761Y1138563D02*
Y1140973D01*
G01X499161Y1138563D02*
Y1140973D01*
G01X500944Y1329139D02*
X499788D01*
X498103Y1327454D01*
Y1325752D01*
G01X496319Y1330493D02*
Y1328093D01*
G01D02*
X496679D01*
X499497Y1330911D01*
X500944D01*
G01X496319Y1335443D02*
X496655D01*
X499416Y1332682D01*
X500944D01*
G01X496319Y1333043D02*
Y1335443D01*
G01X507979Y869511D02*
Y867401D01*
G01X515379Y869511D02*
Y867401D01*
G01X507979Y882329D02*
Y880219D01*
G01X515379Y882329D02*
Y880219D01*
G01X502428Y898350D02*
Y896240D01*
G01X506128Y898350D02*
Y896240D01*
G01X504279Y895146D02*
Y893036D01*
G01X515379Y895146D02*
Y893036D01*
G01X507979Y901555D02*
X507978Y901554D01*
Y899445D01*
G01X515379Y901555D02*
X515378Y901554D01*
Y899445D01*
G01X511679Y907963D02*
X511678Y907962D01*
Y905853D01*
G01X509828Y911167D02*
X509829Y911166D01*
Y909057D01*
G01X507979Y914372D02*
Y912262D01*
G01X502428Y911167D02*
X502429Y911166D01*
Y909057D01*
G01X502428Y904759D02*
X502429Y904758D01*
Y902649D01*
G01X509828Y904759D02*
Y902649D01*
G01X515379Y914372D02*
X515378Y914371D01*
Y912262D01*
G01X515379Y907963D02*
X515378Y907962D01*
Y905853D01*
G01X511679Y927189D02*
X511678Y927188D01*
Y925079D01*
G01X509828Y930393D02*
X509829Y930392D01*
Y928283D01*
G01X502428Y930393D02*
X502429Y930392D01*
Y928283D01*
G01X502428Y923985D02*
X502429Y923984D01*
Y921875D01*
G01X509828Y923985D02*
Y921875D01*
G01X507979Y920780D02*
X507978Y920779D01*
Y918670D01*
G01X515379Y927189D02*
X515378Y927188D01*
Y925079D01*
G01X515379Y920780D02*
X515378Y920779D01*
Y918670D01*
G01X507979Y933598D02*
Y931488D01*
G01X511679Y946414D02*
X511678Y946413D01*
Y944304D01*
G01X509828Y943210D02*
Y941100D01*
G01X507979Y940006D02*
X507978Y940005D01*
Y937896D01*
G01X502428Y943210D02*
X502429Y943209D01*
Y941100D01*
G01X515379Y946414D02*
X515378Y946413D01*
Y944304D01*
G01X515379Y940006D02*
X515378Y940005D01*
Y937896D01*
G01X509828Y949619D02*
X509829Y949618D01*
Y947509D01*
G01X502428Y949619D02*
X502429Y949618D01*
Y947509D01*
G01X509828Y962436D02*
Y960326D01*
G01X507979Y959232D02*
X507978Y959231D01*
Y957122D01*
G01X506128Y956027D02*
Y953918D01*
X506129Y953917D01*
G01X502428Y962436D02*
X502429Y962435D01*
Y960326D01*
G01X502428Y956027D02*
Y953918D01*
X502429Y953917D01*
G01X507979Y952823D02*
Y950713D01*
G01X515379Y959232D02*
X515378Y959231D01*
Y957122D01*
G01X515379Y952823D02*
X515378Y952822D01*
Y950713D01*
G01X511679Y965640D02*
X511678Y965639D01*
Y963530D01*
G01X504279Y965640D02*
X504278Y965639D01*
Y963530D01*
G01X515379Y965640D02*
X515378Y965639D01*
Y963530D01*
G01X509828Y968845D02*
X509829Y968844D01*
Y966735D01*
G01X502428Y968845D02*
Y966735D01*
G01X507979Y978457D02*
X507978Y978456D01*
Y976347D01*
G01X507979Y972049D02*
Y969939D01*
G01X502428Y981662D02*
X502429Y981661D01*
Y979552D01*
G01X502428Y975253D02*
X502429Y975252D01*
Y973143D01*
G01X513528Y975253D02*
X513529Y975252D01*
Y973143D01*
G01X509828Y981662D02*
Y979552D01*
G01X506128Y975253D02*
X506129Y975252D01*
Y973143D01*
G01X515379Y978457D02*
Y976347D01*
G01Y972049D02*
X515378Y972048D01*
Y969939D01*
G01X517228Y975253D02*
Y973143D01*
G01X511679Y984866D02*
X511678Y984865D01*
Y982756D01*
G01X515379Y984866D02*
X515378Y984865D01*
Y982756D01*
G01X510261Y997574D02*
Y999684D01*
G01X502861Y997574D02*
Y999683D01*
X502862Y999684D01*
G01X506561Y1003983D02*
Y1006092D01*
X506562Y1006093D01*
G01X502861Y1003983D02*
X506562Y1006093D01*
G01X502861Y1012501D02*
Y1010391D01*
G01X508412Y1007187D02*
Y1009297D01*
G01X510261Y1010391D02*
Y1011053D01*
X510262Y1012501D01*
G01X501012Y1013595D02*
Y1015705D01*
G01X504712Y1013595D02*
X504711Y1015705D01*
G01X515812Y1013595D02*
X515811Y1015705D01*
G01X512112Y1013595D02*
X512111Y1015705D01*
G01X508412Y1026413D02*
Y1028522D01*
X508411Y1028523D01*
G01X502861Y1016800D02*
Y1018909D01*
X502862Y1018910D01*
G01X510261Y1016800D02*
Y1018910D01*
G01X508412Y1020004D02*
Y1020053D01*
X508411Y1022114D01*
G01X506561Y1023208D02*
X506562Y1025318D01*
G01X515812Y1026413D02*
Y1028522D01*
X515811Y1028523D01*
G01X515812Y1020004D02*
Y1020053D01*
X515811Y1022114D01*
G01X502861Y1042434D02*
X502862Y1044544D01*
G01X502861Y1036026D02*
Y1038135D01*
X502862Y1038136D01*
G01X512112Y1032821D02*
X512111Y1034931D01*
G01X510261Y1036026D02*
Y1038136D01*
G01X508412Y1039230D02*
Y1041338D01*
X508411Y1041339D01*
Y1041340D01*
G01X506561Y1042434D02*
X506562Y1044544D01*
G01X515812Y1032821D02*
X515811Y1034931D01*
G01X515812Y1039230D02*
Y1041338D01*
X515811Y1041339D01*
Y1041340D01*
G01X510261Y1055251D02*
X510262Y1057361D01*
G01X508412Y1058455D02*
X508411Y1060565D01*
G01X502861Y1055251D02*
X502862Y1057361D01*
G01X502861Y1048842D02*
X502862Y1050952D01*
G01X510261Y1048842D02*
X510262Y1050952D01*
G01X515812Y1058455D02*
X515811Y1060565D01*
G01X502861Y1061660D02*
X502862Y1063653D01*
Y1063770D01*
G01X506561Y1061660D02*
X506562Y1063653D01*
Y1063770D01*
G01X510261Y1074477D02*
X510262Y1076587D01*
G01X510261Y1068068D02*
X510262Y1070178D01*
G01X502861Y1074477D02*
X502862Y1076587D01*
G01X502861Y1068068D02*
X502862Y1070178D01*
G01X512112Y1071273D02*
X512111Y1073383D01*
G01X508412Y1064864D02*
X508411Y1066974D01*
G01X515812Y1071273D02*
X515811Y1073383D01*
G01X515812Y1064864D02*
X515811Y1066974D01*
G01X508412Y1077681D02*
X508411Y1079791D01*
G01X515812Y1077681D02*
X515811Y1079791D01*
G01X512112Y1090498D02*
Y1092608D01*
G01X510261Y1087294D02*
X510262Y1089404D01*
G01X508412Y1084090D02*
Y1086200D01*
G01X506561Y1080885D02*
X506562Y1082995D01*
G01X502861Y1087294D02*
X502862Y1089404D01*
G01X502861Y1080885D02*
X502862Y1082995D01*
G01X515812Y1090498D02*
Y1092608D01*
G01Y1084090D02*
X515811Y1086200D01*
G01X513961Y1093703D02*
Y1095813D01*
G01X502861Y1093703D02*
X502862Y1095813D01*
G01X506561Y1106520D02*
X506562Y1108630D01*
G01X504712Y1096907D02*
X504711Y1099017D01*
G01X502861Y1100111D02*
X502862Y1102221D01*
G01X513961Y1112929D02*
Y1115039D01*
G01X510261Y1112929D02*
Y1115039D01*
G01X513961Y1125746D02*
Y1127856D01*
G01X506561Y1125746D02*
Y1127856D01*
G01X513961Y1138563D02*
Y1140973D01*
G01X506561Y1138563D02*
Y1140973D01*
G01X513382Y1343818D02*
Y1342040D01*
X513188Y1341846D01*
Y1338686D01*
G01X517424Y1343818D02*
X514960Y1341354D01*
Y1338686D01*
G01X517424Y1346968D02*
X513382D01*
G01X530179Y863103D02*
Y860993D01*
G01Y856694D02*
Y854584D01*
G01X522779Y856694D02*
Y854584D01*
G01X532028Y859899D02*
Y857789D01*
G01X530179Y869511D02*
Y867402D01*
X530178Y867401D01*
G01X522779Y869511D02*
Y867401D01*
G01Y882329D02*
Y880219D01*
G01X530179Y882329D02*
Y880219D01*
G01X528329Y898350D02*
Y896240D01*
G01X526479Y895146D02*
Y893036D01*
G01X524628Y898350D02*
X524629Y898349D01*
Y896240D01*
G01X532028Y898350D02*
X532029Y898349D01*
Y896240D01*
G01X522779Y899445D02*
Y901555D01*
G01X528329Y904759D02*
Y902649D01*
G01X522779Y914372D02*
X522778Y914371D01*
Y912262D01*
G01X520928Y909057D02*
Y911167D01*
G01X519079Y907963D02*
Y905853D01*
G01X520928Y904759D02*
X520929Y904758D01*
Y902649D01*
G01X528329Y917576D02*
Y915466D01*
G01X524628Y917576D02*
Y915466D01*
G01X532028Y917576D02*
Y915467D01*
X532029Y915466D01*
G01X528329Y909057D02*
Y911167D01*
G01Y921875D02*
Y923985D01*
G01X520928Y930393D02*
Y928283D01*
G01X519079Y927189D02*
Y925079D01*
G01X522779Y920780D02*
Y918670D01*
G01X520928Y923985D02*
X520929Y923984D01*
Y921875D01*
G01X522779Y933598D02*
X522778Y931488D01*
G01X528329Y930393D02*
Y928283D01*
G01Y943210D02*
Y941100D01*
G01X522779Y940006D02*
Y937896D01*
G01X520928Y943210D02*
X520929Y943209D01*
Y941100D01*
G01X519079Y946414D02*
Y944304D01*
G01X520928Y949619D02*
Y947509D01*
G01X528329D02*
Y949619D01*
G01Y962436D02*
Y960326D01*
G01Y956027D02*
Y953917D01*
G01X524628Y956027D02*
Y953918D01*
X524629Y953917D01*
G01X522779Y959232D02*
Y957122D01*
G01X520928Y962436D02*
X520929Y962435D01*
Y960326D01*
G01X522779Y952823D02*
X522778Y952822D01*
Y950713D01*
G01X526479Y965640D02*
Y963530D01*
G01X519079Y965640D02*
Y963530D01*
G01X532028Y956027D02*
Y953918D01*
X532029Y953917D01*
G01X530179Y965640D02*
X530178Y965639D01*
Y963530D01*
G01X520928Y968845D02*
Y966735D01*
G01X528329D02*
Y968845D01*
G01Y979552D02*
Y981662D01*
G01Y975253D02*
Y973143D01*
G01X522779Y978457D02*
Y976347D01*
G01Y972049D02*
X522778Y972048D01*
Y969939D01*
G01X524628Y975253D02*
Y973143D01*
G01X520928Y981662D02*
X520929Y981661D01*
Y979552D01*
G01X532028Y975253D02*
X532029Y975252D01*
Y973143D01*
G01X519079Y984866D02*
Y982756D01*
G01X521361Y997574D02*
Y999684D01*
G01X528761Y997574D02*
Y999683D01*
X528762Y999684D01*
G01X521361Y1012501D02*
Y1010391D01*
G01X528761Y1003983D02*
Y1006092D01*
X528762Y1006093D01*
G01X525061Y1003983D02*
Y1006093D01*
G01X523212Y1000778D02*
Y1002888D01*
G01X532461Y1003983D02*
Y1006093D01*
G01X528761Y1012501D02*
Y1010391D01*
G01X519512Y1013595D02*
Y1015705D01*
G01X526912Y1013595D02*
Y1015705D01*
G01X530612Y1013595D02*
Y1015704D01*
X530611Y1015705D01*
G01X528761Y1023208D02*
Y1025317D01*
X528762Y1025318D01*
G01X523212Y1026413D02*
Y1028522D01*
X523211Y1028523D01*
G01X525061Y1023208D02*
Y1025318D01*
G01X528761Y1029617D02*
Y1031726D01*
X528762Y1031727D01*
G01X521361Y1029617D02*
Y1031727D01*
G01Y1016800D02*
Y1018909D01*
X521362Y1018910D01*
G01X523212Y1020004D02*
Y1020053D01*
X523211Y1022114D01*
G01X528761Y1016800D02*
Y1018909D01*
X528762Y1018910D01*
G01X528761Y1042434D02*
X528762Y1044544D01*
G01X525061Y1042434D02*
Y1044544D01*
G01X523212Y1039230D02*
Y1041340D01*
G01X521361Y1036026D02*
Y1038135D01*
X521362Y1038136D01*
G01X519512Y1032821D02*
Y1034931D01*
G01X532461Y1042434D02*
X532462Y1044544D01*
G01X528761Y1036026D02*
Y1038135D01*
X528762Y1038136D01*
G01X528761Y1055251D02*
X528762Y1057361D01*
G01X528761Y1048842D02*
X528762Y1050952D01*
G01X523212Y1058455D02*
Y1060565D01*
G01X521361Y1055251D02*
X521362Y1057361D01*
G01X521361Y1048842D02*
Y1050952D01*
G01X519512Y1052047D02*
Y1054157D01*
G01X528761Y1061660D02*
X528762Y1063653D01*
Y1063770D01*
G01X525061Y1061660D02*
Y1063770D01*
G01X532461Y1061660D02*
X532462Y1063653D01*
Y1063770D01*
G01X528761Y1074477D02*
X528762Y1076587D01*
G01X528761Y1068068D02*
X528762Y1070178D01*
G01X521361Y1074477D02*
X521362Y1076587D01*
G01X521361Y1068068D02*
Y1070178D01*
G01X519512Y1071273D02*
Y1073383D01*
G01X523212Y1064864D02*
X523211Y1066974D01*
G01X523212Y1077681D02*
Y1079791D01*
G01X517661Y1093703D02*
X517662Y1095813D01*
G01X523212Y1084090D02*
X523211Y1086200D01*
G01X521361Y1087294D02*
Y1089404D01*
G01X519512Y1090498D02*
X519511Y1092608D01*
G01X528761Y1087294D02*
X528762Y1089404D01*
G01X528761Y1080885D02*
Y1082994D01*
X528762Y1082995D01*
G01X525061Y1080885D02*
Y1082995D01*
G01X532461Y1080885D02*
Y1082995D01*
X532462Y1082996D01*
G01X528761Y1093703D02*
Y1095813D01*
G01X519512Y1103316D02*
X519511Y1105426D01*
G01X530612Y1122541D02*
Y1124650D01*
X530611Y1124651D01*
G01X528761Y1119337D02*
X528762Y1121447D01*
G01X528761Y1125746D02*
Y1127856D01*
G01X521361Y1125746D02*
Y1127856D01*
G01Y1138563D02*
Y1140973D01*
G01X533072Y1351937D02*
X531916D01*
X530231Y1350252D01*
Y1348550D01*
G01X533072Y1353709D02*
X531625D01*
X528807Y1350891D01*
X528447D01*
G01Y1355816D02*
Y1358241D01*
G01D02*
X528783D01*
X531544Y1355480D01*
X533072D01*
G01X535729Y851380D02*
Y853490D01*
G01X533879Y863103D02*
Y860993D01*
G01Y869511D02*
Y867401D01*
G01X544979Y854584D02*
Y856694D01*
G01X539428Y866307D02*
Y864197D01*
G01X537579Y863103D02*
Y860993D01*
G01X541279Y869511D02*
Y867401D01*
G01X537579Y869511D02*
Y867401D01*
G01X533879Y882329D02*
Y880219D01*
G01X541279Y875920D02*
Y873810D01*
G01X535729Y870606D02*
Y872716D01*
G01X541279Y880219D02*
Y882329D01*
G01X533879Y918670D02*
Y920780D01*
G01X537579Y927189D02*
Y925080D01*
X537578Y925079D01*
G01X535729Y921875D02*
Y923985D01*
G01X544979Y965640D02*
X548146D01*
G01X539428Y975253D02*
X539429Y975252D01*
Y973143D01*
G01X544979Y978457D02*
X547489D01*
X548089Y979057D01*
X551429D01*
G01X544979Y972049D02*
X549142D01*
X549701Y972608D01*
X550701D01*
G01X536161Y997574D02*
Y999684D01*
G01X534311Y1007187D02*
Y1009297D01*
G01Y1000778D02*
Y1002888D01*
G01X541711Y1000778D02*
X539977Y999776D01*
X539885Y999684D01*
X539861D01*
G01X545412Y1000778D02*
X549124D01*
X549254Y1000648D01*
G01X536161Y1012501D02*
Y1010391D01*
G01X534311Y1028523D02*
Y1026413D01*
G01Y1020004D02*
Y1020053D01*
X534310Y1022114D01*
G01X538012Y1077681D02*
X536161Y1076587D01*
G01X534311Y1096907D02*
Y1099017D01*
G01X545412Y1103316D02*
Y1105426D01*
G01X539861Y1100111D02*
Y1102221D01*
G01X536161Y1100111D02*
Y1102221D01*
G01X545412Y1122541D02*
Y1124650D01*
X545411Y1124651D01*
G01X545412Y1116133D02*
Y1118242D01*
X545411Y1118243D01*
G01X538012Y1122541D02*
X538011Y1122542D01*
Y1124651D01*
G01X534311Y1128950D02*
Y1131060D01*
G01X541711Y1128950D02*
Y1131060D01*
G01X545510Y1366616D02*
Y1364838D01*
X545316Y1364644D01*
Y1361484D01*
G01X549552Y1369766D02*
X545510D01*
G01X549552Y1366616D02*
X547088Y1364152D01*
Y1361484D01*
G01X667812Y1399131D02*
X666610D01*
X664896Y1400845D01*
Y1401561D01*
X663187Y1403270D01*
G01X667812Y1395588D02*
X666351D01*
X663533Y1392770D01*
X663187D01*
G01X667812Y1397359D02*
X666396D01*
X663635Y1400120D01*
X663187D01*
G01X667812Y1393816D02*
X666524D01*
X664971Y1392263D01*
Y1390429D01*
G01X680250Y1408495D02*
Y1406647D01*
X680056Y1406453D01*
Y1403363D01*
G01X684292Y1408495D02*
Y1408064D01*
X681828Y1405600D01*
Y1403363D01*
G01X684292Y1411645D02*
X680250D01*
G01X704666Y1393815D02*
X703114Y1392263D01*
Y1390429D01*
G01X705955Y1393815D02*
X704666D01*
G01X701330Y1403270D02*
X703208Y1401392D01*
Y1400488D01*
X704565Y1399131D01*
X705955D01*
G01X701330Y1395195D02*
Y1392770D01*
G01X705955Y1395588D02*
X704494D01*
X701676Y1392770D01*
X701330D01*
G01Y1397695D02*
Y1400120D01*
G01D02*
X701666D01*
X704427Y1397359D01*
X705955D01*
G01X718393Y1408495D02*
Y1406647D01*
X718199Y1406453D01*
Y1403363D01*
G01X722435Y1408495D02*
Y1408064D01*
X719971Y1405600D01*
Y1403363D01*
G01X722435Y1411645D02*
X718393D01*
G01X918532Y492445D02*
Y492371D01*
X916389Y490228D01*
X916331D01*
G01Y507944D02*
X918264Y506011D01*
G01X932089Y492691D02*
Y492186D01*
X934047Y490228D01*
G01X927154Y492103D02*
Y491209D01*
X926173Y490228D01*
G01X934047Y507944D02*
X932089Y505986D01*
G01X932289Y502986D02*
X933236Y502039D01*
X934047D01*
G01X991369Y379186D02*
X990500Y378317D01*
Y377362D01*
X989500Y376362D01*
G01X1029395Y375844D02*
Y376542D01*
G01D02*
X1025693Y380244D01*
G01X1127504Y1430120D02*
X1126216D01*
X1124663Y1428567D01*
Y1426733D01*
G01X1122879Y1439574D02*
X1124588Y1437865D01*
Y1437004D01*
X1126157Y1435435D01*
X1127504D01*
G01X1122879Y1425924D02*
X1123854D01*
X1124663Y1426733D01*
G01X1122879Y1429074D02*
X1123225D01*
X1126043Y1431892D01*
X1127504D01*
G01X1122879Y1436424D02*
X1123167D01*
X1125928Y1433663D01*
X1127504D01*
G01X1139942Y1444799D02*
Y1442771D01*
X1139748Y1442577D01*
Y1439667D01*
G01X1143984Y1447949D02*
X1139942D01*
G01X1143984Y1444799D02*
Y1444368D01*
X1141520Y1441904D01*
Y1439667D01*
G01X1165647Y1430120D02*
X1164359D01*
X1162806Y1428567D01*
Y1426733D01*
G01X1161022Y1439574D02*
X1162900Y1437696D01*
Y1436792D01*
X1164257Y1435435D01*
X1165647D01*
G01X1161022Y1431499D02*
Y1429074D01*
G01D02*
X1161368D01*
X1164186Y1431892D01*
X1165647D01*
G01X1161022Y1436424D02*
X1161358D01*
X1164119Y1433663D01*
X1165647D01*
G01X1161022Y1433999D02*
Y1436424D01*
G01X1178085Y1444799D02*
Y1442535D01*
X1177891Y1442341D01*
Y1439667D01*
G01X1182127Y1447949D02*
X1178085D01*
G01X1182127Y1444799D02*
Y1444368D01*
X1179663Y1441904D01*
Y1439667D01*
G01X1210795Y195362D02*
X1213720D01*
G01X1281596Y1348786D02*
Y1350608D01*
X1283161Y1352173D01*
X1284437D01*
G01X1285767Y150750D02*
Y153329D01*
G01X1289035D02*
X1288347Y150750D01*
G01D02*
X1285767D01*
G01X1283781Y149115D02*
X1284227Y149542D01*
X1284500Y149536D01*
X1285767Y150750D01*
G01X1294866Y148170D02*
Y147077D01*
X1294624Y146493D01*
X1292293Y144162D01*
G01D02*
Y143162D01*
G01X1297007Y161149D02*
X1295929Y162999D01*
G01X1287401Y155299D02*
X1289035Y153329D01*
G01X1292303Y165146D02*
X1292078Y165371D01*
Y168860D01*
X1292303Y169085D01*
G01X1299134Y161149D02*
X1297007D01*
G01X1293802Y162999D02*
X1295929D01*
G01X1292303Y161207D02*
X1293802Y162999D01*
G01X1292896Y153072D02*
X1289035Y153329D01*
G01Y161207D02*
X1292303D01*
G01Y157268D02*
X1293049Y156522D01*
X1294866Y154706D01*
G01X1298805D02*
X1294866D01*
G01D02*
X1292896Y153072D01*
G01X1292303Y161207D02*
Y160182D01*
X1292082Y159961D01*
Y158563D01*
X1292303Y158342D01*
Y157268D01*
G01X1285767Y153329D02*
X1287401Y155299D01*
G01X1293802Y162999D02*
X1292303Y165146D01*
G01X1283781Y155788D02*
X1285261Y157268D01*
X1285767D01*
G01X1299134Y168549D02*
X1297012D01*
G01X1299134Y164849D02*
X1297007D01*
G01X1292303Y173024D02*
X1292078Y172799D01*
Y169310D01*
X1292303Y169085D01*
G01X1283425Y179272D02*
X1287061D01*
X1287401Y178932D01*
G01X1290669D02*
X1287401D01*
G01X1289035Y200596D02*
X1287401Y202566D01*
G01X1283397Y202085D02*
X1286920D01*
X1287401Y202566D01*
G01X1292303Y216352D02*
X1292103Y216552D01*
Y220091D01*
X1292303Y220291D01*
G01Y208474D02*
X1292103Y208274D01*
Y206170D01*
X1292000Y205921D01*
Y204838D01*
X1292303Y204535D01*
G01D02*
X1293802Y201849D01*
G01X1292303Y212413D02*
X1292103Y212613D01*
Y216152D01*
X1292303Y216352D01*
G01Y208474D02*
X1292103Y208674D01*
Y212213D01*
X1292303Y212413D01*
G01D02*
X1289035D01*
G01X1292303Y208474D02*
X1296998Y209247D01*
X1296999Y209249D01*
G01X1282568Y212722D02*
X1282877Y212413D01*
X1285767D01*
G01X1292303Y220291D02*
X1297012Y220349D01*
X1299134D01*
G01X1287943Y233748D02*
X1288262Y231382D01*
X1288347Y230748D01*
G01X1289035Y228169D02*
X1288347Y230748D01*
G01X1285767Y228169D02*
X1287401Y226199D01*
G01X1294866Y236535D02*
Y233328D01*
G01X1292896Y228426D02*
X1294530Y226792D01*
X1294866D01*
G01D02*
X1298805D01*
G01X1290927Y230060D02*
X1291262D01*
X1292896Y228426D01*
G01X1296875Y1366852D02*
Y1364430D01*
X1296681Y1364236D01*
Y1361720D01*
G01X1300917Y1370002D02*
X1296875D01*
G01X1301993Y140462D02*
Y140730D01*
X1302747Y141484D01*
Y146048D01*
X1302744Y148170D01*
G01X1300774Y155288D02*
X1302744Y154706D01*
G01X1298805D02*
X1300774Y155288D01*
G01X1302744Y154706D02*
X1304713Y155288D01*
X1306683Y154706D01*
G01D02*
X1308123Y155132D01*
X1308652Y155288D01*
X1310621Y154706D01*
G01D02*
X1312591Y155288D01*
X1314560Y154706D01*
G01X1311955Y161149D02*
X1309832D01*
G01X1305544D02*
X1303417D01*
G01X1311955Y168549D02*
X1309832D01*
G01X1305544D02*
X1303417D01*
G01X1305544Y172249D02*
X1303422D01*
G01X1313033Y174099D02*
X1315160D01*
G01X1311955Y175949D02*
X1312752Y174582D01*
X1313033Y174099D01*
G01X1308749D02*
X1306622D01*
G01X1305544Y179649D02*
X1306617Y181499D01*
G01X1309817Y187049D02*
X1308749Y185199D01*
G01X1311955Y179649D02*
X1313027Y181499D01*
G01Y185199D02*
X1312919Y185012D01*
X1311955Y183349D01*
G01X1308749Y188899D02*
X1309817Y187049D01*
G01X1305544Y190749D02*
X1306617Y192599D01*
G01X1313023Y199999D02*
X1311955Y198149D01*
G01D02*
X1315352Y195474D01*
G01D02*
X1315344Y195472D01*
X1311955Y194449D01*
G01X1306617Y199999D02*
X1308749Y203699D01*
G01X1305544Y198149D02*
X1306617Y199999D01*
G01X1300207D02*
X1299137Y198149D01*
X1299134D01*
G01X1311955Y190749D02*
X1313027Y192599D01*
G01X1309817Y190749D02*
X1309249D01*
X1308749Y191249D01*
Y192599D01*
G01Y207399D02*
Y203699D01*
G01X1302340D02*
X1303407Y201849D01*
G01X1305544Y209249D02*
X1303422D01*
G01X1315160Y214799D02*
X1313032D01*
G01D02*
X1311955Y212949D01*
G01D02*
X1315160Y211099D01*
G01X1313032Y214799D02*
X1312599Y215542D01*
X1311955Y216649D01*
G01X1305544Y212949D02*
X1303417D01*
G01X1305544Y216649D02*
X1303417D01*
G01X1302340Y214799D02*
X1300207D01*
G01X1311955Y209249D02*
X1309832D01*
G01X1313027Y203699D02*
X1311955Y201849D01*
G01Y205549D02*
X1313027Y203699D01*
G01X1306622Y218499D02*
X1308749D01*
G01X1301151Y225450D02*
X1302744Y226792D01*
G01X1298805D02*
X1301151Y225450D01*
G01X1298805Y226792D02*
X1300774Y228426D01*
G01D02*
X1302744Y226792D01*
G01D02*
X1306683D01*
G01D02*
Y227972D01*
X1307137Y228426D01*
X1308652D01*
G01X1310621Y226792D02*
X1306683D01*
G01X1314560D02*
X1310621D01*
G01X1300774Y228426D02*
Y231694D01*
G01X1309100Y236477D02*
Y234597D01*
X1308652Y234149D01*
Y231694D01*
G01X1309828Y224049D02*
X1311955D01*
G01X1306622Y222199D02*
X1308749D01*
G01X1313921Y856694D02*
Y854585D01*
X1313920Y854584D01*
G01X1312070Y859899D02*
Y858168D01*
X1312266Y857972D01*
G01X1310221Y875920D02*
X1308370Y877014D01*
G01X1312070Y898350D02*
Y896240D01*
G01X1310221Y895146D02*
X1310220Y893036D01*
G01X1310221Y901555D02*
X1308371Y902649D01*
G01X1312070Y915466D02*
Y917576D01*
G01X1310221Y914372D02*
X1308370Y915466D01*
G01X1310221Y920780D02*
X1308371Y921875D01*
G01X1310221Y933598D02*
X1308370Y934692D01*
G01X1313921Y965640D02*
X1315749Y966694D01*
X1315771Y966716D01*
Y966735D01*
G01X1310221Y959232D02*
Y957122D01*
G01Y972049D02*
X1308371Y973143D01*
G01X1312070Y975253D02*
X1310221Y976347D01*
G01X1313921Y984866D02*
X1312848Y985939D01*
X1311491D01*
G01X1316203Y997574D02*
X1314352Y996480D01*
G01X1309976Y1062790D02*
X1310049Y1062751D01*
X1310050Y1062749D01*
X1312103Y1061660D01*
X1312503D01*
G01X1314353Y1077681D02*
X1316204Y1076587D01*
G01X1305774Y1092168D02*
X1310648Y1087294D01*
X1312503D01*
G01X1314353Y1084090D02*
X1312502Y1082995D01*
G01X1314353Y1109724D02*
Y1111834D01*
G01Y1103316D02*
Y1105426D01*
G01X1311486Y1097289D02*
X1311868Y1096907D01*
X1314353D01*
G01X1312503Y1112929D02*
Y1115039D01*
G01X1316445Y1329139D02*
X1315289D01*
X1313604Y1327454D01*
Y1325752D01*
G01X1316445Y1334454D02*
X1315110D01*
X1313698Y1335866D01*
Y1336715D01*
X1311820Y1338593D01*
G01Y1330518D02*
Y1328093D01*
G01X1316445Y1330911D02*
X1314998D01*
X1312180Y1328093D01*
X1311820D01*
G01Y1333018D02*
Y1335443D01*
G01X1316445Y1332682D02*
X1314891D01*
X1312130Y1335443D01*
X1311820D01*
G01X1300917Y1366852D02*
X1298453Y1364388D01*
Y1361720D01*
G01X1324408Y153072D02*
Y149804D01*
G01X1323958Y146227D02*
Y149354D01*
X1324408Y149804D01*
G01X1320469Y155288D02*
X1322438Y154706D01*
G01X1324408Y153072D02*
X1322438Y154706D01*
G01D02*
X1324408Y155288D01*
X1326377Y154706D01*
G01X1330316D02*
X1326377D01*
G01D02*
X1324408Y153072D01*
G01X1334255Y154706D02*
X1330316D01*
G01X1318499D02*
X1320469Y155288D01*
G01X1314560Y154706D02*
X1318499D01*
G01X1324775Y161149D02*
X1322652D01*
G01X1318364D02*
X1316242D01*
G01X1324775Y168549D02*
X1321570Y170399D01*
G01X1319452Y166699D02*
X1321570D01*
G01X1329062Y168549D02*
X1331184D01*
G01X1327979Y166699D02*
X1329062Y168549D01*
G01X1321570Y170399D02*
X1319442D01*
G01X1318502Y176574D02*
X1320077Y178149D01*
G01X1318502Y182874D02*
X1320077Y184449D01*
G01Y181299D02*
X1318502Y182874D01*
G01X1331184Y172249D02*
X1329062D01*
G01X1318364D02*
X1316237D01*
G01X1329527Y178149D02*
X1331102Y176574D01*
G01X1327952Y182874D02*
X1329527Y184449D01*
G01Y181299D02*
X1327952Y182874D01*
G01X1327979Y174099D02*
X1325853D01*
G01X1327979Y170399D02*
X1324775Y172249D01*
G01X1325853Y174099D02*
X1324775Y172249D01*
G01X1323227Y178149D02*
X1323338D01*
X1325085Y176402D01*
G01D02*
X1326377Y177694D01*
Y178149D01*
G01X1323227Y181299D02*
X1324802Y179724D01*
G01D02*
X1326377Y181299D01*
G01Y184449D02*
X1324802Y182874D01*
G01D02*
X1323227Y184449D01*
G01X1315352Y186024D02*
X1316927Y184449D01*
G01X1315352Y179724D02*
X1316927Y178149D01*
G01Y181299D02*
X1315352Y179724D01*
G01X1319442Y174099D02*
X1321570D01*
G01X1318502Y189174D02*
X1320077Y190749D01*
G01D02*
X1323227D01*
G01X1318502Y186024D02*
X1320077Y187599D01*
G01X1329527D02*
X1327952Y186024D01*
G01X1315352Y195474D02*
X1316927Y197049D01*
G01X1315352Y195474D02*
X1316927Y193899D01*
G01X1327952Y189174D02*
X1326377Y190749D01*
G01X1329527D02*
X1327952Y189174D01*
G01Y198624D02*
X1326377Y197049D01*
G01X1329527D02*
X1327952Y198624D01*
G01X1321652D02*
X1323227Y197049D01*
G01X1320077D02*
X1321652Y198624D01*
G01X1326377Y187599D02*
X1324802Y186024D01*
G01D02*
X1323227Y187599D01*
G01X1326377Y193899D02*
X1324802Y195474D01*
G01X1329527Y193899D02*
X1327952Y195474D01*
G01X1318502D02*
X1320077Y193899D01*
G01X1323227D02*
X1321652Y195474D01*
G01X1327952Y201774D02*
X1329527Y200199D01*
G01X1320077D02*
X1321652Y201774D01*
G01X1316927Y200199D02*
X1320077D01*
G01X1321652Y201774D02*
X1323227Y200199D01*
G01X1316927Y190749D02*
X1315405Y189227D01*
G01X1316927Y187599D02*
X1315352Y186024D01*
G01X1325852Y214799D02*
X1327979D01*
G01X1319442Y218499D02*
X1320798Y216142D01*
X1321570Y214799D01*
G01X1318364Y212949D02*
X1321570Y214799D01*
G01X1324775Y212949D02*
X1325852Y214799D01*
G01X1321570D02*
X1324775Y212949D01*
G01X1315160Y214799D02*
X1318364Y212949D01*
G01X1315160Y211099D02*
X1318364Y212949D01*
G01X1331184Y209249D02*
X1329062D01*
G01X1319442Y207399D02*
X1315160D01*
G01X1321570D02*
X1319442D01*
G01X1331184Y216649D02*
X1329062D01*
G01X1331184Y212949D02*
X1329062D01*
G01X1327979Y211099D02*
X1325852D01*
G01X1319442D02*
X1321570D01*
G01X1323227Y203349D02*
X1324802Y204924D01*
G01D02*
X1326377Y203349D01*
G01X1329527D02*
X1327952Y204924D01*
G01X1318502D02*
X1320077Y203349D01*
G01X1316927D02*
X1315352Y204924D01*
G01X1324775Y209249D02*
X1322652D01*
G01X1321570Y218499D02*
X1319442D01*
G01X1326377Y235784D02*
Y233328D01*
G01X1322438Y226792D02*
X1318499D01*
G01D02*
X1314560D01*
G01X1322438Y230060D02*
X1322011Y231848D01*
X1322438Y233328D01*
G01Y226792D02*
X1326377D01*
G01Y230060D02*
Y226792D01*
G01Y233328D02*
Y230060D01*
G01X1321986Y236726D02*
Y235240D01*
X1322438Y234788D01*
Y233328D01*
G01X1319442Y222199D02*
X1321570D01*
G01X1331184Y224049D02*
X1329061D01*
G01X1326870Y847081D02*
Y844972D01*
X1326869Y844971D01*
G01X1323171Y847081D02*
Y844972D01*
X1323170Y844971D01*
G01X1321321Y850286D02*
Y848177D01*
X1321320Y848176D01*
G01X1323171Y853490D02*
Y851381D01*
X1323170Y851380D01*
G01X1319470Y853490D02*
Y851381D01*
X1319469Y851380D01*
G01X1317621Y856694D02*
Y854585D01*
X1317620Y854584D01*
G01X1315771Y859899D02*
Y857790D01*
X1315770Y857789D01*
G01X1328721Y856694D02*
Y854584D01*
G01X1323171Y859899D02*
Y857789D01*
G01X1325021Y856694D02*
Y854585D01*
X1325020Y854584D01*
G01X1321321Y863103D02*
Y860993D01*
G01X1319470Y859899D02*
Y857790D01*
X1319469Y857789D01*
G01X1328721Y869511D02*
Y867401D01*
G01X1325021Y869511D02*
Y867401D01*
G01X1315771Y879124D02*
Y877014D01*
G01Y872716D02*
X1317621Y873810D01*
G01X1319470Y879124D02*
Y877015D01*
X1319471Y877014D01*
G01X1328721Y901555D02*
Y899446D01*
X1328720Y899445D01*
G01X1315771Y898350D02*
Y896240D01*
G01Y891942D02*
Y889832D01*
G01X1328721Y895146D02*
X1328720Y895145D01*
Y893036D01*
G01X1328721Y888737D02*
Y886628D01*
X1328720Y886627D01*
G01X1325021Y888737D02*
Y886627D01*
G01X1328721Y907963D02*
X1328720Y907962D01*
Y905853D01*
G01X1325021Y907963D02*
X1325020Y907962D01*
Y905853D01*
G01X1315771Y911167D02*
X1317621Y912262D01*
G01X1315771Y904759D02*
X1317620Y905853D01*
G01X1328721Y914372D02*
X1328720Y914371D01*
Y912262D01*
G01X1323171Y902649D02*
Y904759D01*
G01X1315771Y915466D02*
Y917576D01*
G01X1328721Y927189D02*
X1328720Y927188D01*
Y925079D01*
G01X1328721Y920780D02*
X1328720Y920779D01*
Y918670D01*
G01X1325021Y927189D02*
X1325020Y927188D01*
Y925079D01*
G01X1315771Y923985D02*
X1317620Y925079D01*
G01X1315771Y930393D02*
X1317621Y931488D01*
G01X1325021Y946414D02*
X1325020Y946413D01*
Y944304D01*
G01X1328721Y946414D02*
X1328720Y946413D01*
Y944304D01*
G01X1328721Y952823D02*
X1328720Y952822D01*
Y950713D01*
G01X1328721Y959232D02*
X1328720Y959231D01*
Y957122D01*
G01X1325021Y965640D02*
X1325020Y965639D01*
Y963530D01*
G01X1328721Y965640D02*
X1328720Y965639D01*
Y963530D01*
G01X1321321Y959232D02*
Y957122D01*
G01X1323171Y962436D02*
Y960326D01*
G01X1315771Y956027D02*
Y953917D01*
G01Y962436D02*
X1319470Y960326D01*
G01X1326870Y975253D02*
Y973144D01*
X1326871Y973143D01*
G01X1328721Y972049D02*
X1328720Y972048D01*
Y969939D01*
G01X1319470Y975253D02*
Y973144D01*
X1319471Y973143D01*
G01X1321321Y972049D02*
Y969939D01*
G01X1323171Y979552D02*
Y981662D01*
G01X1321321Y978457D02*
Y976347D01*
G01X1315771Y973143D02*
Y975253D01*
G01X1330570D02*
Y973143D01*
G01X1328721Y978457D02*
Y976347D01*
G01X1323171Y966735D02*
Y968845D01*
G01X1315771D02*
Y966735D01*
G01Y981662D02*
Y979552D01*
G01X1325021Y984866D02*
X1325020Y984865D01*
Y982756D01*
G01X1328721Y984866D02*
X1328720Y984865D01*
Y982756D01*
G01X1323603Y997574D02*
Y999684D01*
G01X1327303Y1003983D02*
X1327304Y1006093D01*
G01X1329153Y1007187D02*
Y1009297D01*
G01Y1000778D02*
Y1002888D01*
G01X1321753Y1007187D02*
Y1009297D01*
G01X1319903Y1003983D02*
Y1006093D01*
G01X1321753Y1000778D02*
Y1002888D01*
G01X1323603Y1012501D02*
Y1010391D01*
G01X1329153Y1013595D02*
Y1015705D01*
G01X1325454Y1013595D02*
Y1015704D01*
X1325453Y1015705D01*
G01X1329153Y1026413D02*
Y1028523D01*
G01Y1020004D02*
Y1022114D01*
G01X1323603Y1016800D02*
Y1018910D01*
G01Y1031727D02*
Y1029617D01*
G01X1329153Y1032821D02*
Y1034931D01*
G01Y1039230D02*
Y1041340D01*
G01X1325454Y1032821D02*
Y1034930D01*
X1325453Y1034931D01*
G01X1319903Y1042434D02*
Y1044544D01*
G01X1321753Y1045639D02*
Y1047749D01*
G01X1329153Y1058455D02*
Y1060565D01*
G01Y1052047D02*
Y1054157D01*
G01X1325454Y1052047D02*
Y1054156D01*
X1325453Y1054157D01*
G01X1316203Y1055251D02*
X1319903Y1057361D01*
G01X1316203Y1048842D02*
X1319903Y1050952D01*
G01X1323603Y1048842D02*
Y1050952D01*
G01Y1055251D02*
Y1057361D01*
G01X1321753Y1058455D02*
Y1060565D01*
G01X1319903Y1061660D02*
Y1063770D01*
G01X1329153Y1071273D02*
Y1073383D01*
G01X1316203Y1074477D02*
X1319903Y1076587D01*
G01X1316203Y1068068D02*
X1319903Y1070178D01*
G01X1329153Y1064864D02*
Y1066974D01*
G01X1323603Y1074477D02*
Y1076587D01*
G01Y1068068D02*
Y1070178D01*
G01X1325454Y1071273D02*
Y1073383D01*
G01X1321753Y1064864D02*
Y1066974D01*
G01X1329153Y1077681D02*
Y1079791D01*
G01X1321753Y1077681D02*
Y1079791D01*
G01X1319903Y1080885D02*
X1318053Y1079791D01*
G01X1329153Y1084090D02*
Y1086200D01*
G01Y1092608D02*
Y1090498D01*
G01X1318054Y1084090D02*
X1316202Y1082995D01*
G01X1329153Y1096907D02*
X1329152Y1099015D01*
X1329153Y1099016D01*
Y1099017D01*
G01X1316203Y1106520D02*
Y1108630D01*
G01Y1100111D02*
Y1102221D01*
G01X1325454Y1096907D02*
X1325453Y1099017D01*
G01X1323603Y1100111D02*
Y1102221D01*
G01X1319903Y1100111D02*
Y1102221D01*
G01X1316203Y1112929D02*
Y1115039D01*
G01X1327303Y1119337D02*
Y1121447D01*
G01Y1112929D02*
Y1115039D01*
G01X1325454Y1122541D02*
X1325453Y1124651D01*
G01X1319903Y1112929D02*
Y1115039D01*
G01X1318054Y1122541D02*
Y1124650D01*
X1318053Y1124651D01*
G01X1328883Y1343818D02*
Y1341862D01*
X1328689Y1341668D01*
Y1338686D01*
G01X1332925Y1343818D02*
Y1343387D01*
X1330461Y1340923D01*
Y1338686D01*
G01X1332925Y1346968D02*
X1328883D01*
G01X1344103Y155288D02*
X1342133Y154706D01*
G01X1338194D02*
X1334255D01*
G01X1346071D02*
X1344103Y155288D01*
G01X1346071Y154706D02*
X1350010D01*
G01X1342133D02*
X1338194D01*
G01X1335472Y161149D02*
X1337594D01*
G01X1331184D02*
X1335472D01*
G01X1342907Y166699D02*
X1343608Y167912D01*
X1343970Y168539D01*
X1344005Y168549D01*
G01X1332268Y166699D02*
X1334390D01*
G01X1337594Y168549D02*
X1335472D01*
G01X1340799Y181499D02*
X1339727Y179649D01*
G01X1344005Y183349D02*
X1342937Y181499D01*
G01X1344005Y187049D02*
X1342937Y185199D01*
G01X1346137Y172249D02*
X1344005Y175949D01*
G01X1347210Y174099D02*
X1347207D01*
X1346137Y172249D01*
G01X1337594D02*
X1335472D01*
G01X1340799Y177799D02*
X1340312Y177312D01*
X1339568Y176028D01*
G01D02*
X1337447Y178149D01*
X1335827D01*
G01X1339568Y176028D02*
X1339837Y175759D01*
X1340799Y174099D01*
G01X1335827Y181299D02*
X1332677D01*
G01D02*
X1331102Y179724D01*
G01X1332677Y184449D02*
X1335827D01*
G01X1331102Y182874D02*
X1332677Y184449D01*
G01X1332268Y170399D02*
X1334390D01*
G01X1332677Y178149D02*
X1334252Y176574D01*
G01X1339727Y183349D02*
X1340691Y185012D01*
X1340799Y185199D01*
G01Y192599D02*
X1339727Y190749D01*
G01X1344005D02*
X1342937Y188899D01*
G01X1335827Y197049D02*
X1334252Y195474D01*
G01X1331102D02*
X1332677Y197049D01*
G01Y203349D02*
Y200199D01*
G01D02*
Y197049D01*
G01Y193899D02*
X1331102Y195474D01*
G01X1346137Y194449D02*
X1344005Y198149D01*
G01Y201849D02*
Y198149D01*
G01X1347210Y196299D02*
X1347207D01*
X1346137Y194449D01*
G01X1332677Y190749D02*
X1331102Y189174D01*
G01X1335827Y190749D02*
X1332677D01*
G01Y187599D02*
X1331102Y186024D01*
G01X1335827Y187599D02*
X1332677D01*
G01X1340799Y196299D02*
X1337901Y196035D01*
G01X1340799Y188899D02*
X1339727Y187049D01*
G01X1335827Y200199D02*
X1337402Y198624D01*
G01D02*
X1340799Y199999D01*
G01X1344005Y194449D02*
X1342937Y192599D01*
G01X1346147Y209248D02*
X1347217Y211098D01*
X1347210Y211099D01*
G01X1344005Y209249D02*
X1346147Y209248D01*
G01X1340799Y214799D02*
X1342035Y212534D01*
X1344005Y212949D01*
G01Y209249D02*
Y205549D01*
G01D02*
Y201849D01*
G01Y212949D02*
Y209249D01*
G01X1337594Y212949D02*
Y209249D01*
G01X1337102Y206675D02*
X1337594Y207167D01*
Y209249D01*
G01X1334390Y214799D02*
X1332262D01*
G01X1334390Y211099D02*
X1332262D01*
G01X1335827Y203349D02*
X1337345Y201831D01*
G01X1334390Y207399D02*
X1332262D01*
G01X1340799D02*
X1339686Y205478D01*
G01X1340799Y203699D02*
X1339727Y201849D01*
G01X1334390Y218499D02*
X1332262D01*
G01X1333811Y235348D02*
X1334255Y234904D01*
Y233328D01*
G01X1346071Y226792D02*
X1342133D01*
G01X1350010D02*
X1348041Y226210D01*
X1346071Y226792D01*
G01X1334255Y233328D02*
X1333811Y231548D01*
X1334255Y230060D01*
G01X1334390Y222199D02*
X1332267D01*
G01X1343521Y856694D02*
Y854584D01*
G01X1336121Y856694D02*
Y854584D01*
G01X1343521Y869511D02*
Y867401D01*
G01X1336121Y869511D02*
Y867401D01*
G01X1343521Y882329D02*
Y880219D01*
G01X1336121D02*
Y882329D01*
G01X1332421Y888737D02*
Y886628D01*
X1332420Y886627D01*
G01X1345370Y898350D02*
X1345371Y898349D01*
Y896240D01*
G01X1341670Y898350D02*
X1341671Y898349D01*
Y896240D01*
G01X1337970Y898350D02*
Y896240D01*
G01X1336121Y895146D02*
Y893036D01*
G01Y899445D02*
Y901555D01*
G01X1339821Y888737D02*
Y886628D01*
X1339820Y886627D01*
G01X1341670Y911167D02*
X1341671Y911166D01*
Y909057D01*
G01X1341670Y904759D02*
X1341671Y904758D01*
Y902649D01*
G01X1336121Y914372D02*
X1336120Y914371D01*
Y912262D01*
G01X1334270Y909057D02*
Y911167D01*
G01Y904759D02*
X1334271Y904758D01*
Y902649D01*
G01X1337970Y917576D02*
Y915466D01*
G01X1332421Y927189D02*
Y925079D01*
G01X1341670Y930393D02*
X1341671Y930392D01*
Y928283D01*
G01X1336121Y920780D02*
Y918670D01*
G01X1334270Y930393D02*
Y928283D01*
G01X1336121Y933598D02*
X1336120Y933597D01*
Y931488D01*
G01X1341670Y943210D02*
X1341671Y943209D01*
Y941100D01*
G01X1341670Y949619D02*
X1341671Y949618D01*
Y947509D01*
G01X1334270Y949619D02*
Y947509D01*
G01Y943210D02*
X1334271Y941100D01*
G01X1332421Y946414D02*
Y944304D01*
G01X1336121Y937896D02*
Y940006D01*
G01X1334270Y962436D02*
X1334271Y962435D01*
Y960326D01*
G01X1336121Y952823D02*
X1336120Y952822D01*
Y950713D01*
G01X1337970Y956027D02*
Y953918D01*
X1337971Y953917D01*
G01X1341670Y956027D02*
Y953918D01*
X1341671Y953917D01*
G01X1341670Y962436D02*
X1341671Y962435D01*
Y960326D01*
G01X1345370Y956027D02*
Y953918D01*
X1345371Y953917D01*
G01X1343521Y965640D02*
X1343520Y965639D01*
Y963530D01*
G01X1339821Y965640D02*
Y963530D01*
G01X1336121Y957122D02*
Y959232D01*
G01X1332421Y965640D02*
Y963530D01*
G01X1334270Y981662D02*
X1334271Y981661D01*
Y979552D01*
G01X1336121Y972049D02*
X1336120Y972048D01*
Y969939D01*
G01X1341670Y975253D02*
Y973144D01*
X1341671Y973143D01*
G01X1341670Y981662D02*
X1341671Y981661D01*
Y979552D01*
G01X1345370Y975253D02*
Y973144D01*
X1345371Y973143D01*
G01X1337970Y975253D02*
Y973143D01*
G01X1336121Y978457D02*
Y976347D01*
G01X1334270Y968845D02*
Y966735D01*
G01X1341670Y968845D02*
Y966735D01*
G01X1332421Y984866D02*
Y982756D01*
G01X1342103Y997574D02*
Y999683D01*
X1342104Y999684D01*
G01X1334703Y997574D02*
Y999683D01*
X1334704Y999684D01*
G01X1331003Y1003983D02*
Y1006093D01*
G01X1345803Y1003983D02*
Y1006092D01*
X1345804Y1006093D01*
G01X1342103Y1003983D02*
Y1006092D01*
X1342104Y1006093D01*
G01X1338403Y1003983D02*
Y1006093D01*
G01X1336554Y1007187D02*
Y1009296D01*
X1336553Y1009297D01*
G01X1336554Y1000778D02*
Y1002888D01*
G01X1342103Y1012501D02*
Y1010391D01*
G01X1334703Y1012501D02*
Y1010391D01*
G01X1332854Y1013595D02*
Y1015705D01*
G01X1343954Y1013595D02*
Y1015704D01*
X1343953Y1015705D01*
G01X1340254Y1013595D02*
Y1015705D01*
G01X1345803Y1023208D02*
G02X1345804Y1025318I2226050J0D01*
G01X1342103Y1023208D02*
G02X1342104Y1025318I2226050J0D01*
G01X1342103Y1016800D02*
G02X1342104Y1018910I2226050J0D01*
G01X1336554Y1026413D02*
Y1028522D01*
X1336553Y1028523D01*
G01X1338403Y1023208D02*
Y1025318D01*
G01X1336554Y1020004D02*
Y1022114D01*
G01X1334703Y1016800D02*
G02X1334704Y1018910I2226051J0D01*
G01X1342103Y1029617D02*
G02X1342104Y1031727I2226050J0D01*
G01X1334703Y1029617D02*
Y1031727D01*
G01X1332854Y1032821D02*
Y1034931D01*
G01X1345803Y1042434D02*
Y1044543D01*
X1345804Y1044544D01*
G01X1342103Y1042434D02*
Y1044543D01*
X1342104Y1044544D01*
G01X1342103Y1036026D02*
Y1038135D01*
X1342104Y1038136D01*
G01X1338403Y1042434D02*
Y1044544D01*
G01X1336554Y1039230D02*
Y1041340D01*
G01X1334703Y1036026D02*
Y1038135D01*
X1334704Y1038136D01*
G01X1332854Y1052047D02*
Y1054157D01*
G01X1342103Y1055251D02*
X1342104Y1055252D01*
Y1057361D01*
G01X1342103Y1048842D02*
X1342104Y1048843D01*
Y1050952D01*
G01X1336554Y1058455D02*
Y1060565D01*
G01X1334703Y1055251D02*
X1334704Y1055252D01*
Y1057361D01*
G01X1334703Y1050952D02*
Y1048842D01*
G01X1345803Y1061660D02*
X1345804Y1061661D01*
Y1063770D01*
G01X1342103Y1061660D02*
X1342104Y1061661D01*
Y1063770D01*
G01X1338403Y1061660D02*
Y1063770D01*
G01X1332854Y1071273D02*
Y1073383D01*
G01X1342103Y1068068D02*
X1342104Y1068069D01*
Y1070178D01*
G01X1342103Y1074477D02*
Y1076586D01*
X1342104Y1076587D01*
G01X1336554Y1064864D02*
Y1066973D01*
X1336553Y1066974D01*
G01X1334703Y1068068D02*
Y1070178D01*
G01Y1074477D02*
Y1076586D01*
X1334704Y1076587D01*
G01X1336554Y1077681D02*
Y1079791D01*
G01X1345803Y1080885D02*
G02X1345804Y1082995I2226050J0D01*
G01X1342103Y1087294D02*
Y1089403D01*
X1342104Y1089404D01*
G01X1342103Y1080885D02*
G02X1342104Y1082995I2226050J0D01*
G01X1338403Y1080885D02*
Y1082995D01*
G01X1336554Y1084090D02*
Y1086199D01*
X1336553Y1086200D01*
G01X1334703Y1087294D02*
Y1089404D01*
G01X1332854Y1090498D02*
Y1092608D01*
G01X1342103Y1093703D02*
Y1095812D01*
X1342104Y1095813D01*
G01X1334703Y1093703D02*
Y1095813D01*
G01X1331003Y1106520D02*
Y1108630D01*
G01X1336554Y1096907D02*
X1336553Y1099017D01*
G01X1332854Y1096907D02*
X1332853Y1099017D01*
G01X1342103Y1125746D02*
Y1127855D01*
X1342104Y1127856D01*
G01X1334703Y1125746D02*
Y1127856D01*
G01X1342103Y1138563D02*
Y1140973D01*
G01X1334703Y1138563D02*
Y1140973D01*
G01X1348573Y1315713D02*
X1347417D01*
X1345732Y1314028D01*
Y1312326D01*
G01X1348573Y1321028D02*
X1347238D01*
X1345826Y1322440D01*
Y1323289D01*
X1343948Y1325167D01*
G01Y1317092D02*
X1343858Y1317002D01*
Y1314667D01*
G01X1348573Y1317485D02*
X1347126D01*
X1344308Y1314667D01*
X1343858D01*
G01X1343948Y1319592D02*
Y1322017D01*
G01X1348573Y1319256D02*
X1347007D01*
X1344246Y1322017D01*
X1343948D01*
G01X1350010Y151438D02*
Y154706D01*
G01X1349704Y145385D02*
Y145995D01*
X1350010Y146301D01*
Y148170D01*
G01X1357888Y145893D02*
Y148170D01*
G01X1350010Y154706D02*
X1351981Y155288D01*
X1353949Y154706D01*
G01X1359858Y153072D02*
X1363462D01*
X1363719Y153329D01*
G01X1357888Y154706D02*
X1359522Y153072D01*
X1359858D01*
G01X1358865Y166732D02*
X1359871Y168225D01*
X1360451Y169085D01*
G01X1358865Y158854D02*
X1360451Y161207D01*
G01X1358865Y162793D02*
X1360185Y164752D01*
X1360451Y165146D01*
G01Y161207D02*
X1358865Y162793D01*
G01X1360451Y157268D02*
X1358865Y158854D01*
G01X1360451Y165146D02*
X1358865Y166732D01*
G01X1349351Y166698D02*
X1350048Y167912D01*
X1350414Y168549D01*
G01X1358865Y170671D02*
X1360451Y173024D01*
G01X1358865Y174603D02*
X1360444Y173024D01*
X1360451D01*
G01Y176963D02*
X1358865Y174603D01*
G01X1360451Y169085D02*
X1358865Y170671D01*
G01X1360451Y180902D02*
X1360447D01*
X1358865Y182484D01*
G01X1360451Y184841D02*
X1362085Y186810D01*
G01X1360451Y188780D02*
X1362085Y186810D01*
G01X1365353D02*
X1362085D01*
G01X1350414Y194449D02*
X1349351Y192598D01*
G01X1356825Y212949D02*
X1358865Y213994D01*
G01X1360451Y208474D02*
X1358865Y207060D01*
G01X1360451Y208474D02*
X1363719D01*
G01X1349351Y214798D02*
X1349781Y215542D01*
X1350128Y216142D01*
X1350421Y216648D01*
X1350414Y216649D01*
G01X1352561Y212948D02*
X1353631Y214798D01*
X1353621D01*
X1353620Y214799D01*
G01X1349351Y211098D02*
X1350421Y212948D01*
X1350414Y212949D01*
G01X1360451Y220291D02*
X1358865Y217934D01*
G01X1363719Y224230D02*
X1362085Y226199D01*
G01D02*
X1365353D01*
G01X1360451Y224230D02*
Y220291D01*
G01X1363719Y224230D02*
X1360451D01*
G01X1361111Y236448D02*
X1359745Y235882D01*
X1358834Y234971D01*
Y234274D01*
X1357888Y233328D01*
G01D02*
X1359858Y231694D01*
G01X1353949Y226792D02*
X1351980Y226210D01*
X1350010Y226792D01*
G01X1357888D02*
X1353949D01*
G01X1359858Y231694D02*
X1357888Y230060D01*
G01D02*
Y226792D01*
G01X1350414Y224049D02*
X1349351Y222198D01*
G01X1378452Y236055D02*
X1376819Y234422D01*
X1372285D01*
X1371584Y235123D01*
X1363622D01*
X1361827Y233328D01*
G01X1358321Y856694D02*
Y854584D01*
G01X1350921Y856694D02*
Y854584D01*
G01X1358321Y869511D02*
Y867401D01*
G01X1350921Y869511D02*
Y867401D01*
G01X1358321Y882329D02*
Y880219D01*
G01X1350921Y882329D02*
Y880219D01*
G01X1347221Y901555D02*
X1347220Y901554D01*
Y899445D01*
G01X1354621Y895146D02*
Y893036D01*
G01X1362021Y899445D02*
Y901555D01*
G01X1354621D02*
X1354620Y901554D01*
Y899445D01*
G01X1347221Y914372D02*
Y912262D01*
G01X1362021Y914372D02*
X1362020Y914371D01*
Y912262D01*
G01X1360170Y909057D02*
Y911167D01*
G01Y904759D02*
X1360171Y904758D01*
Y902649D01*
G01X1358321Y907963D02*
Y905853D01*
G01X1354621Y914372D02*
X1354620Y914371D01*
Y912262D01*
G01X1354621Y907963D02*
X1354620Y907962D01*
Y905853D01*
G01X1350921Y907963D02*
X1350920Y907962D01*
Y905853D01*
G01X1349070Y911167D02*
X1349071Y911166D01*
Y909057D01*
G01X1349070Y904759D02*
Y902649D01*
G01X1347221Y920780D02*
X1347220Y920779D01*
Y918670D01*
G01X1347221Y933598D02*
Y931488D01*
G01X1362021Y920780D02*
Y918670D01*
G01X1360170Y930393D02*
Y928283D01*
G01X1358321Y927189D02*
Y925079D01*
G01X1354621Y927189D02*
X1354620Y927188D01*
Y925079D01*
G01X1354621Y920780D02*
X1354620Y920779D01*
Y918670D01*
G01X1350921Y927189D02*
X1350920Y927188D01*
Y925079D01*
G01X1349070Y930393D02*
X1349071Y930392D01*
Y928283D01*
G01X1349070Y923985D02*
Y921875D01*
G01X1362021Y933598D02*
X1362020Y933597D01*
Y931488D01*
G01X1354621Y933598D02*
X1354620Y933597D01*
Y931488D01*
G01X1354621Y946414D02*
X1354620Y946413D01*
Y944304D01*
G01X1360170Y943210D02*
X1360171Y943209D01*
Y941100D01*
G01X1349070Y949619D02*
X1349071Y949618D01*
Y947509D01*
G01X1350921Y946414D02*
X1350920Y946413D01*
Y944304D01*
G01X1358321Y946414D02*
Y944304D01*
G01X1360170Y949619D02*
Y947509D01*
G01X1349070Y943210D02*
Y941100D01*
G01X1347221Y940006D02*
X1347220Y940005D01*
Y937896D01*
G01X1362021Y940006D02*
Y937896D01*
G01X1354621Y940006D02*
X1354620Y940005D01*
Y937896D01*
G01X1354621Y952823D02*
X1354620Y952822D01*
Y950713D01*
G01X1354621Y959232D02*
X1354620Y959231D01*
Y957122D01*
G01X1360170Y962436D02*
X1360171Y962435D01*
Y960326D01*
G01X1362021Y952823D02*
X1362020Y952822D01*
Y950713D01*
G01X1347221Y959232D02*
X1347220Y959231D01*
Y957122D01*
G01X1354621Y965640D02*
X1354620Y965639D01*
Y963530D01*
G01X1350921Y965640D02*
X1350920Y965639D01*
Y963530D01*
G01X1362021Y959232D02*
Y957122D01*
G01X1358321Y965640D02*
Y963530D01*
G01X1349070Y962436D02*
Y960326D01*
G01X1347221Y952823D02*
Y950713D01*
G01X1352770Y975253D02*
Y973144D01*
X1352771Y973143D01*
G01X1354621Y972049D02*
X1354620Y972048D01*
Y969939D01*
G01X1360170Y981662D02*
X1360171Y981661D01*
Y979552D01*
G01X1362021Y972049D02*
X1362020Y972048D01*
Y969939D01*
G01X1347221Y978457D02*
X1347220Y978456D01*
Y976347D01*
G01X1349070Y968845D02*
X1349071Y968844D01*
Y966735D01*
G01X1362021Y978457D02*
Y976347D01*
G01X1356470Y975253D02*
Y973143D01*
G01X1354621Y978457D02*
Y976347D01*
G01X1349070Y981662D02*
Y979552D01*
G01X1347221Y972049D02*
Y969939D01*
G01X1360170Y968845D02*
Y966735D01*
G01X1354621Y984866D02*
X1354620Y984865D01*
Y982756D01*
G01X1350921Y984866D02*
X1350920Y984865D01*
Y982756D01*
G01X1358321Y984866D02*
Y982756D01*
G01X1349503Y997574D02*
X1351352Y996480D01*
G01X1360603Y997574D02*
Y999683D01*
X1360604Y999684D01*
G01X1347654Y1007187D02*
Y1009297D01*
G01Y1000778D02*
X1349503Y999684D01*
G01X1362454Y1007187D02*
Y1009296D01*
X1362453Y1009297D01*
G01X1362454Y1000778D02*
Y1002888D01*
G01X1355054Y1007187D02*
G03X1355053Y1009297I-2226050J0D01*
G01X1355054Y1000778D02*
Y1002886D01*
G03X1355053Y1002888I-3J0D01*
G01X1360603Y1012501D02*
Y1010391D01*
G01X1349503D02*
G02X1349504Y1012501I2226050J0D01*
G01X1358754Y1013595D02*
Y1015705D01*
G01X1355054Y1013595D02*
G03X1355053Y1015705I-2226050J0D01*
G01X1351354Y1013595D02*
Y1015704D01*
X1351353Y1015705D01*
G01X1347654Y1026413D02*
Y1028522D01*
X1347653Y1028523D01*
G01X1347654Y1020004D02*
G03X1347653Y1022114I-2226050J0D01*
G01X1362454Y1026413D02*
Y1028522D01*
X1362453Y1028523D01*
G01X1362454Y1020004D02*
Y1022114D01*
G01X1360603Y1016800D02*
Y1018909D01*
X1360604Y1018910D01*
G01X1355054Y1026413D02*
Y1028522D01*
X1355053Y1028523D01*
G01X1355054Y1020004D02*
G03X1355053Y1022114I-2226050J0D01*
G01X1349503Y1016800D02*
Y1018910D01*
G01X1360603Y1029617D02*
Y1031727D01*
G01X1349503Y1029617D02*
G02X1349504Y1031727I2226050J0D01*
G01X1362454Y1039230D02*
Y1041340D01*
G01X1360603Y1036026D02*
G02X1360604Y1038136I2226051J0D01*
G01X1358754Y1032821D02*
Y1034931D01*
G01X1355054Y1032821D02*
G03X1355053Y1034931I-2226050J0D01*
G01X1351354Y1032821D02*
G03X1351353Y1034931I-2226050J0D01*
G01X1349503Y1036026D02*
Y1038136D01*
G01X1347654Y1058455D02*
Y1060564D01*
X1347653Y1060565D01*
G01X1362454Y1058455D02*
Y1060565D01*
G01X1360603Y1055251D02*
X1360604Y1055252D01*
Y1057361D01*
G01X1360603Y1048842D02*
Y1050952D01*
G01X1358754Y1052047D02*
Y1054157D01*
G01X1355054Y1058455D02*
Y1060564D01*
X1355053Y1060565D01*
G01X1355054Y1052047D02*
X1355053Y1052048D01*
Y1054157D01*
G01X1351354Y1052047D02*
X1351353Y1052048D01*
Y1054157D01*
G01X1349503Y1055251D02*
Y1057361D01*
G01Y1048842D02*
X1349504Y1048843D01*
Y1050952D01*
G01X1347654Y1064864D02*
Y1066974D01*
G01Y1077681D02*
G03X1347653Y1079791I-2226050J0D01*
G01X1362454Y1064864D02*
Y1066973D01*
X1362453Y1066974D01*
G01X1360603Y1074477D02*
G02X1360604Y1076587I2226051J0D01*
G01X1360603Y1068068D02*
Y1070178D01*
G01X1358754Y1071273D02*
Y1073383D01*
G01X1355054Y1071273D02*
Y1073382D01*
X1355053Y1073383D01*
G01X1355054Y1064864D02*
G03X1355053Y1066974I-2226050J0D01*
G01X1351354Y1071273D02*
Y1073382D01*
X1351353Y1073383D01*
G01X1349503Y1074477D02*
Y1076587D01*
G01Y1068068D02*
X1349504Y1068069D01*
Y1070178D01*
G01X1362454Y1077681D02*
G03X1362453Y1079791I-2226050J0D01*
G01X1355054Y1077681D02*
G03X1355053Y1079791I-2226050J0D01*
G01X1347654Y1084090D02*
Y1086200D01*
G01X1362454Y1084090D02*
Y1086199D01*
X1362453Y1086200D01*
G01X1360603Y1087294D02*
Y1089404D01*
G01X1358754Y1090498D02*
G03X1358753Y1092608I-2226050J0D01*
G01X1355054Y1090498D02*
G03X1355053Y1092608I-2226050J0D01*
G01X1355054Y1084090D02*
Y1086199D01*
X1355053Y1086200D01*
G01X1351354Y1090498D02*
G03X1351353Y1092608I-2226050J0D01*
G01X1349503Y1087294D02*
Y1089403D01*
X1349504Y1089404D01*
G01X1349503Y1093703D02*
Y1095812D01*
X1349504Y1095813D01*
G01X1360603Y1112929D02*
Y1115039D01*
G01X1353203Y1112929D02*
Y1115039D01*
G01X1349503Y1112929D02*
Y1115039D01*
G01X1356903Y1125746D02*
Y1127856D01*
G01X1349503Y1125746D02*
Y1127856D01*
G01X1356903Y1138563D02*
Y1140973D01*
G01X1349503Y1138563D02*
Y1140973D01*
G01X1362145Y1329843D02*
Y1328572D01*
X1360817Y1327244D01*
Y1325260D01*
G01X1366170Y1332993D02*
X1362145D01*
G01X1364407Y150750D02*
X1366987D01*
G01X1369593Y147462D02*
Y148657D01*
X1367500Y150750D01*
X1366987D01*
G01X1363719Y153329D02*
Y151438D01*
X1364407Y150750D01*
G01X1365353Y155299D02*
Y154963D01*
X1363719Y153329D01*
G01X1366987D02*
Y153665D01*
X1365353Y155299D01*
G01X1369916Y154132D02*
X1369113Y153329D01*
X1366987D01*
G01X1369479Y208384D02*
X1368669D01*
X1368579Y208474D01*
X1366987D01*
G01D02*
X1365929Y208912D01*
X1364777D01*
X1363719Y208474D01*
G01X1364407Y230748D02*
X1366987D01*
G01D02*
Y228169D01*
G01X1370636Y227292D02*
X1369544D01*
X1368667Y228169D01*
X1366987D01*
G01X1363719Y224230D02*
X1365353Y226199D01*
G01X1366987Y228169D02*
X1365353Y226199D01*
G01X1363719Y228169D02*
X1365353Y226199D01*
G01X1366987Y228169D02*
X1363719D01*
G01X1369410Y224504D02*
X1367261D01*
X1366987Y224230D01*
G01X1369421Y850286D02*
Y848178D01*
X1369420Y848177D01*
Y848176D01*
G01X1373121Y856694D02*
Y854584D01*
G01X1365721Y856694D02*
Y854584D01*
G01X1373121Y869511D02*
Y867401D01*
G01X1365721Y869511D02*
Y867401D01*
G01X1373121Y882329D02*
Y880219D01*
G01X1365721Y882329D02*
Y880219D01*
G01X1376821Y875920D02*
Y873811D01*
X1376820Y873810D01*
G01X1363870Y898350D02*
X1363871Y898349D01*
Y896240D01*
G01X1371270Y898350D02*
X1371271Y898349D01*
Y896240D01*
G01X1367570Y898350D02*
Y896240D01*
G01X1365721Y895146D02*
Y893036D01*
G01X1373121Y901555D02*
X1373120Y901554D01*
Y899445D01*
G01X1363870Y917576D02*
Y915466D01*
G01X1374970Y911167D02*
X1374971Y911166D01*
Y909057D01*
G01X1374970Y904759D02*
Y902649D01*
G01X1373121Y914372D02*
Y912262D01*
G01X1367570Y911167D02*
X1367571Y911166D01*
Y909057D01*
G01X1367570Y904759D02*
X1367571Y904758D01*
Y902649D01*
G01X1376821Y927189D02*
X1376820Y925079D01*
G01X1374970Y930393D02*
X1374971Y930392D01*
Y928283D01*
G01X1374970Y923985D02*
Y921875D01*
G01X1373121Y920780D02*
X1373120Y920779D01*
Y918670D01*
G01X1367570Y930393D02*
X1367571Y930392D01*
Y928283D01*
G01X1376821Y940006D02*
X1376820Y940005D01*
Y937896D01*
G01X1374970Y943210D02*
Y941100D01*
G01X1373121Y940006D02*
X1373120Y940005D01*
Y937896D01*
G01X1367570Y943210D02*
X1367571Y943209D01*
Y941100D01*
G01X1367570Y949619D02*
X1367571Y949618D01*
Y947509D01*
G01X1363870Y956027D02*
Y953918D01*
X1363871Y953917D01*
G01X1374970Y962436D02*
Y960326D01*
G01X1367570Y962436D02*
X1367571Y962435D01*
Y960326D01*
G01X1367570Y956027D02*
Y953918D01*
X1367571Y953917D01*
G01X1376821Y965640D02*
X1376820Y965639D01*
Y963530D01*
G01X1363870Y975253D02*
Y973143D01*
G01X1374970Y968845D02*
X1374971Y968844D01*
Y966735D01*
G01X1367570Y968845D02*
X1367571Y968844D01*
Y966735D01*
G01X1376821Y972049D02*
Y969940D01*
X1376820Y969939D01*
G01X1374970Y981662D02*
Y979552D01*
G01X1373121Y978457D02*
X1373120Y978456D01*
Y976347D01*
G01X1373121Y972049D02*
Y969939D01*
G01X1371270Y975253D02*
Y973144D01*
X1371271Y973143D01*
G01X1367570Y981662D02*
X1367571Y981661D01*
Y979552D01*
G01X1367570Y975253D02*
Y973144D01*
X1367571Y973143D01*
G01X1376821Y984866D02*
X1376820Y984865D01*
Y982756D01*
G01X1368003Y997574D02*
Y999683D01*
X1368004Y999684D01*
G01X1364303Y1003983D02*
Y1006093D01*
G01X1377254Y1000778D02*
Y1002886D01*
G03X1377253Y1002888I-3J0D01*
G01X1373554Y1007187D02*
Y1009297D01*
G01Y1000778D02*
Y1002886D01*
G03X1373553Y1002888I-3J0D01*
G01X1371703Y1003983D02*
Y1006092D01*
X1371704Y1006093D01*
G01X1368003Y1003983D02*
Y1006092D01*
X1368004Y1006093D01*
G01X1375403Y1010391D02*
X1375404Y1010392D01*
Y1012501D01*
G01X1368003D02*
Y1010391D01*
G01X1369854Y1013595D02*
Y1015704D01*
X1369853Y1015705D01*
G01X1366154Y1013595D02*
Y1015705D01*
G01X1364303Y1023208D02*
Y1025318D01*
G01X1368003Y1023208D02*
Y1025317D01*
X1368004Y1025318D01*
G01X1368003Y1016800D02*
Y1018909D01*
X1368004Y1018910D01*
G01X1364303Y1042434D02*
Y1044544D01*
G01X1368003Y1042434D02*
Y1044543D01*
X1368004Y1044544D01*
G01X1368003Y1036026D02*
G02X1368004Y1038136I2226050J0D01*
G01X1375403Y1055251D02*
Y1057361D01*
G01X1373554Y1058455D02*
X1373553Y1058456D01*
Y1060565D01*
G01X1368003Y1055251D02*
X1368004Y1055252D01*
Y1057361D01*
G01X1368003Y1048842D02*
G02X1368004Y1050952I2226050J0D01*
G01X1364303Y1061660D02*
Y1063770D01*
G01X1371703Y1061660D02*
Y1063769D01*
X1371704Y1063770D01*
G01X1368003Y1061660D02*
X1368004Y1061661D01*
Y1063770D01*
G01X1377254Y1071273D02*
Y1073382D01*
X1377253Y1073383D01*
G01X1375403Y1074477D02*
Y1076587D01*
G01Y1068068D02*
X1375404Y1068069D01*
Y1070178D01*
G01X1373554Y1064864D02*
Y1066974D01*
G01X1368003Y1074477D02*
G02X1368004Y1076587I2226050J0D01*
G01X1368003Y1068068D02*
X1368004Y1068069D01*
Y1070178D01*
G01X1364303Y1080885D02*
Y1082995D01*
G01X1368003Y1087294D02*
Y1089403D01*
X1368004Y1089404D01*
G01X1368003Y1080885D02*
G02X1368004Y1082995I2226050J0D01*
G01X1375403Y1093703D02*
Y1095813D01*
G01X1368003Y1093703D02*
Y1095812D01*
X1368004Y1095813D01*
G01X1377254Y1103316D02*
Y1105425D01*
X1377253Y1105426D01*
G01X1375403Y1100111D02*
Y1102220D01*
X1375404Y1102221D01*
G01X1373554Y1096907D02*
Y1099017D01*
G01Y1109724D02*
X1373553Y1111834D01*
G01X1366154Y1109724D02*
X1366153Y1111834D01*
G01X1364303Y1112929D02*
Y1115039D01*
G01Y1125746D02*
Y1127856D01*
G01X1379103Y1125746D02*
Y1127856D01*
G01X1371703Y1125746D02*
Y1127856D01*
G01X1364303Y1138563D02*
Y1140973D01*
G01X1379103Y1138563D02*
Y1140973D01*
G01X1371703Y1138563D02*
Y1140973D01*
G01X1380701Y1315713D02*
X1379437D01*
X1377860Y1314136D01*
Y1312326D01*
G01X1380701Y1321028D02*
X1379314D01*
X1377954Y1322388D01*
Y1323289D01*
X1376076Y1325167D01*
G01Y1317092D02*
Y1314667D01*
G01X1380701Y1317485D02*
X1379254D01*
X1376436Y1314667D01*
X1376076D01*
G01Y1319592D02*
Y1322017D01*
G01X1380701Y1319256D02*
X1379173D01*
X1376412Y1322017D01*
X1376076D01*
G01X1380521Y856694D02*
Y854584D01*
G01X1395321Y856694D02*
Y854584D01*
G01X1387921Y856694D02*
Y854584D01*
G01X1380521Y869511D02*
Y867401D01*
G01X1395321Y869511D02*
Y867401D01*
G01X1387921Y869511D02*
Y867401D01*
G01X1380521Y882329D02*
Y880219D01*
G01X1395321Y882329D02*
Y880219D01*
G01X1387921Y882329D02*
Y880219D01*
G01X1384221Y875920D02*
Y873811D01*
X1384220Y873810D01*
G01X1395321Y895146D02*
Y893036D01*
G01X1386070Y904759D02*
X1386071Y904758D01*
Y902649D01*
G01X1380521Y914372D02*
Y912263D01*
X1380520Y912262D01*
G01X1380521Y907963D02*
X1380520Y907962D01*
Y905853D01*
G01X1395321Y914372D02*
X1395320Y914371D01*
Y912262D01*
G01X1395321Y907963D02*
Y905853D01*
G01X1393470Y904759D02*
X1393471Y904758D01*
Y902649D01*
G01X1389770Y904759D02*
X1389771Y904758D01*
Y902649D01*
G01X1386070Y911167D02*
X1386071Y911166D01*
Y909057D01*
G01X1386070Y917576D02*
X1386071Y917575D01*
Y915466D01*
G01X1384221Y907963D02*
X1384220Y907962D01*
Y905853D01*
G01X1387921Y907963D02*
X1387920Y907962D01*
Y905853D01*
G01X1380521Y920780D02*
X1380520Y920779D01*
Y918670D01*
G01X1395321Y920780D02*
X1395320Y920779D01*
Y918670D01*
G01X1386070Y923985D02*
X1386071Y923984D01*
Y921875D01*
G01X1380954Y1045639D02*
X1380953D01*
Y1047749D01*
G01X1388354Y1045639D02*
X1388353D01*
Y1047749D01*
G01X1380954Y1058455D02*
X1380953Y1058456D01*
Y1060565D01*
G01X1393903Y1048842D02*
X1393904Y1048843D01*
Y1050952D01*
G01X1386503Y1048842D02*
X1386504Y1048843D01*
Y1050952D01*
G01X1380954Y1064864D02*
X1380953Y1064865D01*
Y1066974D01*
G01X1395754Y1071273D02*
Y1073382D01*
X1395753Y1073383D01*
G01X1386503Y1074477D02*
Y1076586D01*
X1386504Y1076587D01*
G01X1386503Y1068068D02*
X1386504Y1068069D01*
Y1070178D01*
G01X1382803Y1074477D02*
Y1076587D01*
G01X1380954Y1077681D02*
Y1079790D01*
X1380953Y1079791D01*
G01X1388354Y1077681D02*
Y1079790D01*
X1388353Y1079791D01*
G01X1393903Y1087294D02*
Y1089404D01*
G01X1392054Y1090498D02*
Y1092606D01*
X1392053Y1092607D01*
Y1092608D01*
G01X1392054Y1084090D02*
Y1086200D01*
G01X1388354Y1090498D02*
Y1092606D01*
X1388353Y1092607D01*
Y1092608D01*
G01X1384654Y1084090D02*
Y1086199D01*
X1384653Y1086200D01*
G01X1386503Y1093703D02*
Y1095812D01*
X1386504Y1095813D01*
G01X1380954Y1103316D02*
Y1105426D01*
G01X1390203Y1106520D02*
X1390204Y1108630D01*
G01X1388354Y1096907D02*
Y1099016D01*
X1388353Y1099017D01*
G01X1386503Y1100111D02*
Y1102220D01*
X1386504Y1102221D01*
G01X1382803Y1106520D02*
Y1108630D01*
G01Y1100111D02*
Y1102221D01*
G01X1380954Y1109724D02*
Y1111834D01*
G01X1386503Y1112929D02*
Y1115039D01*
G01X1382803Y1112929D02*
Y1115039D01*
G01X1392054Y1122541D02*
Y1124651D01*
G01X1393903Y1119337D02*
Y1121447D01*
G01Y1125746D02*
Y1127856D01*
G01X1390203Y1138563D02*
Y1140973D01*
G01X1392054Y1128950D02*
Y1131060D01*
G01Y1135359D02*
Y1137469D01*
G01X1393903Y1132154D02*
Y1134264D01*
G01Y1138563D02*
Y1140973D01*
G01X1393245Y1329843D02*
X1392945Y1329543D01*
Y1325260D01*
G01X1397365Y1332993D02*
X1393245D01*
G01X1397365Y1329843D02*
X1394717Y1327195D01*
Y1325260D01*
G01X1402721Y856694D02*
Y854584D01*
G01X1410121Y856694D02*
Y854584D01*
G01Y869511D02*
Y867401D01*
G01X1402721Y869511D02*
Y867401D01*
G01X1406421Y863103D02*
Y860994D01*
X1406420Y860993D01*
G01X1410121Y882329D02*
Y880219D01*
G01X1402721Y882329D02*
Y880219D01*
G01X1410121Y895146D02*
Y893036D01*
G01X1402721Y895146D02*
Y893036D01*
G01X1400870Y904759D02*
X1400871Y904758D01*
Y902649D01*
G01X1397170Y904759D02*
X1397171Y904758D01*
Y902649D01*
G01X1408270Y904759D02*
X1408271Y904758D01*
Y902649D01*
G01X1404570Y911167D02*
X1404571Y911166D01*
Y909057D01*
G01X1404570Y904759D02*
X1404571Y904758D01*
Y902649D01*
G01X1411971Y904759D02*
Y902649D01*
G01X1404570Y917576D02*
Y915467D01*
X1404571Y915466D01*
G01X1410121Y927189D02*
Y925079D01*
G01Y933598D02*
Y931488D01*
G01X1404570Y923985D02*
X1404571Y923984D01*
Y921875D01*
G01X1406421Y946414D02*
Y944304D01*
G01X1411971Y943210D02*
Y941100D01*
G01X1408270Y949619D02*
Y947509D01*
G01X1411971Y949619D02*
Y947509D01*
G01X1408270Y943210D02*
Y941101D01*
X1408271Y941100D01*
G01X1406421Y952823D02*
Y950713D01*
G01Y959232D02*
Y957122D01*
G01X1408270Y956027D02*
Y953917D01*
G01Y962436D02*
Y960326D01*
G01X1411971Y956027D02*
Y953917D01*
G01Y962436D02*
Y960326D01*
G01X1406421Y965640D02*
Y963530D01*
G01Y972049D02*
Y969939D01*
G01X1408270Y968845D02*
Y966735D01*
G01Y975253D02*
Y973143D01*
G01X1411971Y968845D02*
Y966735D01*
G01Y975253D02*
Y973143D01*
G01X1408270Y981662D02*
Y979552D01*
G01X1411971Y981662D02*
Y979552D01*
G01X1406421Y978457D02*
Y976359D01*
X1406409Y976347D01*
G01X1406421Y984866D02*
Y982756D01*
G01X1408703Y997574D02*
Y999684D01*
G01X1406853Y1000778D02*
Y1002888D01*
G01Y1007187D02*
Y1009297D01*
G01X1408703Y1003983D02*
Y1006093D01*
G01Y1010391D02*
Y1012501D01*
G01X1406853Y1013595D02*
Y1015705D01*
G01Y1026412D02*
Y1026413D01*
G01D02*
Y1028523D01*
G01Y1020004D02*
Y1022114D01*
G01X1408703Y1016800D02*
Y1018910D01*
G01Y1023208D02*
Y1025318D01*
G01Y1029617D02*
Y1031727D01*
G01X1399454Y1045639D02*
Y1047748D01*
X1399453Y1047749D01*
G01X1406853Y1032821D02*
Y1034931D01*
G01Y1039230D02*
Y1041340D01*
G01X1408703Y1036026D02*
Y1038136D01*
G01Y1042434D02*
Y1044544D01*
G01X1410554Y1039230D02*
Y1041340D01*
G01X1401303Y1055251D02*
Y1057360D01*
X1401304Y1057361D01*
G01X1397603Y1061660D02*
Y1063769D01*
X1397604Y1063770D01*
G01X1406853Y1071273D02*
Y1073383D01*
G01X1403154Y1071273D02*
Y1073382D01*
X1403153Y1073383D01*
G01X1403154Y1064864D02*
Y1066973D01*
X1403153Y1066974D01*
G01X1401303Y1074477D02*
Y1076586D01*
X1401304Y1076587D01*
G01X1399454Y1064864D02*
Y1066973D01*
X1399453Y1066974D01*
G01X1403154Y1077681D02*
Y1079791D01*
G01X1401303Y1087294D02*
Y1089403D01*
X1401304Y1089404D01*
G01X1403154Y1103316D02*
Y1105426D01*
G01Y1109724D02*
Y1111834D01*
G01X1405003Y1100111D02*
Y1102221D01*
G01Y1106520D02*
Y1108630D01*
G01X1406853Y1096907D02*
Y1099017D01*
G01Y1103316D02*
Y1105426D01*
G01Y1109724D02*
Y1111834D01*
G01X1408703Y1100111D02*
Y1102221D01*
G01Y1106520D02*
Y1108630D01*
G01X1401303Y1106520D02*
Y1108629D01*
X1401304Y1108630D01*
G01X1395754Y1122541D02*
Y1124651D01*
G01X1397603Y1119337D02*
Y1121447D01*
G01Y1125746D02*
Y1127856D01*
G01X1403154Y1116133D02*
Y1118243D01*
G01Y1122541D02*
Y1124651D01*
G01X1405003Y1112929D02*
Y1115039D01*
G01Y1119337D02*
Y1121447D01*
G01Y1125746D02*
Y1127856D01*
G01X1406853Y1116133D02*
Y1118243D01*
G01Y1122541D02*
Y1124651D01*
G01X1408703Y1112929D02*
Y1115039D01*
G01Y1119337D02*
Y1121447D01*
G01Y1125746D02*
Y1127856D01*
G01X1401303Y1125746D02*
Y1127855D01*
X1401304Y1127856D01*
G01X1401303Y1119337D02*
Y1121446D01*
X1401304Y1121447D01*
G01X1401303Y1112929D02*
Y1115038D01*
X1401304Y1115039D01*
G01X1395754Y1128950D02*
Y1131060D01*
G01Y1135359D02*
Y1137469D01*
G01X1397603Y1132154D02*
Y1134264D01*
G01Y1138563D02*
Y1140973D01*
G01X1401303Y1138563D02*
Y1140973D01*
G01X1403154Y1128950D02*
Y1131060D01*
G01Y1135359D02*
Y1137569D01*
G01X1405003Y1132154D02*
Y1134264D01*
G01Y1138563D02*
Y1140973D01*
G01X1406853Y1128950D02*
Y1131060D01*
G01X1408703Y1132154D02*
Y1134264D01*
G01X1401303Y1132154D02*
Y1134263D01*
X1401304Y1134264D01*
G01X1412829Y1315713D02*
X1411511D01*
X1409988Y1314190D01*
Y1312326D01*
G01X1408204Y1325167D02*
X1410082Y1323289D01*
Y1322388D01*
X1411442Y1321028D01*
X1412829D01*
G01X1408204Y1317092D02*
Y1314667D01*
G01D02*
X1408564D01*
X1411382Y1317485D01*
X1412829D01*
G01X1408204Y1322017D02*
X1408540D01*
X1411301Y1319256D01*
X1412829D01*
G01X1408204Y1319592D02*
Y1322017D01*
G01X1421221Y850286D02*
Y848177D01*
X1421220Y848176D01*
G01X1417521Y850286D02*
Y848177D01*
X1417520Y848176D01*
G01X1417521Y854584D02*
Y856694D01*
G01X1415670Y859899D02*
Y857790D01*
X1415671Y857789D01*
G01X1424921Y869511D02*
Y867401D01*
G01X1417521Y869511D02*
Y867401D01*
G01X1424921Y880219D02*
Y882329D01*
G01X1417521D02*
Y880219D01*
G01X1424921Y895146D02*
Y893036D01*
G01X1417521Y895146D02*
Y893036D01*
G01X1415670Y898350D02*
X1415671Y898349D01*
Y896240D01*
G01X1413821Y899445D02*
Y901555D01*
G01Y914372D02*
X1413820Y914371D01*
Y912262D01*
G01X1413821Y907963D02*
Y905853D01*
G01X1426771Y904759D02*
Y902649D01*
G01X1423070Y911167D02*
X1423071Y911166D01*
Y909057D01*
G01X1423070Y904759D02*
X1423071Y904758D01*
Y902649D01*
G01X1419370Y904759D02*
X1419371Y904758D01*
Y902649D01*
G01X1415670Y904759D02*
Y902649D01*
G01X1423070Y917576D02*
Y915467D01*
X1423071Y915466D01*
G01X1417521Y927189D02*
X1417520Y927188D01*
Y925079D01*
G01X1423070Y930393D02*
X1423071Y930392D01*
Y928283D01*
G01X1417521Y933598D02*
X1417520Y933597D01*
Y931488D01*
G01X1413821Y920780D02*
X1413820Y920779D01*
Y918670D01*
G01X1423070Y923985D02*
X1423071Y923984D01*
Y921875D01*
G01X1413821Y946414D02*
Y944304D01*
G01X1417521Y946414D02*
Y944304D01*
G01X1424921Y946414D02*
Y944304D01*
G01X1426771Y943210D02*
Y941100D01*
G01X1415670Y949619D02*
Y947509D01*
G01X1419370Y949619D02*
Y947509D01*
G01X1426771D02*
Y949619D01*
G01X1421221Y946414D02*
Y944305D01*
X1421220Y944304D01*
G01X1419370Y943210D02*
Y941101D01*
X1419371Y941100D01*
G01X1415670Y943210D02*
Y941101D01*
X1415671Y941100D01*
G01X1413821Y952823D02*
Y950713D01*
G01Y959232D02*
Y957122D01*
G01X1415670Y956027D02*
Y953917D01*
G01Y962436D02*
Y960326D01*
G01X1417521Y952823D02*
Y950713D01*
G01Y959232D02*
Y957122D01*
G01X1419370Y956027D02*
Y953917D01*
G01Y962436D02*
Y960326D01*
G01X1424921Y952823D02*
Y950713D01*
G01Y957122D02*
Y959232D01*
G01X1426771Y956027D02*
Y953917D01*
G01Y962436D02*
Y960326D01*
G01X1413821Y965640D02*
Y963530D01*
G01X1417521Y965640D02*
Y963530D01*
G01X1424921Y965640D02*
Y963530D01*
G01X1421221Y965640D02*
Y963531D01*
X1421220Y963530D01*
G01X1421221Y959232D02*
Y957123D01*
X1421220Y957122D01*
G01X1421221Y952823D02*
Y950714D01*
X1421220Y950713D01*
G01X1413821Y972049D02*
Y969939D01*
G01Y978457D02*
Y976347D01*
G01X1415670Y968845D02*
Y966735D01*
G01Y975253D02*
Y973143D01*
G01X1417521Y972049D02*
Y969939D01*
G01Y978457D02*
Y976347D01*
G01X1419370Y968845D02*
Y966735D01*
G01Y975253D02*
Y973143D01*
G01X1424921Y972049D02*
Y969939D01*
G01Y978457D02*
Y976347D01*
G01X1426771Y966735D02*
Y968845D01*
G01Y975253D02*
Y973143D01*
G01X1415670Y981662D02*
Y979552D01*
G01X1419370Y981662D02*
Y979552D01*
G01X1426771D02*
Y981662D01*
G01X1421221Y978457D02*
Y976348D01*
X1421220Y976347D01*
G01X1421221Y972049D02*
Y969940D01*
X1421220Y969939D01*
G01X1413821Y984866D02*
Y982756D01*
G01X1417521Y984866D02*
Y982756D01*
G01X1424921Y984866D02*
Y982756D01*
G01X1416103Y997574D02*
Y999684D01*
G01X1419803Y997574D02*
Y999684D01*
G01X1427203Y997574D02*
Y999684D01*
G01X1412403Y997574D02*
Y999683D01*
X1412404Y999684D01*
G01X1421221Y984866D02*
Y982757D01*
X1421220Y982756D01*
G01X1414254Y1000778D02*
Y1002888D01*
G01Y1007187D02*
Y1009297D01*
G01X1416103Y1003983D02*
Y1006093D01*
G01Y1010391D02*
Y1012501D01*
G01X1417954Y1000778D02*
Y1002888D01*
G01Y1007187D02*
Y1009297D01*
G01X1419803Y1003983D02*
Y1006093D01*
G01Y1010391D02*
Y1012501D01*
G01X1421653Y1000778D02*
Y1002888D01*
G01Y1007187D02*
Y1009297D01*
G01X1425354Y1000778D02*
Y1002888D01*
G01Y1007187D02*
Y1009297D01*
G01X1427203Y1003983D02*
Y1006093D01*
G01Y1010391D02*
Y1012501D01*
G01X1414254Y1013595D02*
Y1015705D01*
G01X1417954Y1013595D02*
Y1015705D01*
G01X1421653Y1013595D02*
Y1015705D01*
G01X1425354Y1013595D02*
Y1015705D01*
G01X1412403Y1010391D02*
Y1012500D01*
X1412404Y1012501D01*
G01X1412403Y1003983D02*
Y1006092D01*
X1412404Y1006093D01*
G01X1421653Y1026412D02*
Y1026413D01*
G01X1414254Y1026412D02*
Y1026413D01*
G01X1417954Y1026412D02*
Y1026413D01*
G01X1425354Y1026412D02*
Y1026413D01*
G01X1421653D02*
Y1028523D01*
G01X1414254Y1026413D02*
Y1028523D01*
G01X1417954Y1026413D02*
Y1028523D01*
G01X1425354Y1026413D02*
Y1028523D01*
G01X1414254Y1020004D02*
Y1022114D01*
G01X1416103Y1016800D02*
Y1018910D01*
G01X1417954Y1020004D02*
Y1022114D01*
G01X1419803Y1016800D02*
Y1018910D01*
G01X1421653Y1020004D02*
Y1022114D01*
G01X1425354Y1020004D02*
Y1022114D01*
G01X1427203Y1016800D02*
Y1018910D01*
G01X1416103Y1023208D02*
Y1025318D01*
G01X1419803Y1023208D02*
Y1025318D01*
G01X1427203Y1023208D02*
Y1025318D01*
G01X1416103Y1029617D02*
Y1031727D01*
G01X1419803Y1029617D02*
Y1031727D01*
G01X1427203Y1029617D02*
Y1031727D01*
G01X1412403Y1029617D02*
Y1031726D01*
X1412404Y1031727D01*
G01X1412403Y1023208D02*
Y1025317D01*
X1412404Y1025318D01*
G01X1412403Y1016800D02*
Y1018909D01*
X1412404Y1018910D01*
G01X1425354Y1045639D02*
X1425353Y1047749D01*
G01X1414254Y1045638D02*
Y1045639D01*
G01X1417954Y1045638D02*
Y1045639D01*
G01X1421653Y1045638D02*
Y1045639D01*
G01X1412403Y1036026D02*
Y1038136D01*
G01Y1042434D02*
Y1044544D01*
G01X1414254Y1032821D02*
Y1034931D01*
G01Y1039230D02*
Y1041340D01*
G01X1416103Y1036026D02*
Y1038136D01*
G01Y1042434D02*
Y1044544D01*
G01X1417954Y1032821D02*
Y1034931D01*
G01Y1039230D02*
Y1041340D01*
G01X1419803Y1036026D02*
Y1038136D01*
G01Y1042434D02*
Y1044544D01*
G01X1421653Y1032821D02*
Y1034931D01*
G01Y1039230D02*
Y1041340D01*
G01X1423503Y1042434D02*
Y1044544D01*
G01X1425354Y1032821D02*
Y1034931D01*
G01X1427203Y1036026D02*
Y1038136D01*
G01X1421653Y1045639D02*
Y1047749D01*
G01X1414254Y1045639D02*
Y1047749D01*
G01X1417954Y1045639D02*
Y1047749D01*
G01X1425354Y1039230D02*
Y1041339D01*
X1425353Y1041340D01*
G01X1414254Y1052047D02*
Y1054157D01*
G01X1416103Y1048842D02*
Y1050952D01*
G01X1417954Y1052047D02*
Y1054157D01*
G01X1419803Y1048842D02*
Y1050952D01*
G01X1421653Y1052047D02*
Y1054157D01*
G01X1414254Y1058455D02*
Y1060565D01*
G01X1416103Y1055251D02*
Y1057361D01*
G01X1417954Y1058455D02*
Y1060565D01*
G01X1419803Y1055251D02*
Y1057361D01*
G01X1421653Y1058455D02*
Y1060565D01*
G01X1416103Y1061660D02*
Y1063770D01*
G01X1419803Y1061660D02*
Y1063770D01*
G01X1412403Y1061660D02*
Y1063769D01*
X1412404Y1063770D01*
G01X1412403Y1055251D02*
Y1057360D01*
X1412404Y1057361D01*
G01X1412403Y1048842D02*
Y1050951D01*
X1412404Y1050952D01*
G01X1425354Y1071273D02*
X1425353Y1073383D01*
G01X1414254Y1064864D02*
Y1066974D01*
G01Y1071273D02*
Y1073383D01*
G01X1416103Y1068068D02*
Y1070178D01*
G01Y1074477D02*
Y1076587D01*
G01X1417954Y1064864D02*
Y1066974D01*
G01Y1071273D02*
Y1073383D01*
G01X1419803Y1068068D02*
Y1070178D01*
G01Y1074477D02*
Y1076587D01*
G01X1421653Y1064864D02*
Y1066974D01*
G01Y1071273D02*
Y1073383D01*
G01X1414254Y1077681D02*
Y1079791D01*
G01X1417954Y1077681D02*
Y1079791D01*
G01X1421653Y1077681D02*
Y1079791D01*
G01X1412403Y1074477D02*
Y1076586D01*
X1412404Y1076587D01*
G01X1412403Y1068068D02*
Y1070177D01*
X1412404Y1070178D01*
G01X1412403Y1093703D02*
Y1095813D01*
G01X1416103Y1080885D02*
Y1082995D01*
G01X1419803Y1080885D02*
Y1082995D01*
G01X1414254Y1084090D02*
Y1086200D01*
G01Y1090498D02*
Y1092608D01*
G01X1416103Y1087294D02*
Y1089404D01*
G01Y1093703D02*
Y1095813D01*
G01X1417954Y1084090D02*
Y1086200D01*
G01Y1090498D02*
Y1092608D01*
G01X1419803Y1087294D02*
Y1089404D01*
G01Y1093703D02*
Y1095813D01*
G01X1421653Y1084090D02*
Y1086200D01*
G01Y1090498D02*
Y1092608D01*
G01X1423503Y1087294D02*
Y1089404D01*
G01X1425354Y1090498D02*
Y1092607D01*
X1425353Y1092608D01*
G01X1412403Y1087294D02*
Y1089403D01*
X1412404Y1089404D01*
G01X1412403Y1080885D02*
Y1082994D01*
X1412404Y1082995D01*
G01X1414254Y1096907D02*
Y1099017D01*
G01Y1103316D02*
Y1105426D01*
G01Y1109724D02*
Y1111834D01*
G01X1416103Y1100111D02*
Y1102221D01*
G01Y1106520D02*
Y1108630D01*
G01X1417954Y1096907D02*
Y1099017D01*
G01Y1103316D02*
Y1105426D01*
G01Y1109724D02*
Y1111834D01*
G01X1419803Y1100111D02*
Y1102221D01*
G01Y1106520D02*
Y1108630D01*
G01X1421653Y1096907D02*
Y1099017D01*
G01Y1103316D02*
Y1105426D01*
G01Y1109724D02*
Y1111834D01*
G01X1425354Y1096907D02*
Y1099017D01*
G01Y1103316D02*
Y1105426D01*
G01Y1109724D02*
Y1111834D01*
G01X1427203Y1100111D02*
Y1102221D01*
G01Y1106520D02*
Y1108630D01*
G01X1412403Y1106520D02*
Y1108629D01*
X1412404Y1108630D01*
G01X1412403Y1100111D02*
Y1102220D01*
X1412404Y1102221D01*
G01X1414254Y1116133D02*
Y1118243D01*
G01Y1122541D02*
Y1124651D01*
G01X1416103Y1112929D02*
Y1115039D01*
G01Y1119337D02*
Y1121447D01*
G01Y1125746D02*
Y1127856D01*
G01X1417954Y1116133D02*
Y1118243D01*
G01Y1122541D02*
Y1124651D01*
G01X1419803Y1112929D02*
Y1115039D01*
G01Y1119337D02*
Y1121447D01*
G01Y1125746D02*
Y1127856D01*
G01X1421653Y1116133D02*
Y1118243D01*
G01Y1122541D02*
Y1124651D01*
G01X1425354Y1116133D02*
Y1118243D01*
G01Y1122541D02*
Y1124651D01*
G01X1427203Y1112929D02*
Y1115039D01*
G01Y1119337D02*
Y1121447D01*
G01Y1125746D02*
Y1127856D01*
G01X1412403Y1125746D02*
Y1127855D01*
X1412404Y1127856D01*
G01X1412403Y1119337D02*
Y1121446D01*
X1412404Y1121447D01*
G01X1412403Y1112929D02*
Y1115038D01*
X1412404Y1115039D01*
G01X1412403Y1132154D02*
Y1134264D01*
G01X1414254Y1128950D02*
Y1131060D01*
G01Y1135359D02*
Y1137769D01*
G01X1416103Y1132154D02*
Y1134264D01*
G01X1417954Y1128950D02*
Y1131060D01*
G01Y1135359D02*
Y1137769D01*
G01X1419803Y1132154D02*
Y1134264D01*
G01X1421653Y1128950D02*
Y1131060D01*
G01Y1135359D02*
Y1137769D01*
G01X1425354Y1128950D02*
Y1131060D01*
G01Y1135359D02*
Y1137769D01*
G01X1427203Y1132154D02*
Y1134264D01*
G01X1425014Y1329843D02*
X1425073Y1329784D01*
Y1325260D01*
G01X1429102Y1332985D02*
X1429094Y1332993D01*
X1425014D01*
G01X1429102Y1329835D02*
Y1329754D01*
X1426845Y1327497D01*
Y1325260D01*
G01X1428621Y850286D02*
X1428620Y850285D01*
Y848176D01*
G01X1432321Y869511D02*
Y867401D01*
G01X1439721Y869511D02*
Y867401D01*
G01X1432321Y882329D02*
Y880219D01*
G01X1439721D02*
Y882329D01*
G01X1432321Y895146D02*
Y893036D01*
G01X1439721Y895146D02*
Y893036D01*
G01X1437870Y904759D02*
X1437871Y904758D01*
Y902649D01*
G01X1432321Y914372D02*
X1432320Y914371D01*
Y912262D01*
G01X1432321Y907963D02*
X1432320Y907962D01*
Y905853D01*
G01X1430470Y904759D02*
X1430471Y904758D01*
Y902649D01*
G01X1441570Y911167D02*
X1441571Y911166D01*
Y909057D01*
G01X1441570Y917576D02*
Y915467D01*
X1441571Y915466D01*
G01X1437870Y923985D02*
X1437871Y923984D01*
Y921875D01*
G01X1432321Y920780D02*
X1432320Y920779D01*
Y918670D01*
G01X1436454Y1039230D02*
Y1041338D01*
X1436453Y1041339D01*
Y1041340D01*
G01X1432754Y1045639D02*
X1432753Y1047749D01*
G01X1440154Y1045639D02*
Y1047748D01*
X1440153Y1047749D01*
G01X1429054Y1058455D02*
X1429053Y1060565D01*
G01X1432754Y1052047D02*
X1432753Y1054157D01*
G01X1438303Y1048842D02*
X1438304Y1050952D01*
G01X1434603Y1061660D02*
X1434604Y1063653D01*
Y1063770D01*
G01X1432754Y1071273D02*
X1432753Y1073383D01*
G01X1430903Y1068068D02*
X1430904Y1070178D01*
G01X1443854Y1071273D02*
X1443853Y1073383D01*
G01X1438303Y1068068D02*
X1438304Y1070178D01*
G01X1432754Y1084090D02*
X1432753Y1086200D01*
G01X1436454Y1090498D02*
X1436453Y1092608D01*
G01X1429054Y1103316D02*
Y1105426D01*
G01Y1109724D02*
Y1111834D01*
G01X1430903Y1100111D02*
Y1102221D01*
G01Y1106520D02*
Y1108630D01*
G01X1432754Y1103316D02*
Y1105426D01*
G01X1434603Y1106520D02*
Y1108630D01*
G01X1436454Y1109724D02*
Y1111834D01*
G01X1432754Y1109724D02*
Y1111833D01*
X1432753Y1111834D01*
G01X1429054Y1116133D02*
Y1118243D01*
G01Y1122541D02*
Y1124651D01*
G01X1430903Y1112929D02*
Y1115039D01*
G01Y1119337D02*
Y1121447D01*
G01Y1125746D02*
Y1127856D01*
G01X1436454Y1116133D02*
Y1118243D01*
G01Y1122541D02*
Y1124651D01*
G01X1438303Y1112929D02*
Y1115039D01*
G01Y1119337D02*
Y1121447D01*
G01Y1125746D02*
Y1127856D01*
G01X1440154Y1122541D02*
Y1124651D01*
G01X1442003Y1125746D02*
Y1127856D01*
G01X1440154Y1116133D02*
Y1118242D01*
X1440153Y1118243D01*
G01X1432754Y1122541D02*
Y1124650D01*
X1432753Y1124651D01*
G01X1432754Y1116133D02*
Y1118242D01*
X1432753Y1118243D01*
G01X1429054Y1128950D02*
Y1131060D01*
G01Y1135359D02*
Y1137769D01*
G01X1443854Y1128950D02*
Y1131060D01*
G01Y1135359D02*
Y1137469D01*
G01X1430903Y1132154D02*
Y1134264D01*
G01Y1138563D02*
Y1140973D01*
G01X1432754Y1135359D02*
Y1137469D01*
G01X1434603Y1138563D02*
Y1140973D01*
G01X1436454Y1128950D02*
Y1131060D01*
G01Y1135359D02*
Y1137469D01*
G01X1438303Y1132154D02*
Y1134264D01*
G01Y1138563D02*
Y1140973D01*
G01X1440154Y1128950D02*
Y1131060D01*
G01Y1135359D02*
Y1137469D01*
G01X1442003Y1132154D02*
Y1134264D01*
G01Y1138563D02*
Y1140973D01*
G01X1432754Y1128950D02*
Y1131059D01*
X1432753Y1131060D01*
G01X1444957Y1315713D02*
X1443801D01*
X1442116Y1314028D01*
Y1312326D01*
G01X1440332Y1325167D02*
X1442210Y1323289D01*
Y1322388D01*
X1443570Y1321028D01*
X1444957D01*
G01X1440332Y1317092D02*
Y1314667D01*
G01D02*
X1440692D01*
X1443510Y1317485D01*
X1444957D01*
G01X1440332Y1322017D02*
X1440668D01*
X1443429Y1319256D01*
X1444957D01*
G01X1440332Y1319592D02*
Y1322017D01*
G01X1454521Y869511D02*
Y867401D01*
G01X1447121Y869511D02*
Y867401D01*
G01X1454521Y882329D02*
Y880219D01*
G01X1447121Y882329D02*
Y880219D01*
G01X1456370Y898350D02*
Y896240D01*
G01X1454521Y895146D02*
Y893036D01*
G01X1447121Y895146D02*
Y893036D01*
G01X1450821Y914372D02*
X1450820Y914371D01*
Y912262D01*
G01X1450821Y907963D02*
X1450820Y907962D01*
Y905853D01*
G01X1460070Y930393D02*
X1460071Y930392D01*
Y928283D01*
G01X1460070Y943210D02*
Y941100D01*
G01X1458221Y940006D02*
X1458220Y940005D01*
Y937896D01*
G01X1454520Y946413D02*
Y944304D01*
G01X1460070Y962436D02*
Y960326D01*
G01Y968845D02*
X1460071Y968844D01*
Y966735D01*
G01X1458221Y972049D02*
Y969939D01*
G01X1460070Y981662D02*
Y979552D01*
G01X1458221Y978457D02*
X1458220Y978456D01*
Y976347D01*
G01X1460503Y997574D02*
Y999684D01*
G01X1458654Y1007187D02*
Y1009297D01*
G01X1460503Y1010391D02*
Y1011053D01*
X1460504Y1012501D01*
G01X1458654Y1026413D02*
Y1028522D01*
X1458653Y1028523D01*
G01X1460503Y1029617D02*
Y1031727D01*
G01X1458654Y1039230D02*
Y1041338D01*
X1458653Y1041339D01*
Y1041340D01*
G01X1458654Y1032821D02*
Y1034931D01*
G01X1451254Y1039230D02*
Y1041338D01*
X1451253Y1041339D01*
Y1041340D01*
G01X1460503Y1036026D02*
Y1038136D01*
G01X1447554Y1045639D02*
Y1047748D01*
X1447553Y1047749D01*
G01X1460503Y1074477D02*
Y1076587D01*
G01X1451254Y1064864D02*
X1451253Y1066974D01*
G01X1449403Y1068068D02*
X1449404Y1070178D01*
G01X1460503Y1068068D02*
X1460504Y1070178D01*
G01X1454954Y1071273D02*
X1454953Y1073383D01*
G01X1458654Y1077681D02*
X1458653Y1079791D01*
G01X1454954Y1077681D02*
Y1079791D01*
G01X1451254Y1077681D02*
X1451253Y1079791D01*
G01X1445703Y1087294D02*
Y1089404D01*
G01X1456803Y1080885D02*
X1456804Y1082995D01*
G01X1453103Y1087294D02*
X1453104Y1089404D01*
G01X1460503Y1087294D02*
X1460504Y1089404D01*
G01X1460503Y1125746D02*
Y1127856D01*
G01X1453103Y1125746D02*
Y1127856D01*
G01Y1138563D02*
Y1140973D01*
G01X1460503Y1138563D02*
Y1140973D01*
G01X1445703Y1132154D02*
Y1134264D01*
G01X1457395Y1329835D02*
Y1328023D01*
X1457201Y1327829D01*
Y1325260D01*
G01X1461437Y1332985D02*
X1457395D01*
G01X1461437Y1329835D02*
X1458973Y1327371D01*
Y1325260D01*
G01X1461921Y869511D02*
Y867401D01*
G01X1476721Y869511D02*
Y867401D01*
G01X1469321Y869511D02*
Y867401D01*
G01X1461921Y882329D02*
Y880219D01*
G01X1476721Y882329D02*
Y880219D01*
G01X1469321Y882329D02*
Y880219D01*
G01X1465621Y895146D02*
Y893036D01*
G01X1476721Y895146D02*
Y893036D01*
G01X1474870Y898350D02*
X1474871Y898349D01*
Y896240D01*
G01X1473021Y899445D02*
Y901555D01*
G01Y914372D02*
X1473020Y914371D01*
Y912262D01*
G01X1471170Y911167D02*
X1471171Y911166D01*
Y909057D01*
G01X1465621Y907963D02*
Y905854D01*
X1465620Y905853D01*
G01X1471170Y904759D02*
X1471171Y904758D01*
Y902649D01*
G01X1469321Y907963D02*
Y905853D01*
G01X1474870Y917576D02*
Y915466D01*
G01X1461921Y927189D02*
X1461920Y927188D01*
Y925079D01*
G01X1471170Y930393D02*
Y928283D01*
G01X1469321Y927189D02*
Y925079D01*
G01X1465621Y927189D02*
X1465620Y927188D01*
Y925079D01*
G01X1473021Y920780D02*
Y918670D01*
G01X1471170Y923985D02*
X1471171Y923984D01*
Y921875D01*
G01X1461921Y946414D02*
X1461920Y946413D01*
Y944304D01*
G01X1473021Y940006D02*
Y937896D01*
G01X1471170Y943210D02*
X1471171Y943209D01*
Y941100D01*
G01X1469321Y946414D02*
Y944304D01*
G01X1465621Y946414D02*
X1465620Y946413D01*
Y944304D01*
G01X1465621Y940006D02*
X1465620Y940005D01*
Y937896D01*
G01X1471170Y949619D02*
Y947509D01*
G01X1474870Y956027D02*
Y953918D01*
X1474871Y953917D01*
G01X1473021Y959232D02*
Y957122D01*
G01X1471170Y962436D02*
X1471171Y962435D01*
Y960326D01*
G01X1465621Y959232D02*
X1465620Y959231D01*
Y957122D01*
G01X1465621Y952823D02*
X1465620Y952822D01*
Y950713D01*
G01X1473021Y952823D02*
X1473020Y952822D01*
Y950713D01*
G01X1461921Y965640D02*
X1461920Y965639D01*
Y963530D01*
G01X1476721Y965640D02*
Y963530D01*
G01X1469321Y965640D02*
Y963530D01*
G01X1465621Y965640D02*
X1465620Y965639D01*
Y963530D01*
G01X1471170Y968845D02*
Y966735D01*
G01X1473021Y978457D02*
Y976347D01*
G01Y972049D02*
X1473020Y972048D01*
Y969939D01*
G01X1465621Y978457D02*
X1465620Y978456D01*
Y976347D01*
G01X1465621Y972049D02*
X1465620Y972048D01*
Y969939D01*
G01X1474870Y975253D02*
Y973143D01*
G01X1471170Y981662D02*
X1471171Y981661D01*
Y979552D01*
G01X1461921Y984866D02*
X1461920Y984865D01*
Y982756D01*
G01X1469321Y984866D02*
Y982756D01*
G01X1465621Y984866D02*
X1465620Y984865D01*
Y982756D01*
G01X1471603Y997574D02*
Y999683D01*
X1471604Y999684D01*
G01X1475303Y1003983D02*
Y1006093D01*
G01X1473454Y1000778D02*
Y1002888D01*
G01X1466054Y1000778D02*
Y1002888D01*
G01X1467903Y1003983D02*
Y1006093D01*
G01X1464203Y1003983D02*
Y1006092D01*
X1464204Y1006093D01*
G01X1471603Y1012501D02*
Y1010391D01*
G01X1462354Y1013595D02*
X1462353Y1015705D01*
G01X1466054Y1013595D02*
X1466053Y1015705D01*
G01X1469754Y1013595D02*
Y1015705D01*
G01X1473454Y1026413D02*
Y1028522D01*
X1473453Y1028523D01*
G01X1466054Y1026413D02*
Y1028522D01*
X1466053Y1028523D01*
G01X1466054Y1020004D02*
Y1020053D01*
X1466053Y1022114D01*
G01X1475303Y1023208D02*
Y1025318D01*
G01X1473454Y1020004D02*
Y1020053D01*
X1473453Y1022114D01*
G01X1471603Y1016800D02*
Y1018909D01*
X1471604Y1018910D01*
G01X1471603Y1029617D02*
Y1031727D01*
G01X1473454Y1039230D02*
Y1041340D01*
G01X1466054Y1039230D02*
Y1041338D01*
X1466053Y1041339D01*
Y1041340D01*
G01X1475303Y1042434D02*
Y1044544D01*
G01X1471603Y1036026D02*
Y1038135D01*
X1471604Y1038136D01*
G01X1469754Y1032821D02*
Y1034931D01*
G01X1473454Y1058455D02*
X1473453Y1060565D01*
G01X1471603Y1055251D02*
X1471604Y1057361D01*
G01X1466054Y1052047D02*
X1466053Y1054157D01*
G01X1471603Y1048842D02*
Y1050952D01*
G01X1469754Y1052047D02*
X1469753Y1054157D01*
G01X1475303Y1061660D02*
X1475304Y1063653D01*
Y1063770D01*
G01X1462354Y1071273D02*
X1462353Y1073383D01*
G01X1471603Y1074477D02*
X1471604Y1076587D01*
G01X1469754Y1071273D02*
Y1073383D01*
G01X1466054Y1064864D02*
X1466053Y1066974D01*
G01X1473454Y1064864D02*
X1473453Y1066974D01*
G01X1471603Y1068068D02*
Y1070178D01*
G01X1466054Y1071273D02*
X1466053Y1073383D01*
G01X1473454Y1077681D02*
Y1079791D01*
G01X1462354Y1090498D02*
X1462353Y1092608D01*
G01X1475303Y1080885D02*
Y1082995D01*
G01X1473454Y1084090D02*
X1473453Y1086200D01*
G01X1469754Y1090498D02*
Y1092608D01*
G01X1466054Y1090498D02*
X1466053Y1092608D01*
G01X1466054Y1084090D02*
X1466053Y1086200D01*
G01X1471603Y1087294D02*
Y1089404D01*
G01X1475303Y1093703D02*
X1475304Y1095813D01*
G01X1471603Y1093703D02*
X1471604Y1095813D01*
G01X1475303Y1106520D02*
Y1108630D01*
G01Y1100111D02*
Y1102221D01*
G01Y1125746D02*
Y1127856D01*
G01X1467903Y1125746D02*
Y1127856D01*
G01X1475303Y1138563D02*
Y1140973D01*
G01X1467903Y1138563D02*
Y1140973D01*
G01X1477085Y1329139D02*
X1475929D01*
X1474244Y1327454D01*
Y1325752D01*
G01X1472460Y1338593D02*
X1474338Y1336715D01*
Y1335814D01*
X1475698Y1334454D01*
X1477085D01*
G01X1472460Y1330493D02*
Y1328093D01*
G01D02*
X1472820D01*
X1475638Y1330911D01*
X1477085D01*
G01X1472460Y1335443D02*
X1472796D01*
X1475557Y1332682D01*
X1477085D01*
G01X1472460Y1333043D02*
Y1335443D01*
G01X1491521Y869511D02*
Y867401D01*
G01X1484121Y869511D02*
Y867401D01*
G01X1491521Y882329D02*
Y880219D01*
G01X1484121Y882329D02*
Y880219D01*
G01X1478570Y898350D02*
Y896240D01*
G01X1491521Y895146D02*
Y893036D01*
G01X1482270Y898350D02*
Y896240D01*
G01X1480421Y895146D02*
Y893036D01*
G01X1491521Y901555D02*
X1491520Y901554D01*
Y899445D01*
G01X1484121Y901555D02*
X1484120Y901554D01*
Y899445D01*
G01X1478570Y911167D02*
X1478571Y911166D01*
Y909057D01*
G01X1478570Y904759D02*
X1478571Y904758D01*
Y902649D01*
G01X1491521Y914372D02*
X1491520Y914371D01*
Y912262D01*
G01X1487821Y907963D02*
X1487820Y907962D01*
Y905853D01*
G01X1485970Y911167D02*
X1485971Y911166D01*
Y909057D01*
G01X1484121Y914372D02*
Y912262D01*
G01X1491521Y907963D02*
X1491520Y907962D01*
Y905853D01*
G01X1485970Y904759D02*
Y902649D01*
G01X1478570Y930393D02*
X1478571Y930392D01*
Y928283D01*
G01X1478570Y923985D02*
X1478571Y923984D01*
Y921875D01*
G01X1491521Y927189D02*
X1491520Y927188D01*
Y925079D01*
G01X1491521Y920780D02*
X1491520Y920779D01*
Y918670D01*
G01X1487821Y927189D02*
X1487820Y927188D01*
Y925079D01*
G01X1485970Y930393D02*
X1485971Y930392D01*
Y928283D01*
G01X1485970Y923985D02*
Y921875D01*
G01X1484121Y920780D02*
X1484120Y920779D01*
Y918670D01*
G01X1484121Y933598D02*
Y931488D01*
G01X1478570Y943210D02*
X1478571Y943209D01*
Y941100D01*
G01X1491521Y946414D02*
X1491520Y946413D01*
Y944304D01*
G01X1491521Y940006D02*
X1491520Y940005D01*
Y937896D01*
G01X1487821Y946414D02*
X1487820Y946413D01*
Y944304D01*
G01X1485970Y943210D02*
Y941100D01*
G01X1484121Y940006D02*
X1484120Y940005D01*
Y937896D01*
G01X1478570Y949619D02*
X1478571Y949618D01*
Y947509D01*
G01X1485970Y949619D02*
X1485971Y949618D01*
Y947509D01*
G01X1478570Y962436D02*
X1478571Y962435D01*
Y960326D01*
G01X1478570Y956027D02*
Y953918D01*
X1478571Y953917D01*
G01X1491521Y959232D02*
X1491520Y959231D01*
Y957122D01*
G01X1491521Y952823D02*
X1491520Y952822D01*
Y950713D01*
G01X1485970Y962436D02*
Y960326D01*
G01X1484121Y959232D02*
X1484120Y959231D01*
Y957122D01*
G01X1482270Y956027D02*
Y953918D01*
X1482271Y953917D01*
G01X1484121Y952823D02*
Y950713D01*
G01X1491521Y965640D02*
X1491520Y965639D01*
Y963530D01*
G01X1487821Y965640D02*
X1487820Y965639D01*
Y963530D01*
G01X1480421Y965640D02*
X1480420Y965639D01*
Y963530D01*
G01X1478570Y968845D02*
Y966735D01*
G01X1485970Y968845D02*
X1485971Y968844D01*
Y966735D01*
G01X1478570Y981662D02*
X1478571Y981661D01*
Y979552D01*
G01X1478570Y975253D02*
X1478571Y975252D01*
Y973143D01*
G01X1491521Y978457D02*
Y976347D01*
G01Y972049D02*
X1491520Y972048D01*
Y969939D01*
G01X1484121Y978457D02*
X1484120Y978456D01*
Y976347D01*
G01X1484121Y972049D02*
Y969939D01*
G01X1489670Y975253D02*
X1489671Y975252D01*
Y973143D01*
G01X1485970Y981662D02*
Y979552D01*
G01X1482270Y975253D02*
X1482271Y975252D01*
Y973143D01*
G01X1491521Y984866D02*
X1491520Y984865D01*
Y982756D01*
G01X1487821Y984866D02*
X1487820Y984865D01*
Y982756D01*
G01X1479003Y997574D02*
Y999683D01*
X1479004Y999684D01*
G01X1486403Y997574D02*
Y999684D01*
G01X1482703Y1003983D02*
Y1006092D01*
X1482704Y1006093D01*
G01X1479003Y1003983D02*
X1482704Y1006093D01*
G01X1479003Y1012501D02*
Y1010391D01*
G01X1486403D02*
Y1011053D01*
X1486404Y1012501D01*
G01X1484554Y1007187D02*
Y1009297D01*
G01X1477154Y1013595D02*
Y1015705D01*
G01X1480854Y1013595D02*
X1480853Y1015705D01*
G01X1488254Y1013595D02*
X1488253Y1015705D01*
G01X1491954Y1013595D02*
X1491953Y1015705D01*
G01X1479003Y1016800D02*
Y1018909D01*
X1479004Y1018910D01*
G01X1491954Y1026413D02*
Y1028522D01*
X1491953Y1028523D01*
G01X1491954Y1020004D02*
Y1020053D01*
X1491953Y1022114D01*
G01X1484554Y1026413D02*
Y1028522D01*
X1484553Y1028523D01*
G01X1486403Y1016800D02*
Y1018910D01*
G01X1484554Y1020004D02*
Y1020053D01*
X1484553Y1022114D01*
G01X1482703Y1023208D02*
X1482704Y1025318D01*
G01X1479003Y1042434D02*
X1479004Y1044544D01*
G01X1479003Y1036026D02*
Y1038135D01*
X1479004Y1038136D01*
G01X1491954Y1032821D02*
X1491953Y1034931D01*
G01X1491954Y1039230D02*
Y1041338D01*
X1491953Y1041339D01*
Y1041340D01*
G01X1488254Y1032821D02*
X1488253Y1034931D01*
G01X1486403Y1036026D02*
Y1038136D01*
G01X1484554Y1039230D02*
Y1041338D01*
X1484553Y1041339D01*
Y1041340D01*
G01X1482703Y1042434D02*
X1482704Y1044544D01*
G01X1479003Y1055251D02*
X1479004Y1057361D01*
G01X1479003Y1048842D02*
X1479004Y1050952D01*
G01X1486403Y1055251D02*
X1486404Y1057361D01*
G01X1484554Y1058455D02*
X1484553Y1060565D01*
G01X1486403Y1048842D02*
X1486404Y1050952D01*
G01X1491954Y1058455D02*
X1491953Y1060565D01*
G01X1479003Y1061660D02*
X1479004Y1063653D01*
Y1063770D01*
G01X1482703Y1061660D02*
X1482704Y1063653D01*
Y1063770D01*
G01X1479003Y1074477D02*
X1479004Y1076587D01*
G01X1479003Y1068068D02*
X1479004Y1070178D01*
G01X1486403Y1074477D02*
X1486404Y1076587D01*
G01X1486403Y1068068D02*
X1486404Y1070178D01*
G01X1488254Y1071273D02*
X1488253Y1073383D01*
G01X1484554Y1064864D02*
X1484553Y1066974D01*
G01X1491954Y1071273D02*
X1491953Y1073383D01*
G01X1491954Y1064864D02*
X1491953Y1066974D01*
G01X1484554Y1077681D02*
X1484553Y1079791D01*
G01X1491954Y1077681D02*
X1491953Y1079791D01*
G01X1479003Y1087294D02*
X1479004Y1089404D01*
G01X1479003Y1080885D02*
X1479004Y1082995D01*
G01X1488254Y1090498D02*
Y1092608D01*
G01X1486403Y1087294D02*
X1486404Y1089404D01*
G01X1484554Y1084090D02*
Y1086200D01*
G01X1482703Y1080885D02*
X1482704Y1082995D01*
G01X1491954Y1090498D02*
Y1092608D01*
G01Y1084090D02*
X1491953Y1086200D01*
G01X1479003Y1093703D02*
X1479004Y1095813D01*
G01X1490103Y1093703D02*
Y1095813D01*
G01X1479003Y1100111D02*
X1479004Y1102221D01*
G01X1482703Y1106520D02*
X1482704Y1108630D01*
G01X1490103Y1125746D02*
Y1127856D01*
G01X1482703Y1125746D02*
Y1127856D01*
G01X1490103Y1138563D02*
Y1140973D01*
G01X1482703Y1138563D02*
Y1140973D01*
G01X1489523Y1343818D02*
Y1342110D01*
X1489329Y1341916D01*
Y1338686D01*
G01X1493565Y1343818D02*
X1491101Y1341354D01*
Y1338686D01*
G01X1493565Y1346968D02*
X1489523D01*
G01X1508170Y859899D02*
Y857789D01*
G01X1506321Y863103D02*
Y860993D01*
G01Y856694D02*
Y854584D01*
G01X1498921Y856694D02*
Y854584D01*
G01X1506321Y869511D02*
Y867402D01*
X1506320Y867401D01*
G01X1498921Y869511D02*
Y867401D01*
G01Y882329D02*
Y880219D01*
G01X1506321Y882329D02*
Y880219D01*
G01X1504471Y898350D02*
Y896240D01*
G01X1508170Y898350D02*
X1508171Y898349D01*
Y896240D01*
G01X1502621Y895146D02*
Y893036D01*
G01X1500770Y898350D02*
X1500771Y898349D01*
Y896240D01*
G01X1498921Y899445D02*
Y901555D01*
G01X1495221Y907963D02*
Y905853D01*
G01X1504471Y904759D02*
Y902649D01*
G01X1498921Y914372D02*
X1498920Y914371D01*
Y912262D01*
G01X1497070Y909057D02*
Y911167D01*
G01Y904759D02*
X1497071Y904758D01*
Y902649D01*
G01X1508170Y917576D02*
Y915467D01*
X1508171Y915466D01*
G01X1504471Y917576D02*
Y915466D01*
G01X1500770Y917576D02*
Y915466D01*
G01X1504471Y909057D02*
Y911167D01*
G01X1495221Y927189D02*
Y925079D01*
G01X1504471Y921875D02*
Y923985D01*
G01X1497070Y930393D02*
Y928283D01*
G01X1498921Y920780D02*
Y918670D01*
G01X1497070Y923985D02*
X1497071Y923984D01*
Y921875D01*
G01X1498921Y933598D02*
X1498920Y931488D01*
G01X1504471Y930393D02*
Y928283D01*
G01X1495221Y946414D02*
Y944304D01*
G01X1504471Y943210D02*
Y941100D01*
G01X1498921Y940006D02*
Y937896D01*
G01X1497070Y943210D02*
X1497071Y943209D01*
Y941100D01*
G01X1497070Y949619D02*
Y947509D01*
G01X1504471D02*
Y949619D01*
G01Y962436D02*
Y960326D01*
G01Y956027D02*
Y953917D01*
G01X1500770Y956027D02*
Y953918D01*
X1500771Y953917D01*
G01X1498921Y959232D02*
Y957122D01*
G01X1497070Y962436D02*
X1497071Y962435D01*
Y960326D01*
G01X1498921Y952823D02*
X1498920Y952822D01*
Y950713D01*
G01X1495221Y965640D02*
Y963530D01*
G01X1502621Y965640D02*
Y963530D01*
G01X1508170Y956027D02*
Y953918D01*
X1508171Y953917D01*
G01X1506321Y965640D02*
X1506320Y965639D01*
Y963530D01*
G01X1497070Y968845D02*
Y966735D01*
G01X1504471D02*
Y968845D01*
G01X1493370Y975253D02*
Y973143D01*
G01X1504471Y979552D02*
Y981662D01*
G01Y975253D02*
Y973143D01*
G01X1498921Y978457D02*
Y976347D01*
G01Y972049D02*
X1498920Y972048D01*
Y969939D01*
G01X1500770Y975253D02*
Y973143D01*
G01X1497070Y981662D02*
X1497071Y981661D01*
Y979552D01*
G01X1508170Y975253D02*
X1508171Y975252D01*
Y973143D01*
G01X1495221Y984866D02*
Y982756D01*
G01X1497503Y997574D02*
Y999684D01*
G01X1504903Y997574D02*
Y999683D01*
X1504904Y999684D01*
G01X1497503Y1012501D02*
Y1010391D01*
G01X1504903Y1003983D02*
Y1006092D01*
X1504904Y1006093D01*
G01X1501203Y1003983D02*
Y1006093D01*
G01X1499354Y1000778D02*
Y1002888D01*
G01X1508603Y1003983D02*
Y1006093D01*
G01X1504903Y1012501D02*
Y1010391D01*
G01X1495654Y1013595D02*
Y1015705D01*
G01X1503054Y1013595D02*
Y1015705D01*
G01X1506754Y1013595D02*
Y1015704D01*
X1506753Y1015705D01*
G01X1504903Y1023208D02*
Y1025317D01*
X1504904Y1025318D01*
G01X1499354Y1026413D02*
Y1028522D01*
X1499353Y1028523D01*
G01X1501203Y1023208D02*
Y1025318D01*
G01X1504903Y1029617D02*
Y1031726D01*
X1504904Y1031727D01*
G01X1497503Y1029617D02*
Y1031727D01*
G01Y1016800D02*
Y1018909D01*
X1497504Y1018910D01*
G01X1499354Y1020004D02*
Y1020053D01*
X1499353Y1022114D01*
G01X1504903Y1016800D02*
Y1018909D01*
X1504904Y1018910D01*
G01X1504903Y1042434D02*
X1504904Y1044544D01*
G01X1501203Y1042434D02*
Y1044544D01*
G01X1499354Y1039230D02*
Y1041340D01*
G01X1497503Y1036026D02*
Y1038135D01*
X1497504Y1038136D01*
G01X1495654Y1032821D02*
Y1034931D01*
G01X1508603Y1042434D02*
X1508604Y1044544D01*
G01X1504903Y1036026D02*
Y1038135D01*
X1504904Y1038136D01*
G01X1504903Y1055251D02*
X1504904Y1057361D01*
G01X1504903Y1048842D02*
X1504904Y1050952D01*
G01X1499354Y1058455D02*
Y1060565D01*
G01X1497503Y1055251D02*
X1497504Y1057361D01*
G01X1497503Y1048842D02*
Y1050952D01*
G01X1495654Y1052047D02*
Y1054157D01*
G01X1504903Y1061660D02*
X1504904Y1063653D01*
Y1063770D01*
G01X1501203Y1061660D02*
Y1063770D01*
G01X1508603Y1061660D02*
X1508604Y1063653D01*
Y1063770D01*
G01X1504903Y1074477D02*
X1504904Y1076587D01*
G01X1504903Y1068068D02*
X1504904Y1070178D01*
G01X1497503Y1074477D02*
X1497504Y1076587D01*
G01X1497503Y1068068D02*
Y1070178D01*
G01X1495654Y1071273D02*
Y1073383D01*
G01X1499354Y1064864D02*
X1499353Y1066974D01*
G01X1499354Y1077681D02*
Y1079791D01*
G01X1493803Y1093703D02*
X1493804Y1095813D01*
G01X1499354Y1084090D02*
X1499353Y1086200D01*
G01X1497503Y1087294D02*
Y1089404D01*
G01X1495654Y1090498D02*
X1495653Y1092608D01*
G01X1504903Y1087294D02*
X1504904Y1089404D01*
G01X1504903Y1080885D02*
Y1082994D01*
X1504904Y1082995D01*
G01X1501203Y1080885D02*
Y1082995D01*
G01X1508603Y1080885D02*
Y1082995D01*
X1508604Y1082996D01*
G01X1504903Y1093703D02*
Y1095813D01*
G01X1506754Y1122541D02*
Y1124650D01*
X1506753Y1124651D01*
G01X1504903Y1119337D02*
X1504904Y1121447D01*
G01X1504903Y1125746D02*
Y1127855D01*
X1504904Y1127856D01*
G01X1497503Y1125746D02*
Y1127856D01*
G01Y1138563D02*
Y1140973D01*
G01X1509213Y1351937D02*
X1508057D01*
X1506372Y1350252D01*
Y1348550D01*
G01X1509213Y1353709D02*
X1507766D01*
X1504948Y1350891D01*
X1504588D01*
G01Y1353316D02*
Y1350891D01*
G01Y1358241D02*
X1504924D01*
X1507685Y1355480D01*
X1509213D01*
G01X1504588Y1355816D02*
Y1358241D01*
G01Y1361391D02*
X1506466Y1359513D01*
Y1358746D01*
X1507960Y1357252D01*
X1509213D01*
G01X1511871Y851380D02*
Y853490D01*
G01X1510021Y863103D02*
Y860993D01*
G01Y869511D02*
Y867401D01*
G01X1521121Y854584D02*
Y856694D01*
G01X1515570Y866307D02*
Y864197D01*
G01X1513721Y856694D02*
Y854584D01*
G01Y863103D02*
Y860993D01*
G01X1517421Y869511D02*
Y867401D01*
G01X1513721Y869511D02*
Y867401D01*
G01X1510021Y882329D02*
Y880219D01*
G01X1511871Y870606D02*
Y872716D01*
G01X1517421Y875920D02*
Y873810D01*
G01Y880219D02*
Y882329D01*
G01X1522970Y885533D02*
Y883424D01*
X1522971Y883423D01*
G01X1510021Y918670D02*
Y920780D01*
G01X1511871Y921875D02*
Y923985D01*
G01X1513721Y927189D02*
Y925080D01*
X1513720Y925079D01*
G01X1521121Y965640D02*
X1524288D01*
G01X1515570Y975253D02*
X1515571Y975252D01*
Y973143D01*
G01X1521121Y978457D02*
X1523249D01*
X1523849Y979057D01*
X1527571D01*
G01X1521121Y972049D02*
X1525232D01*
X1525791Y972608D01*
X1526843D01*
G01X1512303Y997574D02*
Y999684D01*
G01X1510453Y1007187D02*
Y1009297D01*
G01Y1000778D02*
Y1002888D01*
G01X1517853Y1000778D02*
X1516119Y999776D01*
X1516027Y999684D01*
X1516003D01*
G01X1521554Y1000778D02*
X1525266D01*
X1525396Y1000648D01*
G01X1512303Y1012501D02*
Y1010391D01*
G01X1510453Y1028523D02*
Y1026413D01*
G01Y1020004D02*
Y1020053D01*
X1510452Y1022114D01*
G01X1514154Y1077681D02*
X1512303Y1076587D01*
G01X1510453Y1096907D02*
Y1099017D01*
G01X1521554Y1103316D02*
Y1105426D01*
G01X1516003Y1106520D02*
Y1108630D01*
G01Y1100111D02*
Y1102221D01*
G01X1512303Y1100111D02*
Y1102221D01*
G01X1521554Y1122541D02*
Y1124650D01*
X1521553Y1124651D01*
G01X1521554Y1116133D02*
X1521553Y1116134D01*
Y1118243D01*
G01X1514154Y1122541D02*
Y1124650D01*
X1514153Y1124651D01*
G01X1510453Y1128950D02*
Y1131060D01*
G01X1521651Y1366616D02*
Y1364560D01*
X1521457Y1364366D01*
Y1361484D01*
G01X1525693Y1369766D02*
X1521651D01*
G01X1525693Y1366616D02*
X1523229Y1364152D01*
Y1361484D01*
G01X1639703Y647976D02*
Y649132D01*
X1638013Y650822D01*
X1635120D01*
G01X1639703Y681976D02*
Y683131D01*
X1638017Y684817D01*
X1634725D01*
G01X1639703Y715976D02*
Y717132D01*
X1638018Y718817D01*
X1636316D01*
G01D02*
X1635507Y719626D01*
Y720601D01*
G01X1628978Y1427412D02*
X1627690D01*
X1626137Y1425859D01*
Y1424025D01*
G01X1624353Y1436866D02*
X1626062Y1435157D01*
Y1434296D01*
X1627631Y1432727D01*
X1628978D01*
G01X1624353Y1426366D02*
X1624699D01*
X1627517Y1429184D01*
X1628978D01*
G01X1624353Y1433716D02*
X1624641D01*
X1627402Y1430955D01*
X1628978D01*
G01X1653833Y635791D02*
X1653774Y635732D01*
X1649250D01*
G01X1653825Y631703D02*
X1653744D01*
X1651487Y633960D01*
X1649250D01*
G01X1649157Y652601D02*
X1647279Y650723D01*
X1646378D01*
X1645018Y649363D01*
Y647976D01*
G01X1646007Y652601D02*
Y652265D01*
X1643246Y649504D01*
Y647976D01*
G01X1653833Y669791D02*
X1653774Y669732D01*
X1649250D01*
G01X1653825Y665703D02*
X1653744D01*
X1651487Y667960D01*
X1649250D01*
G01X1649157Y686601D02*
X1647279Y684723D01*
X1646378D01*
X1645018Y683363D01*
Y681976D01*
G01X1646007Y686601D02*
Y686265D01*
X1643246Y683504D01*
Y681976D01*
G01X1653833Y703791D02*
X1653774Y703732D01*
X1649250D01*
G01X1653825Y699703D02*
X1653744D01*
X1651487Y701960D01*
X1649250D01*
G01X1649157Y720601D02*
X1647279Y718723D01*
X1646378D01*
X1645018Y717363D01*
Y715976D01*
G01X1646007Y720601D02*
Y720265D01*
X1643246Y717504D01*
Y715976D01*
G01X1641416Y1442091D02*
Y1439883D01*
X1641222Y1439689D01*
Y1436959D01*
G01X1645458Y1442091D02*
Y1441660D01*
X1642994Y1439196D01*
Y1436959D01*
G01X1645458Y1445241D02*
X1641416D01*
G01X1656975Y631703D02*
X1656983Y631711D01*
Y635791D01*
G01X1656975Y665703D02*
X1656983Y665711D01*
Y669791D01*
G01X1656975Y699703D02*
X1656983Y699711D01*
Y703791D01*
G01X1667121Y1427412D02*
X1665833D01*
X1664280Y1425859D01*
Y1424025D01*
G01X1662496Y1436866D02*
X1664374Y1434988D01*
Y1434084D01*
X1665731Y1432727D01*
X1667121D01*
G01X1662496Y1428791D02*
Y1426366D01*
G01D02*
X1662842D01*
X1665660Y1429184D01*
X1667121D01*
G01X1662496Y1433716D02*
X1662832D01*
X1665593Y1430955D01*
X1667121D01*
G01X1662496Y1431291D02*
Y1433716D01*
G01X1679559Y1442091D02*
Y1440507D01*
X1679365Y1440313D01*
Y1436959D01*
G01X1683601Y1442091D02*
Y1441660D01*
X1681137Y1439196D01*
Y1436959D01*
G01X1683601Y1445241D02*
X1679559D01*
G01X1799400Y1508830D02*
Y1508431D01*
X1798409Y1506039D01*
X1797722Y1505352D01*
Y1502618D01*
G01X1800975Y1507705D02*
Y1505755D01*
X1800450Y1505230D01*
G54D333*
G01X77416Y1534944D02*
X73624D01*
X72274Y1533594D01*
Y1530094D01*
G01X62349Y1520194D02*
X62350Y1520195D01*
X65019D01*
X72274Y1527450D01*
Y1530094D01*
G01X62349Y1524094D02*
Y1520194D01*
G01D02*
Y1520094D01*
G01Y1528194D02*
X65212D01*
X68274Y1531256D01*
Y1533594D01*
G01X62349Y1532094D02*
Y1528194D01*
G01Y1536094D02*
Y1532094D01*
G01X77416Y1536519D02*
X71199D01*
X68274Y1533594D01*
G01X62349Y1552094D02*
Y1551995D01*
X70250Y1544094D01*
G01X77416Y1541244D02*
X73100D01*
X70250Y1544094D01*
G01X62349Y1540094D02*
X63349Y1539094D01*
X69274D01*
G01X62349Y1544094D02*
Y1540094D01*
G01Y1548094D02*
Y1544094D01*
G01X77416Y1539669D02*
X69849D01*
X69274Y1539094D01*
G01X62349Y1552094D02*
Y1556094D01*
G01Y1560094D02*
Y1556094D01*
G01X85487Y1533173D02*
Y1531275D01*
X86050Y1530712D01*
Y1527962D01*
G01X84474Y1523169D02*
Y1526386D01*
X86050Y1527962D01*
G01X85487Y1543015D02*
Y1556594D01*
G01X87061Y1543015D02*
Y1553480D01*
X89675Y1556094D01*
X92928D01*
G01X87500Y1561519D02*
Y1558607D01*
X85487Y1556594D01*
G01X87500Y1561519D02*
X86844D01*
X84856Y1563507D01*
Y1568194D01*
X88048Y1571386D01*
G01X91500Y1561519D02*
Y1560720D01*
X92928Y1559292D01*
Y1556094D01*
G01X91500Y1561519D02*
X92207D01*
X94033Y1563345D01*
Y1569604D01*
X92251Y1571386D01*
G01X84048D02*
X88048D01*
G01X92251D02*
X96251D01*
G01X102070Y1524694D02*
Y1522267D01*
X107170Y1517167D01*
G01X95132Y1534944D02*
X97959D01*
X102070Y1530833D01*
Y1524694D01*
G01X107199Y1532694D02*
X104174D01*
X101274Y1535594D01*
G01X107199Y1532694D02*
Y1536594D01*
G01X95132Y1541244D02*
X96424D01*
X99400Y1544220D01*
Y1548695D01*
X100236Y1549531D01*
G01D02*
X107199Y1556494D01*
Y1556594D01*
G01X95132Y1539669D02*
X99349D01*
X100274Y1540594D01*
G01D02*
X104274Y1544594D01*
X107199D01*
G01D02*
Y1548594D01*
G01D02*
Y1552594D01*
G01Y1536594D02*
Y1540594D01*
G01X95132Y1536519D02*
X100349D01*
X101274Y1535594D01*
G01X107199Y1560594D02*
Y1556594D01*
G01Y1564594D02*
Y1560594D01*
G01X119308Y1535767D02*
Y1533778D01*
X120298Y1532788D01*
X130045D01*
X133112Y1535855D01*
G01X119481Y1548027D02*
Y1547423D01*
X121361Y1545543D01*
X130964D01*
X133356Y1547935D01*
G01X119410Y1541935D02*
Y1539992D01*
X120256Y1539146D01*
X130536D01*
X133264Y1541874D01*
G01X138793Y1535926D02*
X140485D01*
X144639Y1540080D01*
X149843D01*
G01X133112Y1535855D02*
X133183Y1535926D01*
X138793D01*
G01X139453Y1548920D02*
X147276D01*
X148242Y1547954D01*
X149843D01*
G01X133356Y1547935D02*
X134341Y1548920D01*
X139453D01*
G01X139247Y1542048D02*
X149843D01*
G01X133264Y1541874D02*
X133438Y1542048D01*
X139247D01*
G01X149843Y1549922D02*
X148166D01*
X142884Y1555204D01*
G01X158307Y1531330D02*
Y1537521D01*
G01X158570Y1526580D02*
X158307Y1526843D01*
Y1531330D01*
G01X154581Y1526539D02*
X158529D01*
X158570Y1526580D01*
G01X156339Y1537521D02*
Y1532954D01*
X154581Y1531196D01*
Y1526539D01*
G01X156339Y1552481D02*
Y1556502D01*
X154685Y1558156D01*
G01D02*
Y1562677D01*
X155098Y1563090D01*
G01X154580Y1573834D02*
Y1572224D01*
X153127Y1570771D01*
Y1565061D01*
X155098Y1563090D01*
G01X159794Y1558238D02*
Y1557783D01*
X158307Y1556296D01*
Y1552481D01*
G01X159107Y1563018D02*
X159794Y1562331D01*
Y1558238D01*
G01X159014Y1573834D02*
X161293D01*
X161713Y1573414D01*
Y1565624D01*
X159107Y1563018D01*
G01X164803Y1540080D02*
X165806D01*
X170745Y1535141D01*
X171570D01*
G01D02*
X179586D01*
X179907Y1535462D01*
G01X164803Y1542048D02*
X165943D01*
X168144Y1539847D01*
X174501D01*
G01D02*
X179772D01*
X179896Y1539723D01*
G01X164803Y1545985D02*
X175121D01*
G01D02*
X177372D01*
X179873Y1548486D01*
G01X164803Y1547954D02*
X168862D01*
X172623Y1551715D01*
G01X164803Y1549922D02*
X166355D01*
X174307Y1557874D01*
X175064D01*
G01X164803Y1544017D02*
X166863D01*
X168391Y1542489D01*
X169754D01*
G01D02*
X178254D01*
X179793Y1544028D01*
G01X172623Y1551715D02*
X173965Y1553057D01*
X179681D01*
X179864Y1552874D01*
G01X175064Y1557874D02*
X179864D01*
G01X192875Y1535377D02*
X190552Y1537700D01*
X181066D01*
X179907Y1536541D01*
Y1535462D01*
G01X192816Y1539678D02*
X190624Y1541870D01*
X181148D01*
X179896Y1540618D01*
Y1539723D01*
G01X192708Y1548430D02*
Y1548597D01*
X190973Y1550332D01*
X181719D01*
X179873Y1548486D01*
G01X183014Y1557874D02*
X185894D01*
X185895Y1557875D01*
G01X192616Y1552940D02*
X189939Y1555617D01*
X182607D01*
X179864Y1552874D01*
G01X1138430Y1524150D02*
X1138670D01*
X1139685Y1525165D01*
Y1528937D01*
G01X1167245D02*
Y1524187D01*
G01X1159371Y1528937D02*
Y1524187D01*
G01X1163308Y1528937D02*
Y1524187D01*
G01X1155433Y1528937D02*
Y1524187D01*
G54D216*
X765160Y275881D03*
G54D117*
X220668Y582055D03*
Y616055D03*
Y650055D03*
G54D270*
X1127008Y1537244D03*
G54D51*
X94705Y704442D03*
X1708137Y708568D03*
G54D171*
X427474Y1412789D03*
X1403615D03*
G54D108*
X164470Y1430123D03*
X178840D03*
X678299Y1430118D03*
X692669D03*
X990710Y288546D03*
X976340D03*
X1152361Y1466422D03*
X1137991D03*
X1639465Y1463714D03*
X1653835D03*
X1682863Y648743D03*
X1697233D03*
G54D306*
X1710959Y210080D03*
Y215080D03*
Y220080D03*
Y225080D03*
G54D144*
X312277Y152338D03*
X321333Y148598D03*
Y156078D03*
X862232Y183600D03*
X871288Y187340D03*
X862232Y191080D03*
X1656982Y201640D03*
Y209120D03*
X1666038Y205380D03*
G54D234*
X892000Y886962D03*
X887000D03*
X882000D03*
Y907762D03*
X887000D03*
X892000D03*
X897000Y886962D03*
Y907762D03*
X1540989Y601238D03*
Y622038D03*
X1555989Y601238D03*
X1550989D03*
X1545989D03*
Y622038D03*
X1550989D03*
X1555989D03*
G54D162*
X386824Y1657204D03*
Y1678070D03*
X401824Y1657204D03*
X396824D03*
X391824D03*
Y1678070D03*
X396824D03*
X401824D03*
X1457757Y1655836D03*
X1452757D03*
Y1676702D03*
X1457757D03*
X1467757Y1655836D03*
X1462757D03*
Y1676702D03*
X1467757D03*
G54D135*
X269772Y228719D03*
X271740D03*
Y220845D03*
X269772D03*
X273708Y228719D03*
Y220845D03*
X1516181Y294071D03*
X1514212D03*
X1512244D03*
X1510275D03*
Y305489D03*
X1512244D03*
X1514212D03*
X1516181D03*
X1655610Y410265D03*
X1653642D03*
Y418139D03*
X1655610D03*
X1657578Y410265D03*
Y418139D03*
G54D315*
X1756127Y296368D03*
X1774731D03*
G54D252*
X999455Y201049D03*
Y197506D03*
Y193962D03*
Y204592D03*
G54D207*
X720360Y-12484D03*
Y-10516D03*
X837320Y17516D03*
Y19484D03*
X983580Y-10516D03*
Y-12484D03*
Y19484D03*
Y17516D03*
X1029752Y-22495D03*
Y-20527D03*
Y-2495D03*
Y-527D03*
Y17505D03*
Y19473D03*
X1292972Y-20527D03*
Y-22495D03*
Y-527D03*
Y-2495D03*
Y19473D03*
Y17505D03*
X1339071Y-22495D03*
Y-20527D03*
Y-2495D03*
Y-527D03*
Y17505D03*
Y19473D03*
X1485331Y-20527D03*
Y-22495D03*
Y-527D03*
Y-2495D03*
Y19473D03*
Y17505D03*
X1759327Y286919D03*
G54D243*
X938780Y1714890D03*
G54D24*
X42809Y366396D03*
X39008D03*
X36524Y395255D03*
X54620Y61801D03*
X50308D03*
X59322Y366396D03*
X51114D03*
X56163Y416987D03*
X59833Y1609818D03*
Y1618818D03*
X50333D03*
X54333D03*
X47333Y1659818D03*
X53700Y1677684D03*
X63429Y366396D03*
X67681D03*
X69523Y416987D03*
X77588Y659636D03*
X75274Y1549578D03*
X74100Y1618784D03*
X78000D03*
X73833Y1686718D03*
X77833Y1686618D03*
X69833D03*
X86302Y640089D03*
X89461Y663615D03*
X85565Y663623D03*
X93547Y688629D03*
X82311Y712833D03*
X84048Y1574445D03*
X88048D03*
X92251D03*
X81900Y1618784D03*
X85800D03*
X81833Y1686618D03*
X110987Y544699D03*
X97549Y688549D03*
X100931Y705261D03*
X100914Y712231D03*
X107170Y1520226D03*
X96251Y1574445D03*
X104900Y1611884D03*
X124170Y483297D03*
X120060D03*
X115060Y544706D03*
X127377Y544939D03*
X123257Y544869D03*
X119087Y544779D03*
X114021Y666841D03*
X118021D03*
X135006Y493599D03*
X130006D03*
X141103Y483297D03*
X145213D03*
X149568Y1403154D03*
X155098Y1566149D03*
X159107Y1566077D03*
X158118Y1711501D03*
X166631Y1412429D03*
X191267Y702510D03*
X187711Y1403154D03*
X176793Y1582458D03*
X195888Y578455D03*
X199941Y600557D03*
X195888Y612455D03*
X199941Y634557D03*
X195888Y646455D03*
X193461Y669627D03*
X195467Y702510D03*
X204174Y1411729D03*
X200720Y1713346D03*
X222907Y321740D03*
X247487Y107744D03*
X243487D03*
X254297Y127027D03*
X250297D03*
X246297D03*
X242297D03*
X254756Y159786D03*
X271797Y127027D03*
X261297D03*
X268297Y130527D03*
X259933Y146786D03*
X260100Y156946D03*
X263240Y242266D03*
X289357Y118987D03*
X277240Y242266D03*
X303573Y1361337D03*
X313995Y235233D03*
X306956Y562851D03*
X320614Y1369675D03*
X325617Y84227D03*
X332700Y141846D03*
X328700D03*
X338249Y226993D03*
X328965Y234723D03*
X332465D03*
X324106Y602357D03*
X328106D03*
X335673Y1339037D03*
X339811Y126161D03*
X342285Y213593D03*
X346203Y213611D03*
X346249Y226993D03*
X342249D03*
X352742Y1346877D03*
X367807Y1325076D03*
X386004Y1332902D03*
X385123Y1646233D03*
X378547Y1646239D03*
X374391Y1653935D03*
X374509Y1685643D03*
X399935Y1325076D03*
X391563Y1645703D03*
X414595Y947457D03*
X418595D03*
X410795D03*
X414616Y939132D03*
X414626Y962240D03*
X410826D03*
X418626D03*
X418671Y976741D03*
X414626D03*
X410871D03*
X410800Y991152D03*
X414600D03*
X418600D03*
X414550Y1005634D03*
X410838D03*
X418550D03*
X418591Y1020094D03*
X410816D03*
X414591D03*
X417104Y1332902D03*
X407125Y1422487D03*
X407557Y1658369D03*
X422395Y947457D03*
X422426Y962240D03*
X422471Y976741D03*
X422400Y991152D03*
X422350Y1005634D03*
X422391Y1020094D03*
X432063Y1325076D03*
X429383Y1600138D03*
X433383D03*
X437840Y125255D03*
X452071Y263973D03*
X445720Y402246D03*
X451720Y411246D03*
X451520Y482321D03*
X442520D03*
X437520D03*
X447520D03*
X448873Y1332902D03*
X446258Y1439115D03*
X449778D03*
X438020Y1567921D03*
X450020D03*
X437990Y1647261D03*
X441990D03*
X468323Y264055D03*
X455720Y411246D03*
X462720Y402246D03*
X466520Y473321D03*
X456520Y482321D03*
X461520D03*
X462704Y947457D03*
X466704Y939132D03*
X462704D03*
X458904D03*
X466704Y947457D03*
X458904D03*
X466704Y962240D03*
X458904D03*
X462704D03*
X466704Y976741D03*
X458904D03*
X462704D03*
X466704Y991152D03*
X462704D03*
X458904D03*
X466704Y1005634D03*
X458904D03*
X462704D03*
X466704Y1020094D03*
X458904D03*
X462704D03*
X464191Y1325076D03*
X468620Y1407446D03*
X459520Y1552421D03*
X456020Y1577921D03*
X464020D03*
X457220Y1589479D03*
X464930Y1654716D03*
X473500Y237846D03*
X475252Y263994D03*
X481500Y296846D03*
X478720Y366346D03*
X482720D03*
X479169Y482180D03*
X474169D03*
X484169D03*
X470504Y939132D03*
Y947457D03*
Y962240D03*
Y976741D03*
Y991152D03*
Y1005634D03*
Y1020094D03*
X481254Y1332894D03*
X476281Y1418977D03*
X477368Y1407454D03*
X480252Y1418977D03*
X472701Y1407454D03*
X481468D03*
X499096Y264698D03*
X492936Y264741D03*
X485500Y296846D03*
X494720Y366346D03*
X488169Y482180D03*
X498169D03*
X493169D03*
X496319Y1338502D03*
X485712Y1424961D03*
X517020Y86346D03*
X512220D03*
X515804Y264947D03*
X509496Y265023D03*
X514720Y366346D03*
X510720D03*
X502720D03*
X513720Y395846D03*
X504040Y381386D03*
X509720Y395846D03*
X503169Y473180D03*
X513382Y1346877D03*
X525720Y293846D03*
X527720Y366346D03*
X529720Y395846D03*
X520830Y383866D03*
X525720Y395846D03*
X528447Y1361300D03*
X535720Y366346D03*
X545510Y1369675D03*
X552720Y167846D03*
X559300Y420241D03*
X552000Y1459846D03*
X569300Y411391D03*
X597220Y91346D03*
X589330Y91004D03*
X593240D03*
X598724Y153355D03*
X593220Y182346D03*
Y190346D03*
X596800Y505016D03*
X614384Y124876D03*
X610104D03*
X602278D03*
X599720Y182346D03*
Y190346D03*
X614095Y278114D03*
X608895D03*
X611609Y323904D03*
X603822Y323854D03*
X622000Y91346D03*
X630951Y124876D03*
X626699D03*
X622592D03*
X627064Y256186D03*
X619496Y323954D03*
X627236Y323935D03*
X647725Y1649178D03*
X643725D03*
X653820Y87246D03*
X655000Y94846D03*
X661865Y511538D03*
X659039Y521075D03*
X654927Y528164D03*
X663187Y1403179D03*
X650225Y1705678D03*
X676643Y111869D03*
X680623D03*
X670220Y501346D03*
X675220D03*
X680220D03*
X675220Y514346D03*
X680250Y1411554D03*
X694453Y131152D03*
X687453D03*
X683453D03*
X688290Y385406D03*
X690220Y514346D03*
X685220D03*
X704000Y79346D03*
X704953Y131152D03*
X700963Y131212D03*
X713220Y383846D03*
X711220Y514346D03*
X705220D03*
X701330Y1403179D03*
X711780Y1620414D03*
X723933Y138472D03*
X727000Y371209D03*
X722500D03*
X718393Y1411554D03*
X725552Y1605577D03*
X719612Y1605667D03*
X726720Y1647424D03*
X722630Y1652954D03*
X735800Y371209D03*
X731400D03*
X745220Y501346D03*
Y527846D03*
X730680Y1647424D03*
X760193Y103712D03*
X758220Y444846D03*
X761700Y514946D03*
X751220Y527846D03*
X759859Y1692079D03*
X765160Y284306D03*
X776000Y366846D03*
X764000D03*
X771960Y366966D03*
X767960D03*
X777220Y448346D03*
X772952Y1587177D03*
X763359Y1726579D03*
X789720Y428346D03*
X787520Y519966D03*
X798400Y366184D03*
X806000D03*
X796546Y416110D03*
X819114Y120682D03*
X827114D03*
X823114D03*
X826614Y150182D03*
X813800Y386084D03*
X818000D03*
X824220Y428346D03*
X816670Y505406D03*
X812810Y519866D03*
X815252Y1588077D03*
X839360Y120566D03*
X831114Y120682D03*
X840220Y200846D03*
Y187846D03*
X836300Y424384D03*
X844935Y93235D03*
X844220Y200846D03*
Y187846D03*
X856190Y190094D03*
X845505Y287475D03*
Y297761D03*
X849000Y441184D03*
X857252Y1588077D03*
X886503Y281771D03*
X891747Y870838D03*
X887897D03*
X881372Y917939D03*
X899252Y1588077D03*
X921757Y967671D03*
X916974D03*
X926823Y967636D03*
X957027Y198881D03*
X947348Y988561D03*
X961137Y198833D03*
X981445Y178567D03*
X977195Y206907D03*
X981789Y363944D03*
X987139Y427440D03*
X1005699Y170327D03*
X996415Y178057D03*
X999915D03*
X1005395Y217407D03*
X991140Y427440D03*
X1009735Y156927D03*
X1015275Y156933D03*
X1016506Y427288D03*
X1012506D03*
X1023220Y185083D03*
X1034835Y299194D03*
X1031025D03*
X1025958Y365648D03*
X1029922Y365653D03*
X1043424Y285982D03*
X1038606Y299194D03*
X1091457Y1644334D03*
X1103457D03*
X1113140Y1672975D03*
X1105457Y1672934D03*
X1122879Y1439483D03*
X1124862Y1620734D03*
X1124762Y1628394D03*
X1139942Y1447858D03*
X1152720Y186346D03*
X1156720D03*
X1161022Y1439483D03*
X1164830Y1660599D03*
X1159930D03*
X1173374Y173115D03*
X1178085Y1447858D03*
X1181930Y1660599D03*
X1175830D03*
X1170930D03*
X1191206Y139033D03*
X1185030Y1630445D03*
X1192500Y1660909D03*
X1197400D03*
X1186830Y1660599D03*
X1197240Y1706389D03*
X1192340D03*
X1211720Y210346D03*
X1207220D03*
X1215720D03*
X1212610Y222136D03*
X1207530Y222036D03*
X1216610Y222136D03*
X1209900Y247057D03*
X1216656D03*
X1203267Y1655969D03*
X1208010Y1706434D03*
X1203110D03*
X1213910Y1706699D03*
X1218810D03*
X1263150Y303000D03*
X1251150D03*
X1281940Y90756D03*
X1274864Y110196D03*
X1267322Y106648D03*
X1267150Y303000D03*
X1279834Y1361573D03*
X1286013Y82383D03*
X1297342Y290891D03*
X1293398D03*
X1290437Y752449D03*
X1296875Y1369911D03*
X1313788Y65284D03*
X1303264Y77774D03*
X1307542Y301301D03*
X1303542D03*
X1311820Y1338502D03*
X1328883Y1346877D03*
X1343948Y1325076D03*
X1362145Y1332902D03*
X1366001Y98579D03*
X1366369Y89554D03*
X1376076Y1325076D03*
X1394736Y947456D03*
X1390736D03*
X1390719Y939122D03*
X1386936Y947456D03*
X1386967Y962239D03*
X1390767D03*
X1394767D03*
X1390812Y976740D03*
X1394812D03*
X1387012D03*
X1394741Y991151D03*
X1390741D03*
X1386941D03*
X1390691Y1005633D03*
X1394691D03*
X1386891D03*
X1394732Y1020093D03*
X1386869D03*
X1390732D03*
X1393245Y1332902D03*
X1382347Y1397087D03*
X1385066Y1422487D03*
X1398536Y947456D03*
X1398567Y962239D03*
X1398612Y976740D03*
X1398541Y991151D03*
X1398491Y1005633D03*
X1398532Y1020093D03*
X1408204Y1325076D03*
X1402680Y1603256D03*
X1425014Y1332902D03*
X1427349Y1439625D03*
X1423519Y1439635D03*
X1422680Y1587884D03*
X1438845Y947456D03*
X1435045D03*
X1438845Y939131D03*
X1442845Y947456D03*
Y939131D03*
X1435045D03*
X1442845Y962239D03*
X1438845D03*
X1435045D03*
X1438845Y976740D03*
X1442845D03*
X1435045D03*
X1442845Y991151D03*
X1438845D03*
X1435045D03*
X1438845Y1005633D03*
X1435045D03*
X1442845D03*
X1438845Y1020093D03*
X1442845D03*
X1435045D03*
X1440332Y1325076D03*
X1444720Y1407446D03*
X1438547Y1643819D03*
X1443617Y1643799D03*
X1455600Y294184D03*
X1447800D03*
X1458300Y367446D03*
X1449777Y367480D03*
X1453777D03*
X1451780Y410406D03*
X1456777Y424055D03*
X1446645Y939131D03*
Y947456D03*
Y962239D03*
Y976740D03*
Y991151D03*
Y1005633D03*
Y1020093D03*
X1457395Y1332894D03*
X1453509Y1407454D03*
X1452422Y1418977D03*
X1448842Y1407454D03*
X1457609D03*
X1456393Y1418977D03*
X1454167Y1643899D03*
X1459127D03*
X1448507Y1643809D03*
X1463000Y158846D03*
X1466777Y367480D03*
X1470777D03*
X1472460Y1338502D03*
X1461803Y1424991D03*
X1472565Y1631086D03*
X1463767Y1643899D03*
X1493384Y416772D03*
X1481384D03*
X1489523Y1346877D03*
X1504602Y298241D03*
X1504278Y287939D03*
X1504602Y310240D03*
X1498184Y367182D03*
X1497384Y416772D03*
X1504588Y1361300D03*
X1524654Y57599D03*
X1517263Y196321D03*
X1521828Y302259D03*
X1521651Y1369675D03*
X1528654Y57599D03*
X1537746Y1306402D03*
X1547697Y124262D03*
X1543720Y587346D03*
X1548720D03*
X1557287Y631919D03*
X1563994Y584201D03*
X1567994D03*
X1624353Y1436775D03*
X1644360Y205724D03*
X1648400Y205714D03*
X1652610Y400186D03*
X1647110Y431686D03*
X1649291Y552219D03*
X1649220Y618146D03*
X1653220D03*
X1641416Y1445150D03*
X1661110Y431686D03*
X1664040Y567136D03*
X1672040D03*
X1668040D03*
X1657220Y618146D03*
X1662496Y1436775D03*
X1673872Y431129D03*
X1686154Y431669D03*
X1676040Y567136D03*
X1680040D03*
X1679559Y1445150D03*
X1703932Y229503D03*
X1704624Y431159D03*
X1701124D03*
X1703720Y506846D03*
X1698720D03*
X1702320Y539456D03*
X1695443Y716329D03*
X1718608Y108868D03*
X1717418Y128151D03*
X1721418D03*
X1715044Y410029D03*
X1718931Y410021D03*
X1710408Y423429D03*
X1708977Y468288D03*
X1713977D03*
X1708030Y691236D03*
X1713159Y691259D03*
X1714298Y714599D03*
X1714320Y707746D03*
X1709107Y725269D03*
X1722608Y108868D03*
X1736418Y128151D03*
X1729418D03*
X1725418D03*
X1725500Y380846D03*
X1722500Y371846D03*
X1733780Y396254D03*
X1729810D03*
X1737660D03*
X1730290Y420324D03*
X1734290D03*
X1736611Y493751D03*
X1746918Y128151D03*
X1743418Y131651D03*
X1746366Y286516D03*
X1743170Y408284D03*
X1764478Y120111D03*
X1769230Y307901D03*
X1758563D03*
X1765663D03*
X1762163D03*
X1754963D03*
X1772863D03*
X1778810Y455124D03*
X1790738Y85351D03*
X1819461Y153785D03*
X1813700Y1500271D03*
X1826075Y1507825D03*
X1843166Y241830D03*
G54D60*
X87225Y712316D03*
X1700657Y716442D03*
G54D126*
X238780Y1648385D03*
X230906Y1644448D03*
X238780Y1662558D03*
X230906Y1658621D03*
X238780Y1676732D03*
X230906Y1672795D03*
X238780Y1690905D03*
X230906Y1686968D03*
X238780Y1705078D03*
X230906Y1701141D03*
Y1715314D03*
X238780Y1719251D03*
X230906Y1729488D03*
X238780Y1733425D03*
X254528Y1648385D03*
X246654Y1644448D03*
X254528Y1662558D03*
X246654Y1658621D03*
X254528Y1676732D03*
X246654Y1672795D03*
X254528Y1690905D03*
X246654Y1686968D03*
X254528Y1705078D03*
X246654Y1701141D03*
Y1715314D03*
X254528Y1719251D03*
X246654Y1729488D03*
X254528Y1733425D03*
X270276Y1648385D03*
X262402Y1644448D03*
X270276Y1662558D03*
X262402Y1658621D03*
X270276Y1676732D03*
X262402Y1672795D03*
X270276Y1690905D03*
X262402Y1686968D03*
X270276Y1705078D03*
X262402Y1701141D03*
Y1715314D03*
X270276Y1719251D03*
X262402Y1729488D03*
X270276Y1733425D03*
X286024Y1648385D03*
X278150Y1644448D03*
X286024Y1662558D03*
X278150Y1658621D03*
X286024Y1676732D03*
X278150Y1672795D03*
X286024Y1690905D03*
X278150Y1686968D03*
X286024Y1705078D03*
X278150Y1701141D03*
Y1715314D03*
X286024Y1719251D03*
X278150Y1729488D03*
X286024Y1733425D03*
X297835Y1672795D03*
X305709Y1676732D03*
X297835Y1686968D03*
X305709Y1690905D03*
X297835Y1701141D03*
X305709Y1705078D03*
X297835Y1715314D03*
X305709Y1719251D03*
X297835Y1729488D03*
X305709Y1733425D03*
X313583Y1672795D03*
X321457Y1676732D03*
X313583Y1686968D03*
X321457Y1690905D03*
X313583Y1701141D03*
X321457Y1705078D03*
X313583Y1715314D03*
X321457Y1719251D03*
X313583Y1729488D03*
X321457Y1733425D03*
X329331Y1672795D03*
X337205Y1676732D03*
X329331Y1686968D03*
X337205Y1690905D03*
X329331Y1701141D03*
X337205Y1705078D03*
X329331Y1715314D03*
X337205Y1719251D03*
X329331Y1729488D03*
X337205Y1733425D03*
X345079Y1672795D03*
X352953Y1676732D03*
X345079Y1686968D03*
X352953Y1690905D03*
X345079Y1701141D03*
X352953Y1705078D03*
X345079Y1715314D03*
X352953Y1719251D03*
X345079Y1729488D03*
X352953Y1733425D03*
X495079Y1672795D03*
Y1686968D03*
Y1701141D03*
Y1715314D03*
Y1729488D03*
X510827Y1672795D03*
X502953Y1676732D03*
X518701D03*
X510827Y1686968D03*
X502953Y1690905D03*
X518701D03*
X510827Y1701141D03*
X502953Y1705078D03*
X518701D03*
X510827Y1715314D03*
X502953Y1719251D03*
X518701D03*
X510827Y1729488D03*
X502953Y1733425D03*
X518701D03*
X526575Y1672795D03*
X534449Y1676732D03*
X526575Y1686968D03*
X534449Y1690905D03*
X526575Y1701141D03*
X534449Y1705078D03*
X526575Y1715314D03*
X534449Y1719251D03*
X526575Y1729488D03*
X534449Y1733425D03*
X542323Y1672795D03*
X550197Y1676732D03*
X542323Y1686968D03*
X550197Y1690905D03*
X542323Y1701141D03*
X550197Y1705078D03*
X542323Y1715314D03*
X550197Y1719251D03*
X542323Y1729488D03*
X550197Y1733425D03*
X562008Y1672795D03*
Y1686968D03*
Y1701141D03*
Y1715314D03*
Y1729488D03*
X577756Y1672795D03*
X569882Y1676732D03*
X577756Y1686968D03*
X569882Y1690905D03*
X577756Y1701141D03*
X569882Y1705078D03*
X577756Y1715314D03*
X569882Y1719251D03*
X577756Y1729488D03*
X569882Y1733425D03*
X593504Y1672795D03*
X585630Y1676732D03*
X593504Y1686968D03*
X585630Y1690905D03*
X593504Y1701141D03*
X585630Y1705078D03*
X593504Y1715314D03*
X585630Y1719251D03*
X593504Y1729488D03*
X585630Y1733425D03*
X609252Y1672795D03*
X601378Y1676732D03*
X609252Y1686968D03*
X601378Y1690905D03*
X609252Y1701141D03*
X601378Y1705078D03*
X609252Y1715314D03*
X601378Y1719251D03*
X609252Y1729488D03*
X601378Y1733425D03*
X617126Y1676732D03*
Y1690905D03*
Y1705078D03*
Y1719251D03*
Y1733425D03*
X1238780Y1672795D03*
X1246654Y1676732D03*
X1238780Y1686968D03*
X1246654Y1690905D03*
X1238780Y1701141D03*
X1246654Y1705078D03*
X1238780Y1715314D03*
X1246654Y1719251D03*
X1238780Y1729488D03*
X1246654Y1733425D03*
X1254528Y1672795D03*
X1262402Y1676732D03*
X1254528Y1686968D03*
X1262402Y1690905D03*
X1254528Y1701141D03*
X1262402Y1705078D03*
X1254528Y1715314D03*
X1262402Y1719251D03*
X1254528Y1729488D03*
X1262402Y1733425D03*
X1270276Y1672795D03*
X1278150Y1676732D03*
X1270276Y1686968D03*
X1278150Y1690905D03*
X1270276Y1701141D03*
X1278150Y1705078D03*
X1270276Y1715314D03*
X1278150Y1719251D03*
X1270276Y1729488D03*
X1278150Y1733425D03*
X1286024Y1672795D03*
X1293898Y1676732D03*
X1286024Y1686968D03*
X1293898Y1690905D03*
X1286024Y1701141D03*
X1293898Y1705078D03*
X1286024Y1715314D03*
X1293898Y1719251D03*
X1286024Y1729488D03*
X1293898Y1733425D03*
X1305709Y1672795D03*
X1313583Y1676732D03*
X1305709Y1686968D03*
X1313583Y1690905D03*
X1305709Y1701141D03*
X1313583Y1705078D03*
X1305709Y1715314D03*
X1313583Y1719251D03*
X1305709Y1729488D03*
X1313583Y1733425D03*
X1321457Y1672795D03*
X1329331Y1676732D03*
X1321457Y1686968D03*
X1329331Y1690905D03*
X1321457Y1701141D03*
X1329331Y1705078D03*
X1321457Y1715314D03*
X1329331Y1719251D03*
X1321457Y1729488D03*
X1329331Y1733425D03*
X1337205Y1672795D03*
X1345079Y1676732D03*
X1337205Y1686968D03*
X1345079Y1690905D03*
X1337205Y1701141D03*
X1345079Y1705078D03*
X1337205Y1715314D03*
X1345079Y1719251D03*
X1337205Y1729488D03*
X1345079Y1733425D03*
X1352953Y1672795D03*
X1360827Y1676732D03*
X1352953Y1686968D03*
X1360827Y1690905D03*
X1352953Y1701141D03*
X1360827Y1705078D03*
X1352953Y1715314D03*
X1360827Y1719251D03*
X1352953Y1729488D03*
X1360827Y1733425D03*
X1502953Y1672795D03*
X1510827Y1676732D03*
X1502953Y1686968D03*
X1510827Y1690905D03*
X1502953Y1701141D03*
X1510827Y1705078D03*
X1502953Y1715314D03*
X1510827Y1719251D03*
X1502953Y1729488D03*
X1510827Y1733425D03*
X1518701Y1672795D03*
X1526575Y1676732D03*
X1518701Y1686968D03*
X1526575Y1690905D03*
X1518701Y1701141D03*
X1526575Y1705078D03*
X1518701Y1715314D03*
X1526575Y1719251D03*
X1518701Y1729488D03*
X1526575Y1733425D03*
X1534449Y1672795D03*
X1542323Y1676732D03*
X1534449Y1686968D03*
X1542323Y1690905D03*
X1534449Y1701141D03*
X1542323Y1705078D03*
X1534449Y1715314D03*
X1542323Y1719251D03*
X1534449Y1729488D03*
X1542323Y1733425D03*
X1550197Y1672795D03*
X1558071Y1676732D03*
X1550197Y1686968D03*
X1558071Y1690905D03*
X1550197Y1701141D03*
X1558071Y1705078D03*
X1550197Y1715314D03*
X1558071Y1719251D03*
X1550197Y1729488D03*
X1558071Y1733425D03*
X1569882Y1672795D03*
Y1686968D03*
Y1701141D03*
Y1715314D03*
Y1729488D03*
X1585630Y1672795D03*
X1577756Y1676732D03*
X1585630Y1686968D03*
X1577756Y1690905D03*
X1585630Y1701141D03*
X1577756Y1705078D03*
X1585630Y1715314D03*
X1577756Y1719251D03*
X1585630Y1729488D03*
X1577756Y1733425D03*
X1601378Y1672795D03*
X1593504Y1676732D03*
X1601378Y1686968D03*
X1593504Y1690905D03*
X1601378Y1701141D03*
X1593504Y1705078D03*
X1601378Y1715314D03*
X1593504Y1719251D03*
X1601378Y1729488D03*
X1593504Y1733425D03*
X1617126Y1672795D03*
X1609252Y1676732D03*
X1625000D03*
X1617126Y1686968D03*
X1609252Y1690905D03*
X1625000D03*
X1617126Y1701141D03*
X1609252Y1705078D03*
X1625000D03*
X1617126Y1715314D03*
X1609252Y1719251D03*
X1625000D03*
X1617126Y1729488D03*
X1609252Y1733425D03*
X1625000D03*
G54D225*
X828780Y1694890D03*
Y1684890D03*
X818780Y1694890D03*
Y1684890D03*
X828780Y1704890D03*
X818780D03*
X828780Y1714890D03*
X818780D03*
X853780Y1694890D03*
Y1684890D03*
Y1704890D03*
Y1714890D03*
X863780Y1694890D03*
Y1684890D03*
Y1704890D03*
Y1714890D03*
X888780Y1684890D03*
Y1694890D03*
Y1704890D03*
Y1714890D03*
X898780Y1684890D03*
Y1694890D03*
Y1704890D03*
Y1714890D03*
X918780Y1684890D03*
Y1694890D03*
Y1704890D03*
Y1714890D03*
X928780Y1684890D03*
X938780D03*
X928780Y1694890D03*
X938780D03*
X928780Y1704890D03*
X938780D03*
X928780Y1714890D03*
X958780Y1694890D03*
Y1684890D03*
Y1704890D03*
Y1714890D03*
X968780Y1694890D03*
Y1684890D03*
Y1704890D03*
Y1714890D03*
X993780Y1684890D03*
Y1694890D03*
X1003780Y1684890D03*
Y1694890D03*
X993780Y1704890D03*
Y1714890D03*
X1003780Y1704890D03*
Y1714890D03*
X1028780Y1684890D03*
Y1694890D03*
X1038780Y1684890D03*
Y1694890D03*
X1028780Y1704890D03*
Y1714890D03*
X1038780Y1704890D03*
Y1714890D03*
G54D180*
X473500Y246362D03*
X498563Y607067D03*
X520000Y278543D03*
X549236Y1441207D03*
X688500Y1621900D03*
X1041435Y163357D03*
X1056225Y163131D03*
X1099970Y1722570D03*
X1679646Y175669D03*
X1771457Y1624646D03*
G54D324*
X1881720Y988279D03*
X1886720Y1001463D03*
X1876720D03*
X1875836Y1303980D03*
X1885836D03*
X1880836Y1317164D03*
X1881211Y1350983D03*
X1886211Y1364167D03*
X1876211D03*
X1876165Y1669023D03*
X1886165D03*
X1881165Y1682207D03*
X1902608Y988322D03*
X1897608Y1001506D03*
X1898086Y1305044D03*
X1903086Y1318228D03*
X1902682Y1351295D03*
X1897682Y1364479D03*
X1902402Y1683256D03*
X1897402Y1670072D03*
X1907608Y1001506D03*
X1908086Y1305044D03*
X1907682Y1364479D03*
X1907402Y1670072D03*
X1930200Y1349548D03*
X1935200Y1362732D03*
X1925200D03*
X1929695Y1683220D03*
X1924695Y1670036D03*
X1934695D03*
X1951178Y1349597D03*
X1946178Y1362781D03*
X1950484Y1683497D03*
X1945484Y1670313D03*
X1967697Y1362790D03*
X1956178Y1362781D03*
X1966555Y1669946D03*
X1955484Y1670313D03*
X1972697Y1349606D03*
X1977697Y1362790D03*
X1976555Y1669946D03*
X1971555Y1683130D03*
X1993618Y1349897D03*
X1988618Y1363081D03*
X1998618D03*
X1998147Y1669691D03*
X1988147D03*
X1993147Y1682875D03*
G54D15*
X25320Y146662D03*
X40600Y1580802D03*
X493180Y647432D03*
X932820Y1310432D03*
X1112670Y541642D03*
X1807990Y1656032D03*
X1835620Y210432D03*
G54D33*
X60303Y20354D03*
X312921Y24291D03*
X505185Y41142D03*
X757803Y45079D03*
X922441Y237697D03*
X929331Y160413D03*
X1534712Y20354D03*
X1787330Y24291D03*
G54D153*
X335928Y879124D03*
X337779Y875920D03*
Y882329D03*
X335928Y885533D03*
Y891942D03*
Y898350D03*
X337779Y888737D03*
Y895146D03*
Y901555D03*
X335928Y904759D03*
Y911167D03*
Y917576D03*
X337779Y907963D03*
Y914372D03*
X335928Y923985D03*
Y930393D03*
X337779Y920780D03*
Y927189D03*
Y933598D03*
X335928Y936801D03*
Y943210D03*
Y949619D03*
X337779Y940006D03*
Y946414D03*
X335928Y956027D03*
Y962436D03*
X337779Y952823D03*
Y959232D03*
Y965640D03*
X335928Y968845D03*
Y975253D03*
X337779Y972049D03*
Y978457D03*
X336361Y1010391D03*
X338211Y1007187D03*
Y1013595D03*
X336361Y1016800D03*
Y1023208D03*
X338211Y1020004D03*
X336361Y1029617D03*
X338211Y1026413D03*
Y1022114D03*
X336361Y1036026D03*
Y1042434D03*
X338211Y1032821D03*
Y1039230D03*
Y1045639D03*
Y1041340D03*
X336361Y1048842D03*
X338211Y1052047D03*
Y1058455D03*
Y1060565D03*
Y1064864D03*
Y1071273D03*
Y1077681D03*
Y1084090D03*
Y1090498D03*
Y1096907D03*
Y1103316D03*
Y1109724D03*
Y1105426D03*
X352579Y850286D03*
X347029Y859899D03*
Y866307D03*
X348879Y856694D03*
Y863103D03*
X350728Y853490D03*
Y859899D03*
Y866307D03*
X352579Y856694D03*
Y863103D03*
X354428Y853490D03*
Y859899D03*
Y866307D03*
X343328D03*
X345179Y863103D03*
X341479Y867401D03*
X347029Y872716D03*
X348879Y869511D03*
X350728Y872716D03*
X352579Y869511D03*
X354428Y872716D03*
X339629D03*
X341479Y869511D03*
X343328Y872716D03*
X345179Y869511D03*
X347029Y879124D03*
X348879Y875920D03*
Y882329D03*
X350728Y879124D03*
X352579Y875920D03*
Y882329D03*
X354428Y879124D03*
X339629D03*
X341479Y875920D03*
Y882329D03*
X343328Y879124D03*
X345179Y875920D03*
Y882329D03*
X341479Y873810D03*
X347029Y885533D03*
Y891942D03*
Y898350D03*
X348879Y888737D03*
Y895146D03*
Y901555D03*
X350728Y885533D03*
Y891942D03*
Y898350D03*
X352579Y888737D03*
Y895146D03*
Y901555D03*
X354428Y885533D03*
Y891942D03*
Y898350D03*
X339629Y885533D03*
Y891942D03*
Y898350D03*
X341479Y888737D03*
Y895146D03*
Y901555D03*
X343328Y885533D03*
Y891942D03*
Y898350D03*
X345179Y888737D03*
Y895146D03*
Y901555D03*
X347029Y904759D03*
Y911167D03*
Y917576D03*
X348879Y907963D03*
Y914372D03*
X350728Y904759D03*
Y911167D03*
Y917576D03*
X352579Y907963D03*
Y914372D03*
X354428Y904759D03*
Y911167D03*
Y917576D03*
X339629Y904759D03*
Y911167D03*
Y917576D03*
X341479Y907963D03*
Y914372D03*
X343328Y904759D03*
Y911167D03*
Y917576D03*
X345179Y907963D03*
Y914372D03*
X341479Y912262D03*
X341478Y905853D03*
X347029Y923985D03*
Y930393D03*
X348879Y920780D03*
Y927189D03*
Y933598D03*
X350728Y923985D03*
Y930393D03*
X352579Y920780D03*
Y927189D03*
Y933598D03*
X354428Y923985D03*
Y930393D03*
X339629Y923985D03*
Y930393D03*
X341479Y920780D03*
Y927189D03*
Y933598D03*
X343328Y923985D03*
Y930393D03*
X345179Y920780D03*
Y927189D03*
Y933598D03*
X341478Y925079D03*
X341479Y931488D03*
X347029Y936801D03*
Y943210D03*
Y949619D03*
X348879Y940006D03*
Y946414D03*
X350728Y936801D03*
Y943210D03*
Y949619D03*
X352579Y940006D03*
Y946414D03*
X354428Y936801D03*
Y943210D03*
Y949619D03*
X339629Y936801D03*
Y943210D03*
Y949619D03*
X341479Y940006D03*
Y946414D03*
X343328Y936801D03*
Y943210D03*
Y949619D03*
X345179Y940006D03*
Y946414D03*
X341478Y944304D03*
X347029Y956027D03*
Y962436D03*
X348879Y952823D03*
Y959232D03*
X350728Y956027D03*
Y962436D03*
X352579Y952823D03*
Y959232D03*
X354428Y956027D03*
Y962436D03*
X339629Y956027D03*
Y962436D03*
X341479Y952823D03*
Y959232D03*
X343328Y956027D03*
Y962436D03*
X345179Y952823D03*
Y959232D03*
X348879Y965640D03*
X352579D03*
X341479D03*
X345179D03*
X343328Y960326D03*
X343329Y966735D03*
X341479Y950713D03*
X347029Y968845D03*
Y975253D03*
Y981662D03*
X348879Y972049D03*
Y978457D03*
X350728Y968845D03*
Y975253D03*
Y981662D03*
X352579Y972049D03*
Y978457D03*
X354428Y968845D03*
Y975253D03*
Y981662D03*
X339629Y968845D03*
Y975253D03*
Y981662D03*
X341479Y972049D03*
Y978457D03*
X343328Y968845D03*
Y975253D03*
Y981662D03*
X345179Y972049D03*
Y978457D03*
X348879Y984866D03*
X352579D03*
X341479D03*
X345179D03*
X347461Y997574D03*
X351161D03*
X354861D03*
X343761D03*
X347461Y1003983D03*
Y1010391D03*
X349312Y1000778D03*
Y1007187D03*
Y1013595D03*
X351161Y1003983D03*
Y1010391D03*
X353011Y1000778D03*
Y1007187D03*
Y1013595D03*
X354861Y1003983D03*
Y1010391D03*
X340061Y1003983D03*
Y1010391D03*
X341912Y1000778D03*
Y1007187D03*
Y1013595D03*
X343761Y1003983D03*
Y1010391D03*
X345611Y1000778D03*
Y1007187D03*
Y1013595D03*
X341911Y1009297D03*
Y1002888D03*
X347461Y1016800D03*
Y1023208D03*
X349312Y1020004D03*
X351161Y1016800D03*
Y1023208D03*
X353011Y1020004D03*
X354861Y1016800D03*
Y1023208D03*
X340061Y1016800D03*
Y1023208D03*
X341912Y1020004D03*
X343761Y1016800D03*
Y1023208D03*
X345611Y1020004D03*
X347461Y1029617D03*
X349312Y1026413D03*
X351161Y1029617D03*
X353011Y1026413D03*
X354861Y1029617D03*
X340061D03*
X341912Y1026413D03*
X343761Y1029617D03*
X345611Y1026413D03*
X341911Y1022114D03*
X343761Y1018910D03*
X345611Y1015705D03*
X343761Y1031727D03*
X347461Y1036026D03*
Y1042434D03*
X349312Y1032821D03*
Y1039230D03*
Y1045639D03*
X351161Y1036026D03*
Y1042434D03*
X353011Y1032821D03*
Y1039230D03*
Y1045639D03*
X354861Y1036026D03*
Y1042434D03*
X340061Y1036026D03*
Y1042434D03*
X341912Y1032821D03*
Y1039230D03*
Y1045639D03*
X343761Y1036026D03*
Y1042434D03*
X345611Y1032821D03*
Y1039230D03*
Y1045639D03*
X341911Y1041340D03*
X343761Y1038136D03*
X347461Y1048842D03*
X349312Y1052047D03*
X351161Y1048842D03*
X353011Y1052047D03*
X354861Y1048842D03*
X340061D03*
X341912Y1052047D03*
X343761Y1048842D03*
X345611Y1052047D03*
X347461Y1055251D03*
Y1061660D03*
X349312Y1058455D03*
X351161Y1055251D03*
Y1061660D03*
X353011Y1058455D03*
X354861Y1055251D03*
Y1061660D03*
X340061Y1055251D03*
Y1061660D03*
X341912Y1058455D03*
X343761Y1055251D03*
Y1061660D03*
X345611Y1058455D03*
X343761Y1057361D03*
Y1050952D03*
X347461Y1068068D03*
Y1074477D03*
X349312Y1064864D03*
Y1071273D03*
Y1077681D03*
X351161Y1068068D03*
Y1074477D03*
X353011Y1064864D03*
Y1071273D03*
Y1077681D03*
X354861Y1068068D03*
Y1074477D03*
X340061Y1068068D03*
Y1074477D03*
X341912Y1064864D03*
Y1071273D03*
Y1077681D03*
X343761Y1068068D03*
Y1074477D03*
X345611Y1064864D03*
Y1071273D03*
Y1077681D03*
X343761Y1076587D03*
Y1070178D03*
X341911Y1079791D03*
X347461Y1080885D03*
X351161D03*
X354861D03*
X340061D03*
X343761D03*
X347461Y1087294D03*
Y1093703D03*
X349312Y1084090D03*
Y1090498D03*
X351161Y1087294D03*
Y1093703D03*
X353011Y1084090D03*
Y1090498D03*
X354861Y1087294D03*
Y1093703D03*
X340061Y1087294D03*
Y1093703D03*
X341912Y1084090D03*
Y1090498D03*
X343761Y1087294D03*
Y1093703D03*
X345611Y1084090D03*
Y1090498D03*
X340060Y1082995D03*
X340061Y1095813D03*
X347461Y1100111D03*
Y1106520D03*
Y1112929D03*
X349312Y1096907D03*
Y1103316D03*
Y1109724D03*
X351161Y1100111D03*
Y1106520D03*
Y1112929D03*
X353011Y1096907D03*
Y1103316D03*
Y1109724D03*
X354861Y1100111D03*
Y1106520D03*
Y1112929D03*
X340061Y1100111D03*
Y1106520D03*
Y1112929D03*
X341912Y1096907D03*
Y1103316D03*
Y1109724D03*
X343761Y1100111D03*
Y1106520D03*
Y1112929D03*
X345611Y1096907D03*
Y1103316D03*
Y1109724D03*
X347461Y1119337D03*
Y1125746D03*
X349312Y1116133D03*
Y1122541D03*
Y1128950D03*
X351161Y1119337D03*
Y1125746D03*
X353011Y1116133D03*
Y1122541D03*
Y1128950D03*
X354861Y1119337D03*
Y1125746D03*
X341912Y1116133D03*
X343761Y1119337D03*
X345611Y1116133D03*
Y1122541D03*
X351161Y1132154D03*
X354861D03*
X371079Y850286D03*
X356279D03*
X358128Y847081D03*
X359979Y850286D03*
X361828Y847081D03*
X363679Y850286D03*
X365528Y847081D03*
X367379Y850286D03*
X369228Y847081D03*
X371079Y856694D03*
Y863103D03*
X356279Y856694D03*
Y863103D03*
X358128Y853490D03*
Y859899D03*
Y866307D03*
X359979Y856694D03*
Y863103D03*
X361828Y853490D03*
Y859899D03*
Y866307D03*
X363679Y856694D03*
Y863103D03*
X365528Y853490D03*
Y859899D03*
Y866307D03*
X367379Y856694D03*
Y863103D03*
X369228Y853490D03*
Y859899D03*
Y866307D03*
X371079Y869511D03*
X356279D03*
X358128Y872716D03*
X359979Y869511D03*
X361828Y872716D03*
X363679Y869511D03*
X365528Y872716D03*
X367379Y869511D03*
X369228Y872716D03*
X371079Y875920D03*
Y882329D03*
X356279Y875920D03*
Y882329D03*
X358128Y879124D03*
X359979Y875920D03*
Y882329D03*
X361828Y879124D03*
X363679Y875920D03*
Y882329D03*
X365528Y879124D03*
X367379Y875920D03*
Y882329D03*
X369228Y879124D03*
X371079Y888737D03*
Y895146D03*
Y901555D03*
X356279Y888737D03*
Y895146D03*
Y901555D03*
X358128Y885533D03*
Y891942D03*
Y898350D03*
X359979Y888737D03*
Y895146D03*
Y901555D03*
X361828Y885533D03*
Y891942D03*
Y898350D03*
X363679Y888737D03*
Y895146D03*
Y901555D03*
X365528Y885533D03*
Y891942D03*
Y898350D03*
X367379Y888737D03*
Y895146D03*
Y901555D03*
X369228Y885533D03*
Y891942D03*
Y898350D03*
X371079Y907963D03*
Y914372D03*
X356279Y907963D03*
Y914372D03*
X358128Y904759D03*
Y911167D03*
Y917576D03*
X359979Y907963D03*
Y914372D03*
X361828Y904759D03*
Y911167D03*
Y917576D03*
X363679Y907963D03*
Y914372D03*
X365528Y904759D03*
Y911167D03*
Y917576D03*
X367379Y907963D03*
Y914372D03*
X369228Y904759D03*
Y911167D03*
Y917576D03*
X371079Y920780D03*
Y927189D03*
X356279Y920780D03*
Y927189D03*
Y933598D03*
X358128Y923985D03*
Y930393D03*
X359979Y920780D03*
Y927189D03*
Y933598D03*
X361828Y923985D03*
Y930393D03*
X363679Y920780D03*
Y927189D03*
Y933598D03*
X365528Y923985D03*
Y930393D03*
X367379Y920780D03*
Y927189D03*
Y933598D03*
X369228Y923985D03*
Y930393D03*
X371079Y933598D03*
Y940006D03*
Y946414D03*
X356279Y940006D03*
Y946414D03*
X358128Y936801D03*
Y943210D03*
Y949619D03*
X359979Y940006D03*
Y946414D03*
X361828Y936801D03*
Y943210D03*
Y949619D03*
X363679Y940006D03*
Y946414D03*
X365528Y936801D03*
Y943210D03*
Y949619D03*
X367379Y940006D03*
Y946414D03*
X369228Y936801D03*
Y943210D03*
Y949619D03*
X371079Y952823D03*
Y959232D03*
X356279Y952823D03*
Y959232D03*
X358128Y956027D03*
Y962436D03*
X359979Y952823D03*
Y959232D03*
X361828Y956027D03*
Y962436D03*
X363679Y952823D03*
Y959232D03*
X365528Y956027D03*
Y962436D03*
X367379Y952823D03*
Y959232D03*
X369228Y956027D03*
Y962436D03*
X371079Y965640D03*
X356279D03*
X359979D03*
X363679D03*
X367379D03*
X371079Y972049D03*
Y978457D03*
X356279Y972049D03*
Y978457D03*
X358128Y968845D03*
Y975253D03*
Y981662D03*
X359979Y972049D03*
Y978457D03*
X361828Y968845D03*
Y975253D03*
Y981662D03*
X363679Y972049D03*
Y978457D03*
X365528Y968845D03*
Y975253D03*
Y981662D03*
X367379Y972049D03*
Y978457D03*
X369228Y968845D03*
Y975253D03*
Y981662D03*
X371079Y984866D03*
X356279D03*
X359979D03*
X363679D03*
X367379D03*
X358561Y997574D03*
X362261D03*
X365961D03*
X369661D03*
X356712Y1000778D03*
Y1007187D03*
Y1013595D03*
X358561Y1003983D03*
Y1010391D03*
X360412Y1000778D03*
Y1007187D03*
Y1013595D03*
X362261Y1003983D03*
Y1010391D03*
X364112Y1000778D03*
Y1007187D03*
Y1013595D03*
X365961Y1003983D03*
Y1010391D03*
X367812Y1000778D03*
Y1007187D03*
Y1013595D03*
X369661Y1003983D03*
Y1010391D03*
X367811Y1002888D03*
X371511D03*
X356712Y1020004D03*
X358561Y1016800D03*
Y1023208D03*
X360412Y1020004D03*
X362261Y1016800D03*
Y1023208D03*
X364112Y1020004D03*
X365961Y1016800D03*
Y1023208D03*
X367812Y1020004D03*
X369661Y1016800D03*
Y1023208D03*
X356712Y1026413D03*
X358561Y1029617D03*
X360412Y1026413D03*
X362261Y1029617D03*
X364112Y1026413D03*
X365961Y1029617D03*
X367812Y1026413D03*
X369661Y1029617D03*
X356712Y1032821D03*
Y1039230D03*
Y1045639D03*
X358561Y1036026D03*
Y1042434D03*
X360412Y1032821D03*
Y1039230D03*
Y1045639D03*
X362261Y1036026D03*
Y1042434D03*
X364112Y1032821D03*
Y1039230D03*
Y1045639D03*
X365961Y1036026D03*
Y1042434D03*
X367812Y1032821D03*
Y1039230D03*
Y1045639D03*
X369661Y1036026D03*
Y1042434D03*
X356712Y1052047D03*
X358561Y1048842D03*
X360412Y1052047D03*
X362261Y1048842D03*
X364112Y1052047D03*
X365961Y1048842D03*
X367812Y1052047D03*
X369661Y1048842D03*
X356712Y1058455D03*
X358561Y1055251D03*
Y1061660D03*
X360412Y1058455D03*
X362261Y1055251D03*
Y1061660D03*
X364112Y1058455D03*
X365961Y1055251D03*
Y1061660D03*
X367812Y1058455D03*
X369661Y1055251D03*
Y1061660D03*
X356712Y1064864D03*
Y1071273D03*
Y1077681D03*
X358561Y1068068D03*
Y1074477D03*
X360412Y1064864D03*
Y1071273D03*
Y1077681D03*
X362261Y1068068D03*
Y1074477D03*
X364112Y1064864D03*
Y1071273D03*
Y1077681D03*
X365961Y1068068D03*
Y1074477D03*
X367812Y1064864D03*
Y1071273D03*
Y1077681D03*
X369661Y1068068D03*
Y1074477D03*
X358561Y1080885D03*
X362261D03*
X365961D03*
X369661D03*
X356712Y1084090D03*
Y1090498D03*
X358561Y1087294D03*
Y1093703D03*
X360412Y1084090D03*
Y1090498D03*
X362261Y1087294D03*
Y1093703D03*
X364112Y1084090D03*
Y1090498D03*
X365961Y1087294D03*
Y1093703D03*
X367812Y1084090D03*
Y1090498D03*
X369661Y1087294D03*
Y1093703D03*
X356712Y1096907D03*
Y1103316D03*
Y1109724D03*
X358561Y1100111D03*
Y1106520D03*
Y1112929D03*
X360412Y1096907D03*
Y1103316D03*
Y1109724D03*
X362261Y1100111D03*
Y1106520D03*
Y1112929D03*
X364112Y1096907D03*
Y1103316D03*
Y1109724D03*
X365961Y1100111D03*
Y1106520D03*
Y1112929D03*
X367812Y1096907D03*
Y1103316D03*
Y1109724D03*
X369661Y1100111D03*
Y1106520D03*
Y1112929D03*
X356712Y1116133D03*
Y1122541D03*
Y1128950D03*
X358561Y1119337D03*
Y1125746D03*
X360412Y1116133D03*
Y1122541D03*
Y1128950D03*
X362261Y1119337D03*
Y1125746D03*
X364112Y1116133D03*
Y1122541D03*
Y1128950D03*
X365961Y1119337D03*
Y1125746D03*
X367812Y1116133D03*
Y1122541D03*
Y1128950D03*
X369661Y1119337D03*
Y1125746D03*
X358561Y1132154D03*
X360412Y1135359D03*
X362261Y1132154D03*
X364112Y1135359D03*
X365961Y1132154D03*
X367812Y1135359D03*
X369661Y1132154D03*
X376628Y847081D03*
X378479Y850286D03*
X380328Y847081D03*
X382179Y850286D03*
X384028Y847081D03*
X385879Y850286D03*
X387728Y847081D03*
X372928D03*
X374779Y850286D03*
X376628Y853490D03*
Y859899D03*
Y866307D03*
X378479Y856694D03*
Y863103D03*
X380328Y853490D03*
Y859899D03*
Y866307D03*
X382179Y856694D03*
Y863103D03*
X384028Y853490D03*
Y859899D03*
Y866307D03*
X385879Y856694D03*
Y863103D03*
X387728Y853490D03*
Y859899D03*
Y866307D03*
X372928Y853490D03*
Y859899D03*
Y866307D03*
X374779Y856694D03*
Y863103D03*
X376628Y872716D03*
X378479Y869511D03*
X380328Y872716D03*
X382179Y869511D03*
X384028Y872716D03*
X385879Y869511D03*
X387728Y872716D03*
X372928D03*
X374779Y869511D03*
X376628Y879124D03*
X378479Y875920D03*
Y882329D03*
X380328Y879124D03*
X382179Y875920D03*
Y882329D03*
X384028Y879124D03*
X385879Y875920D03*
Y882329D03*
X387728Y879124D03*
X372928D03*
X374779Y875920D03*
Y882329D03*
X376628Y885533D03*
Y891942D03*
Y898350D03*
X378479Y888737D03*
Y895146D03*
Y901555D03*
X380328Y885533D03*
Y891942D03*
Y898350D03*
X382179Y888737D03*
Y895146D03*
Y901555D03*
X384028Y885533D03*
Y891942D03*
Y898350D03*
X385879Y888737D03*
Y895146D03*
Y901555D03*
X387728Y885533D03*
Y891942D03*
Y898350D03*
X372928Y885533D03*
Y891942D03*
Y898350D03*
X374779Y888737D03*
Y895146D03*
Y901555D03*
X376628Y904759D03*
Y911167D03*
Y917576D03*
X378479Y907963D03*
Y914372D03*
X380328Y904759D03*
Y911167D03*
Y917576D03*
X382179Y907963D03*
Y914372D03*
X384028Y904759D03*
Y911167D03*
Y917576D03*
X385879Y907963D03*
Y914372D03*
X387728Y904759D03*
Y911167D03*
Y917576D03*
X372928Y904759D03*
Y911167D03*
Y917576D03*
X374779Y907963D03*
Y914372D03*
X376628Y923985D03*
Y930393D03*
X378479Y920780D03*
Y927189D03*
X380328Y923985D03*
Y930393D03*
X382179Y920780D03*
Y927189D03*
X384028Y923985D03*
Y930393D03*
X385879Y920780D03*
Y927189D03*
X387728Y923985D03*
Y930393D03*
X372928Y923985D03*
Y930393D03*
X374779Y920780D03*
Y927189D03*
X378479Y933598D03*
X382179D03*
X385879D03*
X374779D03*
X376628Y936801D03*
Y943210D03*
Y949619D03*
X378479Y940006D03*
Y946414D03*
X380328Y936801D03*
Y943210D03*
Y949619D03*
X382179Y940006D03*
Y946414D03*
X384028Y936801D03*
Y943210D03*
Y949619D03*
X385879Y940006D03*
Y946414D03*
X387728Y936801D03*
Y943210D03*
Y949619D03*
X372928Y936801D03*
Y943210D03*
Y949619D03*
X374779Y940006D03*
Y946414D03*
X376628Y956027D03*
Y962436D03*
X378479Y952823D03*
Y959232D03*
X380328Y956027D03*
Y962436D03*
X382179Y952823D03*
Y959232D03*
X384028Y956027D03*
Y962436D03*
X385879Y952823D03*
Y959232D03*
X387728Y956027D03*
Y962436D03*
X372928Y956027D03*
Y962436D03*
X374779Y952823D03*
Y959232D03*
X378479Y965640D03*
X382179D03*
X385879D03*
X374779D03*
X376628Y968845D03*
Y975253D03*
Y981662D03*
X378479Y972049D03*
Y978457D03*
X380328Y968845D03*
Y975253D03*
Y981662D03*
X382179Y972049D03*
Y978457D03*
X384028Y968845D03*
Y975253D03*
Y981662D03*
X385879Y972049D03*
Y978457D03*
X387728Y968845D03*
Y975253D03*
Y981662D03*
X372928Y968845D03*
Y975253D03*
Y981662D03*
X374779Y972049D03*
Y978457D03*
X378479Y984866D03*
X382179D03*
X385879D03*
X374779D03*
X377061Y997574D03*
X380761D03*
X384461D03*
X373361D03*
X377061Y1003983D03*
Y1010391D03*
X378912Y1000778D03*
Y1007187D03*
Y1013595D03*
X380761Y1003983D03*
Y1010391D03*
X382612Y1000778D03*
Y1007187D03*
Y1013595D03*
X384461Y1003983D03*
Y1010391D03*
X386312Y1000778D03*
Y1007187D03*
Y1013595D03*
X371512Y1000778D03*
Y1007187D03*
Y1013595D03*
X373361Y1003983D03*
Y1010391D03*
X375212Y1000778D03*
Y1007187D03*
Y1013595D03*
X377061Y1016800D03*
X378912Y1020004D03*
X380761Y1016800D03*
X382612Y1020004D03*
X384461Y1016800D03*
X386312Y1020004D03*
X371512D03*
X373361Y1016800D03*
X375212Y1020004D03*
X377061Y1023208D03*
Y1029617D03*
X378912Y1026413D03*
X380761Y1023208D03*
Y1029617D03*
X382612Y1026413D03*
X384461Y1023208D03*
Y1029617D03*
X386312Y1026413D03*
X371512D03*
X373361Y1023208D03*
Y1029617D03*
X375212Y1026413D03*
X377061Y1036026D03*
Y1042434D03*
X378912Y1032821D03*
Y1039230D03*
Y1045639D03*
X380761Y1036026D03*
Y1042434D03*
X382612Y1032821D03*
Y1039230D03*
Y1045639D03*
X384461Y1036026D03*
Y1042434D03*
X386312Y1032821D03*
Y1039230D03*
Y1045639D03*
X371512Y1032821D03*
Y1039230D03*
Y1045639D03*
X373361Y1036026D03*
Y1042434D03*
X375212Y1032821D03*
Y1039230D03*
Y1045639D03*
X377061Y1048842D03*
X378912Y1052047D03*
X380761Y1048842D03*
X382612Y1052047D03*
X384461Y1048842D03*
X386312Y1052047D03*
X371512D03*
X373361Y1048842D03*
X375212Y1052047D03*
X377061Y1055251D03*
Y1061660D03*
X378912Y1058455D03*
X380761Y1055251D03*
Y1061660D03*
X382612Y1058455D03*
X384461Y1055251D03*
Y1061660D03*
X386312Y1058455D03*
X371512D03*
X373361Y1055251D03*
Y1061660D03*
X375212Y1058455D03*
X377061Y1068068D03*
Y1074477D03*
X378912Y1064864D03*
Y1071273D03*
Y1077681D03*
X380761Y1068068D03*
Y1074477D03*
X382612Y1064864D03*
Y1071273D03*
Y1077681D03*
X384461Y1068068D03*
Y1074477D03*
X386312Y1064864D03*
Y1071273D03*
Y1077681D03*
X371512Y1064864D03*
Y1071273D03*
Y1077681D03*
X373361Y1068068D03*
Y1074477D03*
X375212Y1064864D03*
Y1071273D03*
Y1077681D03*
X377061Y1080885D03*
X380761D03*
X384461D03*
X373361D03*
X377061Y1087294D03*
Y1093703D03*
X378912Y1084090D03*
Y1090498D03*
X380761Y1087294D03*
Y1093703D03*
X382612Y1084090D03*
Y1090498D03*
X384461Y1087294D03*
Y1093703D03*
X386312Y1084090D03*
Y1090498D03*
X371512Y1084090D03*
Y1090498D03*
X373361Y1087294D03*
Y1093703D03*
X375212Y1084090D03*
Y1090498D03*
X377061Y1100111D03*
Y1106520D03*
X378912Y1096907D03*
Y1103316D03*
Y1109724D03*
X380761Y1100111D03*
Y1106520D03*
X382612Y1096907D03*
Y1103316D03*
Y1109724D03*
X384461Y1100111D03*
Y1106520D03*
X386312Y1096907D03*
Y1103316D03*
Y1109724D03*
X371512Y1096907D03*
Y1103316D03*
Y1109724D03*
X373361Y1100111D03*
Y1106520D03*
X375212Y1096907D03*
Y1103316D03*
Y1109724D03*
X377061Y1112929D03*
X380761D03*
X384461D03*
X373361D03*
X377061Y1119337D03*
Y1125746D03*
X378912Y1116133D03*
Y1122541D03*
Y1128950D03*
X380761Y1119337D03*
Y1125746D03*
X382612Y1116133D03*
Y1122541D03*
Y1128950D03*
X384461Y1119337D03*
Y1125746D03*
X386312Y1116133D03*
Y1122541D03*
Y1128950D03*
X371512Y1116133D03*
Y1122541D03*
Y1128950D03*
X373361Y1119337D03*
Y1125746D03*
X375212Y1116133D03*
Y1122541D03*
Y1128950D03*
X377061Y1132154D03*
X378912Y1135359D03*
X380761Y1132154D03*
X382612Y1135359D03*
X384461Y1132154D03*
X386312Y1135359D03*
X371512D03*
X373361Y1132154D03*
X375212Y1135359D03*
X389579Y850286D03*
X391428Y847081D03*
X393279Y850286D03*
X395128Y847081D03*
X396979Y850286D03*
X398828Y847081D03*
X400679Y850286D03*
X402528Y847081D03*
X389579Y856694D03*
Y863103D03*
X391428Y853490D03*
Y859899D03*
Y866307D03*
X393279Y856694D03*
Y863103D03*
X395128Y853490D03*
Y859899D03*
Y866307D03*
X396979Y856694D03*
Y863103D03*
X398828Y853490D03*
Y859899D03*
Y866307D03*
X400679Y856694D03*
Y863103D03*
X402528Y853490D03*
Y859899D03*
Y866307D03*
X389579Y869511D03*
X391428Y872716D03*
X393279Y869511D03*
X395128Y872716D03*
X396979Y869511D03*
X398828Y872716D03*
X400679Y869511D03*
X402528Y872716D03*
X389579Y875920D03*
Y882329D03*
X391428Y879124D03*
X393279Y875920D03*
Y882329D03*
X395128Y879124D03*
X396979Y875920D03*
Y882329D03*
X398828Y879124D03*
X400679Y875920D03*
Y882329D03*
X402528Y879124D03*
X389579Y888737D03*
Y895146D03*
Y901555D03*
X391428Y885533D03*
Y891942D03*
Y898350D03*
X393279Y888737D03*
Y895146D03*
Y901555D03*
X395128Y885533D03*
Y891942D03*
Y898350D03*
X396979Y888737D03*
Y895146D03*
Y901555D03*
X398828Y885533D03*
Y891942D03*
Y898350D03*
X400679Y888737D03*
Y895146D03*
Y901555D03*
X402528Y885533D03*
Y891942D03*
Y898350D03*
X389579Y907963D03*
Y914372D03*
X391428Y904759D03*
Y911167D03*
Y917576D03*
X393279Y907963D03*
Y914372D03*
X395128Y904759D03*
Y911167D03*
Y917576D03*
X396979Y907963D03*
Y914372D03*
X398828Y904759D03*
Y911167D03*
Y917576D03*
X400679Y907963D03*
Y914372D03*
X402528Y904759D03*
Y911167D03*
Y917576D03*
X389579Y920780D03*
Y927189D03*
X391428Y923985D03*
Y930393D03*
X393279Y920780D03*
Y927189D03*
X395128Y923985D03*
Y930393D03*
X396979Y920780D03*
Y927189D03*
X398828Y923985D03*
Y930393D03*
X400679Y920780D03*
Y927189D03*
X402528Y923985D03*
Y930393D03*
X389579Y933598D03*
X393279D03*
X396979D03*
X400679D03*
X389579Y940006D03*
Y946414D03*
X391428Y936801D03*
Y943210D03*
Y949619D03*
X393279Y940006D03*
Y946414D03*
X395128Y936801D03*
Y943210D03*
Y949619D03*
X396979Y940006D03*
Y946414D03*
X398828Y936801D03*
Y943210D03*
Y949619D03*
X400679Y940006D03*
Y946414D03*
X402528Y936801D03*
Y943210D03*
Y949619D03*
X389579Y952823D03*
Y959232D03*
X391428Y956027D03*
Y962436D03*
X393279Y952823D03*
Y959232D03*
X395128Y956027D03*
Y962436D03*
X396979Y952823D03*
Y959232D03*
X398828Y956027D03*
Y962436D03*
X400679Y952823D03*
Y959232D03*
X402528Y956027D03*
Y962436D03*
X389579Y965640D03*
X393279D03*
X396979D03*
X400679D03*
X389579Y972049D03*
Y978457D03*
X391428Y968845D03*
Y975253D03*
Y981662D03*
X393279Y972049D03*
Y978457D03*
X395128Y968845D03*
Y975253D03*
Y981662D03*
X396979Y972049D03*
Y978457D03*
X398828Y968845D03*
Y975253D03*
Y981662D03*
X400679Y972049D03*
Y978457D03*
X402528Y968845D03*
Y975253D03*
Y981662D03*
X389579Y984866D03*
X393279D03*
X396979D03*
X400679D03*
X388161Y997574D03*
X391861D03*
X395561D03*
X399261D03*
X402961D03*
X388161Y1003983D03*
Y1010391D03*
X390012Y1000778D03*
Y1007187D03*
Y1013595D03*
X391861Y1003983D03*
Y1010391D03*
X393712Y1000778D03*
Y1007187D03*
Y1013595D03*
X395561Y1003983D03*
Y1010391D03*
X397412Y1000778D03*
Y1007187D03*
Y1013595D03*
X399261Y1003983D03*
Y1010391D03*
X401112Y1000778D03*
Y1007187D03*
Y1013595D03*
X402961Y1003983D03*
Y1010391D03*
X388161Y1016800D03*
X390012Y1020004D03*
X391861Y1016800D03*
X393712Y1020004D03*
X395561Y1016800D03*
X397412Y1020004D03*
X399261Y1016800D03*
X401112Y1020004D03*
X402961Y1016800D03*
X388161Y1023208D03*
Y1029617D03*
X390012Y1026413D03*
X391861Y1023208D03*
Y1029617D03*
X393712Y1026413D03*
X395561Y1023208D03*
Y1029617D03*
X397412Y1026413D03*
X399261Y1023208D03*
Y1029617D03*
X401112Y1026413D03*
X402961Y1023208D03*
Y1029617D03*
X388161Y1036026D03*
Y1042434D03*
X390012Y1032821D03*
Y1039230D03*
Y1045639D03*
X391861Y1036026D03*
Y1042434D03*
X393712Y1032821D03*
Y1039230D03*
Y1045639D03*
X395561Y1036026D03*
Y1042434D03*
X397412Y1032821D03*
Y1039230D03*
Y1045639D03*
X399261Y1036026D03*
Y1042434D03*
X401112Y1032821D03*
Y1039230D03*
Y1045639D03*
X402961Y1036026D03*
Y1042434D03*
X388161Y1048842D03*
X390012Y1052047D03*
X391861Y1048842D03*
X393712Y1052047D03*
X395561Y1048842D03*
X397412Y1052047D03*
X399261Y1048842D03*
X401112Y1052047D03*
X402961Y1048842D03*
X388161Y1055251D03*
Y1061660D03*
X390012Y1058455D03*
X391861Y1055251D03*
Y1061660D03*
X393712Y1058455D03*
X395561Y1055251D03*
Y1061660D03*
X397412Y1058455D03*
X399261Y1055251D03*
Y1061660D03*
X401112Y1058455D03*
X402961Y1055251D03*
Y1061660D03*
X388161Y1068068D03*
Y1074477D03*
X390012Y1064864D03*
Y1071273D03*
Y1077681D03*
X391861Y1068068D03*
Y1074477D03*
X393712Y1064864D03*
Y1071273D03*
Y1077681D03*
X395561Y1068068D03*
Y1074477D03*
X397412Y1064864D03*
Y1071273D03*
Y1077681D03*
X399261Y1068068D03*
Y1074477D03*
X401112Y1064864D03*
Y1071273D03*
Y1077681D03*
X402961Y1068068D03*
Y1074477D03*
X388161Y1080885D03*
X391861D03*
X395561D03*
X399261D03*
X402961D03*
X388161Y1087294D03*
Y1093703D03*
X390012Y1084090D03*
Y1090498D03*
X391861Y1087294D03*
Y1093703D03*
X393712Y1084090D03*
Y1090498D03*
X395561Y1087294D03*
Y1093703D03*
X397412Y1084090D03*
Y1090498D03*
X399261Y1087294D03*
Y1093703D03*
X401112Y1084090D03*
Y1090498D03*
X402961Y1087294D03*
Y1093703D03*
X388161Y1100111D03*
Y1106520D03*
X390012Y1096907D03*
Y1103316D03*
Y1109724D03*
X391861Y1100111D03*
Y1106520D03*
X393712Y1096907D03*
Y1103316D03*
Y1109724D03*
X395561Y1100111D03*
Y1106520D03*
X397412Y1096907D03*
Y1103316D03*
Y1109724D03*
X399261Y1100111D03*
Y1106520D03*
X401112Y1096907D03*
Y1103316D03*
Y1109724D03*
X402961Y1100111D03*
Y1106520D03*
X388161Y1112929D03*
X391861D03*
X395561D03*
X399261D03*
X402961D03*
X388161Y1119337D03*
Y1125746D03*
X390012Y1116133D03*
Y1122541D03*
Y1128950D03*
X391861Y1119337D03*
Y1125746D03*
X393712Y1116133D03*
Y1122541D03*
Y1128950D03*
X395561Y1119337D03*
Y1125746D03*
X397412Y1116133D03*
Y1122541D03*
Y1128950D03*
X399261Y1119337D03*
Y1125746D03*
X401112Y1116133D03*
Y1122541D03*
Y1128950D03*
X402961Y1119337D03*
Y1125746D03*
X388161Y1132154D03*
X390012Y1135359D03*
X391861Y1132154D03*
X393712Y1135359D03*
X395561Y1132154D03*
X397412Y1135359D03*
X399261Y1132154D03*
X401112Y1135359D03*
X402961Y1132154D03*
X406228Y847081D03*
X408079Y850286D03*
X409928Y847081D03*
X411779Y850286D03*
X413628Y847081D03*
X415479Y850286D03*
X417328Y847081D03*
X419179Y850286D03*
X404379D03*
X406228Y853490D03*
Y859899D03*
Y866307D03*
X408079Y856694D03*
Y863103D03*
X409928Y853490D03*
Y859899D03*
Y866307D03*
X411779Y856694D03*
Y863103D03*
X413628Y853490D03*
Y859899D03*
Y866307D03*
X415479Y856694D03*
Y863103D03*
X417328Y853490D03*
Y859899D03*
Y866307D03*
X419179Y856694D03*
Y863103D03*
X404379Y856694D03*
Y863103D03*
X406228Y872716D03*
X408079Y869511D03*
X409928Y872716D03*
X411779Y869511D03*
X413628Y872716D03*
X415479Y869511D03*
X417328Y872716D03*
X419179Y869511D03*
X404379D03*
X406228Y879124D03*
X408079Y875920D03*
Y882329D03*
X409928Y879124D03*
X411779Y875920D03*
Y882329D03*
X413628Y879124D03*
X415479Y875920D03*
Y882329D03*
X417328Y879124D03*
X419179Y875920D03*
Y882329D03*
X404379Y875920D03*
Y882329D03*
X406228Y885533D03*
Y891942D03*
Y898350D03*
X408079Y888737D03*
Y895146D03*
Y901555D03*
X409928Y885533D03*
Y891942D03*
Y898350D03*
X411779Y888737D03*
Y895146D03*
Y901555D03*
X413628Y885533D03*
Y891942D03*
Y898350D03*
X415479Y888737D03*
Y895146D03*
Y901555D03*
X417328Y885533D03*
Y891942D03*
Y898350D03*
X419179Y888737D03*
Y895146D03*
Y901555D03*
X404379Y888737D03*
Y895146D03*
Y901555D03*
X406228Y904759D03*
Y911167D03*
Y917576D03*
X408079Y907963D03*
Y914372D03*
X409928Y904759D03*
Y911167D03*
Y917576D03*
X411779Y907963D03*
Y914372D03*
X413628Y904759D03*
Y911167D03*
Y917576D03*
X415479Y907963D03*
Y914372D03*
X417328Y904759D03*
Y911167D03*
Y917576D03*
X419179Y907963D03*
Y914372D03*
X404379Y907963D03*
Y914372D03*
X406228Y923985D03*
X408079Y920780D03*
X409928Y923985D03*
X411779Y920780D03*
X413628Y923985D03*
X415479Y920780D03*
X417328Y923985D03*
X419179Y920780D03*
X404379D03*
X406661Y1042434D03*
X408512Y1039230D03*
Y1045639D03*
X410361Y1042434D03*
X412212Y1039230D03*
Y1045639D03*
X414061Y1042434D03*
X415912Y1039230D03*
Y1045639D03*
X417761Y1042434D03*
X419612Y1039230D03*
Y1045639D03*
X404812Y1039230D03*
Y1045639D03*
X406661Y1048842D03*
X408512Y1052047D03*
X410361Y1048842D03*
X412212Y1052047D03*
X414061Y1048842D03*
X415912Y1052047D03*
X417761Y1048842D03*
X419612Y1052047D03*
X404812D03*
X406661Y1055251D03*
Y1061660D03*
X408512Y1058455D03*
X410361Y1055251D03*
Y1061660D03*
X412212Y1058455D03*
X414061Y1055251D03*
Y1061660D03*
X415912Y1058455D03*
X417761Y1055251D03*
Y1061660D03*
X419612Y1058455D03*
X404812D03*
X406661Y1068068D03*
Y1074477D03*
X408512Y1064864D03*
Y1071273D03*
Y1077681D03*
X410361Y1068068D03*
Y1074477D03*
X412212Y1064864D03*
Y1071273D03*
Y1077681D03*
X414061Y1068068D03*
Y1074477D03*
X415912Y1064864D03*
Y1071273D03*
Y1077681D03*
X417761Y1068068D03*
Y1074477D03*
X419612Y1064864D03*
Y1071273D03*
Y1077681D03*
X404812Y1064864D03*
Y1071273D03*
Y1077681D03*
X406661Y1080885D03*
X410361D03*
X414061D03*
X417761D03*
X406661Y1087294D03*
Y1093703D03*
X408512Y1084090D03*
Y1090498D03*
X410361Y1087294D03*
Y1093703D03*
X412212Y1084090D03*
Y1090498D03*
X414061Y1087294D03*
Y1093703D03*
X415912Y1084090D03*
Y1090498D03*
X417761Y1087294D03*
Y1093703D03*
X419612Y1084090D03*
Y1090498D03*
X404812Y1084090D03*
Y1090498D03*
X406661Y1100111D03*
Y1106520D03*
X408512Y1096907D03*
Y1103316D03*
Y1109724D03*
X410361Y1100111D03*
Y1106520D03*
X412212Y1096907D03*
Y1103316D03*
Y1109724D03*
X414061Y1100111D03*
Y1106520D03*
X415912Y1096907D03*
Y1103316D03*
Y1109724D03*
X417761Y1100111D03*
Y1106520D03*
X419612Y1096907D03*
Y1103316D03*
Y1109724D03*
X404812Y1096907D03*
Y1103316D03*
Y1109724D03*
X406661Y1112929D03*
X410361D03*
X414061D03*
X417761D03*
X406661Y1119337D03*
Y1125746D03*
X408512Y1116133D03*
Y1122541D03*
Y1128950D03*
X410361Y1119337D03*
Y1125746D03*
X412212Y1116133D03*
Y1122541D03*
Y1128950D03*
X414061Y1119337D03*
Y1125746D03*
X415912Y1116133D03*
Y1122541D03*
Y1128950D03*
X417761Y1119337D03*
Y1125746D03*
X419612Y1116133D03*
Y1122541D03*
Y1128950D03*
X404812Y1116133D03*
Y1122541D03*
Y1128950D03*
X406661Y1132154D03*
X408512Y1135359D03*
X410361Y1132154D03*
X412212Y1135359D03*
X414061Y1132154D03*
X415912Y1135359D03*
X417761Y1132154D03*
X419612Y1135359D03*
X404812D03*
X421028Y847081D03*
X422879Y850286D03*
X424728Y847081D03*
X426579Y850286D03*
X430279D03*
X433979D03*
X421028Y853490D03*
Y859899D03*
Y866307D03*
X422879Y856694D03*
Y863103D03*
X424728Y853490D03*
Y859899D03*
Y866307D03*
X426579Y856694D03*
Y863103D03*
X428428Y853490D03*
Y859899D03*
Y866307D03*
X430279Y856694D03*
Y863103D03*
X432128Y853490D03*
Y859899D03*
Y866307D03*
X433979Y856694D03*
Y863103D03*
X435829Y853490D03*
Y859899D03*
Y866307D03*
X421028Y872716D03*
X422879Y869511D03*
X424728Y872716D03*
X426579Y869511D03*
X428428Y872716D03*
X430279Y869511D03*
X432128Y872716D03*
X433979Y869511D03*
X435829Y872716D03*
X421028Y879124D03*
X422879Y875920D03*
Y882329D03*
X424728Y879124D03*
X426579Y875920D03*
Y882329D03*
X428428Y879124D03*
X430279Y875920D03*
Y882329D03*
X432128Y879124D03*
X433979Y875920D03*
Y882329D03*
X435829Y879124D03*
X421028Y885533D03*
Y891942D03*
Y898350D03*
X422879Y888737D03*
Y895146D03*
Y901555D03*
X424728Y885533D03*
Y891942D03*
Y898350D03*
X426579Y888737D03*
Y895146D03*
Y901555D03*
X428428Y885533D03*
Y891942D03*
Y898350D03*
X430279Y888737D03*
Y895146D03*
Y901555D03*
X432128Y885533D03*
Y891942D03*
Y898350D03*
X433979Y888737D03*
Y895146D03*
Y901555D03*
X435829Y885533D03*
Y891942D03*
Y898350D03*
Y904759D03*
X421028D03*
Y911167D03*
Y917576D03*
X422879Y907963D03*
Y914372D03*
X424728Y904759D03*
Y911167D03*
Y917576D03*
X426579Y907963D03*
Y914372D03*
X428428Y904759D03*
Y911167D03*
Y917576D03*
X430279Y907963D03*
Y914372D03*
X432128Y904759D03*
Y911167D03*
Y917576D03*
X433979Y907963D03*
Y914372D03*
X435829Y911167D03*
Y917576D03*
X421028Y923985D03*
X422879Y920780D03*
X424728Y923985D03*
X426579Y920780D03*
X428428Y923985D03*
X430279Y920780D03*
Y927189D03*
X432128Y923985D03*
Y930393D03*
X433979Y920780D03*
Y927189D03*
X435829Y923985D03*
Y930393D03*
X430279Y933598D03*
X433979D03*
X430279Y940006D03*
Y946414D03*
X432128Y936801D03*
Y943210D03*
Y949619D03*
X433979Y940006D03*
Y946414D03*
X435829Y936801D03*
Y943210D03*
Y949619D03*
X430279Y952823D03*
Y959232D03*
X432128Y956027D03*
Y962436D03*
X433979Y952823D03*
Y959232D03*
X435829Y956027D03*
Y962436D03*
X430279Y965640D03*
X433979D03*
X430279Y972049D03*
Y978457D03*
X432128Y968845D03*
Y975253D03*
Y981662D03*
X433979Y972049D03*
Y978457D03*
X435829Y968845D03*
Y975253D03*
Y981662D03*
X430279Y984866D03*
X433979D03*
X436261Y997574D03*
X432561D03*
X436261Y1003983D03*
Y1010391D03*
X430711Y1000778D03*
Y1007187D03*
Y1013595D03*
X432561Y1003983D03*
Y1010391D03*
X434412Y1000778D03*
Y1007187D03*
Y1013595D03*
X436261Y1016800D03*
X430711Y1020004D03*
X432561Y1016800D03*
X434412Y1020004D03*
X436261Y1023208D03*
Y1029617D03*
X430711Y1026413D03*
X432561Y1023208D03*
Y1029617D03*
X434412Y1026413D03*
X436261Y1036026D03*
Y1042434D03*
X421461D03*
X423312Y1039230D03*
Y1045639D03*
X425161Y1042434D03*
X427012Y1039230D03*
Y1045639D03*
X428861Y1042434D03*
X430711Y1032821D03*
Y1039230D03*
Y1045639D03*
X432561Y1036026D03*
Y1042434D03*
X434412Y1032821D03*
Y1039230D03*
Y1045639D03*
X436261Y1048842D03*
X421461D03*
X423312Y1052047D03*
X425161Y1048842D03*
X427012Y1052047D03*
X428861Y1048842D03*
X430711Y1052047D03*
X432561Y1048842D03*
X434412Y1052047D03*
X436261Y1055251D03*
Y1061660D03*
X421461Y1055251D03*
Y1061660D03*
X423312Y1058455D03*
X425161Y1055251D03*
Y1061660D03*
X427012Y1058455D03*
X428861Y1055251D03*
Y1061660D03*
X430711Y1058455D03*
X432561Y1055251D03*
Y1061660D03*
X434412Y1058455D03*
X436261Y1068068D03*
Y1074477D03*
X421461Y1068068D03*
Y1074477D03*
X423312Y1064864D03*
Y1071273D03*
Y1077681D03*
X425161Y1068068D03*
Y1074477D03*
X427012Y1064864D03*
Y1071273D03*
Y1077681D03*
X428861Y1068068D03*
Y1074477D03*
X430711Y1064864D03*
Y1071273D03*
Y1077681D03*
X432561Y1068068D03*
Y1074477D03*
X434412Y1064864D03*
Y1071273D03*
Y1077681D03*
X436261Y1080885D03*
X421461D03*
X425161D03*
X428861D03*
X432561D03*
X436261Y1087294D03*
Y1093703D03*
X421461Y1087294D03*
Y1093703D03*
X423312Y1084090D03*
Y1090498D03*
X425161Y1087294D03*
Y1093703D03*
X427012Y1084090D03*
Y1090498D03*
X428861Y1087294D03*
Y1093703D03*
X430711Y1084090D03*
Y1090498D03*
X432561Y1087294D03*
Y1093703D03*
X434412Y1084090D03*
Y1090498D03*
X436261Y1100111D03*
Y1106520D03*
X421461Y1100111D03*
Y1106520D03*
X423312Y1096907D03*
Y1103316D03*
Y1109724D03*
X425161Y1100111D03*
Y1106520D03*
X427012Y1096907D03*
Y1103316D03*
Y1109724D03*
X428861Y1100111D03*
Y1106520D03*
X430711Y1096907D03*
Y1103316D03*
Y1109724D03*
X432561Y1100111D03*
Y1106520D03*
X434412Y1096907D03*
Y1103316D03*
Y1109724D03*
X436261Y1112929D03*
X421461D03*
X425161D03*
X428861D03*
X432561D03*
X436261Y1119337D03*
Y1125746D03*
X421461Y1119337D03*
Y1125746D03*
X423312Y1116133D03*
Y1122541D03*
Y1128950D03*
X425161Y1119337D03*
Y1125746D03*
X427012Y1116133D03*
Y1122541D03*
Y1128950D03*
X428861Y1119337D03*
Y1125746D03*
X430711Y1116133D03*
Y1122541D03*
Y1128950D03*
X432561Y1119337D03*
Y1125746D03*
X434412Y1116133D03*
Y1122541D03*
Y1128950D03*
X436261Y1132154D03*
X421461D03*
X423312Y1135359D03*
X425161Y1132154D03*
X427012Y1135359D03*
X428861Y1132154D03*
X432561D03*
X437679Y850286D03*
X441379D03*
X445079D03*
X448779D03*
X452479D03*
X437679Y856694D03*
Y863103D03*
X439528Y853490D03*
Y859899D03*
Y866307D03*
X441379Y856694D03*
Y863103D03*
X443228Y853490D03*
Y859899D03*
Y866307D03*
X445079Y856694D03*
Y863103D03*
X446928Y853490D03*
Y859899D03*
Y866307D03*
X448779Y856694D03*
Y863103D03*
X450629Y853490D03*
Y859899D03*
Y866307D03*
X452479Y856694D03*
Y863103D03*
X437679Y869511D03*
X439528Y872716D03*
X441379Y869511D03*
X443228Y872716D03*
X445079Y869511D03*
X446928Y872716D03*
X448779Y869511D03*
X450629Y872716D03*
X452479Y869511D03*
X437679Y875920D03*
Y882329D03*
X439528Y879124D03*
X441379Y875920D03*
Y882329D03*
X443228Y879124D03*
X445079Y875920D03*
Y882329D03*
X446928Y879124D03*
X448779Y875920D03*
Y882329D03*
X450629Y879124D03*
X452479Y875920D03*
Y882329D03*
X437679Y888737D03*
Y895146D03*
Y901555D03*
X439528Y885533D03*
Y891942D03*
Y898350D03*
X441379Y888737D03*
Y895146D03*
Y901555D03*
X443228Y885533D03*
Y891942D03*
Y898350D03*
X445079Y888737D03*
Y895146D03*
Y901555D03*
X446928Y885533D03*
Y891942D03*
Y898350D03*
X448779Y888737D03*
Y895146D03*
Y901555D03*
X450629Y885533D03*
Y891942D03*
Y898350D03*
X452479Y888737D03*
Y895146D03*
Y901555D03*
X437679Y907963D03*
Y914372D03*
X439528Y904759D03*
Y911167D03*
Y917576D03*
X441379Y907963D03*
Y914372D03*
X443228Y904759D03*
Y911167D03*
Y917576D03*
X445079Y907963D03*
Y914372D03*
X446928Y904759D03*
Y911167D03*
Y917576D03*
X448779Y907963D03*
Y914372D03*
X450629Y904759D03*
Y911167D03*
Y917576D03*
X452479Y907963D03*
Y914372D03*
X437679Y920780D03*
Y927189D03*
X439528Y923985D03*
Y930393D03*
X441379Y920780D03*
Y927189D03*
X443228Y923985D03*
Y930393D03*
X445079Y920780D03*
Y927189D03*
X446928Y923985D03*
Y930393D03*
X448779Y920780D03*
Y927189D03*
X450629Y923985D03*
Y930393D03*
X452479Y920780D03*
X437679Y933598D03*
X441379D03*
X445079D03*
X448779D03*
X437679Y940006D03*
Y946414D03*
X439528Y936801D03*
Y943210D03*
Y949619D03*
X441379Y940006D03*
Y946414D03*
X443228Y936801D03*
Y943210D03*
Y949619D03*
X445079Y940006D03*
Y946414D03*
X446928Y936801D03*
Y943210D03*
Y949619D03*
X448779Y940006D03*
Y946414D03*
X450629Y936801D03*
Y943210D03*
Y949619D03*
X437679Y952823D03*
Y959232D03*
X439528Y956027D03*
Y962436D03*
X441379Y952823D03*
Y959232D03*
X443228Y956027D03*
Y962436D03*
X445079Y952823D03*
Y959232D03*
X446928Y956027D03*
Y962436D03*
X448779Y952823D03*
Y959232D03*
X450629Y956027D03*
Y962436D03*
X437679Y965640D03*
X441379D03*
X445079D03*
X448779D03*
X437679Y972049D03*
Y978457D03*
X439528Y968845D03*
Y975253D03*
Y981662D03*
X441379Y972049D03*
Y978457D03*
X443228Y968845D03*
Y975253D03*
Y981662D03*
X445079Y972049D03*
Y978457D03*
X446928Y968845D03*
Y975253D03*
Y981662D03*
X448779Y972049D03*
Y978457D03*
X450629Y968845D03*
Y975253D03*
Y981662D03*
X437679Y984866D03*
X441379D03*
X445079D03*
X448779D03*
X439961Y997574D03*
X443661D03*
X447361D03*
X451061D03*
X438112Y1000778D03*
Y1007187D03*
Y1013595D03*
X439961Y1003983D03*
Y1010391D03*
X441812Y1000778D03*
Y1007187D03*
Y1013595D03*
X443661Y1003983D03*
Y1010391D03*
X445511Y1000778D03*
Y1007187D03*
Y1013595D03*
X447361Y1003983D03*
Y1010391D03*
X449212Y1000778D03*
Y1007187D03*
Y1013595D03*
X451061Y1003983D03*
Y1010391D03*
X438112Y1020004D03*
X439961Y1016800D03*
X441812Y1020004D03*
X443661Y1016800D03*
X445511Y1020004D03*
X447361Y1016800D03*
X449212Y1020004D03*
X451061Y1016800D03*
X438112Y1026413D03*
X439961Y1023208D03*
Y1029617D03*
X441812Y1026413D03*
X443661Y1023208D03*
Y1029617D03*
X445511Y1026413D03*
X447361Y1023208D03*
Y1029617D03*
X449212Y1026413D03*
X451061Y1023208D03*
Y1029617D03*
X438112Y1032821D03*
Y1039230D03*
Y1045639D03*
X439961Y1036026D03*
Y1042434D03*
X441812Y1032821D03*
Y1039230D03*
Y1045639D03*
X443661Y1036026D03*
Y1042434D03*
X445511Y1032821D03*
Y1039230D03*
Y1045639D03*
X447361Y1036026D03*
Y1042434D03*
X449212Y1032821D03*
Y1039230D03*
Y1045639D03*
X451061Y1036026D03*
Y1042434D03*
X438112Y1052047D03*
X439961Y1048842D03*
X441812Y1052047D03*
X443661Y1048842D03*
X445511Y1052047D03*
X447361Y1048842D03*
X449212Y1052047D03*
X451061Y1048842D03*
X438112Y1058455D03*
X439961Y1055251D03*
Y1061660D03*
X441812Y1058455D03*
X443661Y1055251D03*
Y1061660D03*
X445511Y1058455D03*
X447361Y1055251D03*
Y1061660D03*
X449212Y1058455D03*
X451061Y1055251D03*
Y1061660D03*
X438112Y1064864D03*
Y1071273D03*
Y1077681D03*
X439961Y1068068D03*
Y1074477D03*
X441812Y1064864D03*
Y1071273D03*
Y1077681D03*
X443661Y1068068D03*
Y1074477D03*
X445511Y1064864D03*
Y1071273D03*
Y1077681D03*
X447361Y1068068D03*
Y1074477D03*
X449212Y1064864D03*
Y1071273D03*
Y1077681D03*
X451061Y1068068D03*
Y1074477D03*
X439961Y1080885D03*
X443661D03*
X447361D03*
X451061D03*
X438112Y1084090D03*
Y1090498D03*
X439961Y1087294D03*
Y1093703D03*
X441812Y1084090D03*
Y1090498D03*
X443661Y1087294D03*
Y1093703D03*
X445511Y1084090D03*
Y1090498D03*
X447361Y1087294D03*
Y1093703D03*
X449212Y1084090D03*
Y1090498D03*
X451061Y1087294D03*
Y1093703D03*
X438112Y1096907D03*
Y1103316D03*
Y1109724D03*
X439961Y1100111D03*
Y1106520D03*
X441812Y1096907D03*
Y1103316D03*
Y1109724D03*
X443661Y1100111D03*
Y1106520D03*
X445511Y1096907D03*
Y1103316D03*
Y1109724D03*
X447361Y1100111D03*
Y1106520D03*
X449212Y1096907D03*
Y1103316D03*
Y1109724D03*
X451061Y1100111D03*
Y1106520D03*
X439961Y1112929D03*
X443661D03*
X447361D03*
X451061D03*
X438112Y1116133D03*
Y1122541D03*
Y1128950D03*
X439961Y1119337D03*
Y1125746D03*
X441812Y1116133D03*
Y1122541D03*
Y1128950D03*
X443661Y1119337D03*
Y1125746D03*
X445511Y1116133D03*
Y1122541D03*
Y1128950D03*
X447361Y1119337D03*
Y1125746D03*
X449212Y1116133D03*
Y1122541D03*
Y1128950D03*
X451061Y1119337D03*
Y1125746D03*
X439961Y1132154D03*
X443661D03*
X447361D03*
X451061D03*
X467279Y850286D03*
X454328Y847081D03*
X456179Y850286D03*
X458028Y847081D03*
X459879Y850286D03*
X461728Y847081D03*
X463579Y850286D03*
X465428Y847081D03*
X467279Y856694D03*
Y863103D03*
X454328Y853490D03*
Y859899D03*
Y866307D03*
X456179Y856694D03*
Y863103D03*
X458028Y853490D03*
Y859899D03*
Y866307D03*
X459879Y856694D03*
Y863103D03*
X461728Y853490D03*
Y859899D03*
Y866307D03*
X463579Y856694D03*
Y863103D03*
X465428Y853490D03*
Y859899D03*
Y866307D03*
X467279Y869511D03*
X454328Y872716D03*
X456179Y869511D03*
X458028Y872716D03*
X459879Y869511D03*
X461728Y872716D03*
X463579Y869511D03*
X465428Y872716D03*
X467279Y875920D03*
Y882329D03*
X454328Y879124D03*
X456179Y875920D03*
Y882329D03*
X458028Y879124D03*
X459879Y875920D03*
Y882329D03*
X461728Y879124D03*
X463579Y875920D03*
Y882329D03*
X465428Y879124D03*
X467279Y888737D03*
Y895146D03*
Y901555D03*
X454328Y885533D03*
Y891942D03*
Y898350D03*
X456179Y888737D03*
Y895146D03*
Y901555D03*
X458028Y885533D03*
Y891942D03*
Y898350D03*
X459879Y888737D03*
Y895146D03*
Y901555D03*
X461728Y885533D03*
Y891942D03*
Y898350D03*
X463579Y888737D03*
Y895146D03*
Y901555D03*
X465428Y885533D03*
Y891942D03*
Y898350D03*
X467279Y907963D03*
Y914372D03*
X454328Y904759D03*
Y911167D03*
Y917576D03*
X456179Y907963D03*
Y914372D03*
X458028Y904759D03*
Y911167D03*
Y917576D03*
X459879Y907963D03*
Y914372D03*
X461728Y904759D03*
Y911167D03*
Y917576D03*
X463579Y907963D03*
Y914372D03*
X465428Y904759D03*
Y911167D03*
Y917576D03*
X467279Y920780D03*
X454328Y923985D03*
X456179Y920780D03*
X458028Y923985D03*
X459879Y920780D03*
X461728Y923985D03*
X463579Y920780D03*
X465428Y923985D03*
X467712Y1039230D03*
Y1045639D03*
X452912Y1039230D03*
Y1045639D03*
X454761Y1042434D03*
X456612Y1039230D03*
Y1045639D03*
X458461Y1042434D03*
X460312Y1039230D03*
Y1045639D03*
X462161Y1042434D03*
X464012Y1039230D03*
Y1045639D03*
X465861Y1042434D03*
X467712Y1052047D03*
X452912D03*
X454761Y1048842D03*
X456612Y1052047D03*
X458461Y1048842D03*
X460312Y1052047D03*
X462161Y1048842D03*
X464012Y1052047D03*
X465861Y1048842D03*
Y1055251D03*
X467712Y1058455D03*
X452912D03*
X454761Y1055251D03*
Y1061660D03*
X456612Y1058455D03*
X458461Y1055251D03*
Y1061660D03*
X460312Y1058455D03*
X462161Y1055251D03*
Y1061660D03*
X464012Y1058455D03*
X465861Y1061660D03*
X467712Y1064864D03*
Y1071273D03*
Y1077681D03*
X452912Y1064864D03*
Y1071273D03*
Y1077681D03*
X454761Y1068068D03*
Y1074477D03*
X456612Y1064864D03*
Y1071273D03*
Y1077681D03*
X458461Y1068068D03*
Y1074477D03*
X460312Y1064864D03*
Y1071273D03*
Y1077681D03*
X462161Y1068068D03*
Y1074477D03*
X464012Y1064864D03*
Y1071273D03*
Y1077681D03*
X465861Y1068068D03*
Y1074477D03*
X454761Y1080885D03*
X458461D03*
X462161D03*
X465861D03*
X467712Y1084090D03*
Y1090498D03*
X452912Y1084090D03*
Y1090498D03*
X454761Y1087294D03*
Y1093703D03*
X456612Y1084090D03*
Y1090498D03*
X458461Y1087294D03*
Y1093703D03*
X460312Y1084090D03*
Y1090498D03*
X462161Y1087294D03*
Y1093703D03*
X464012Y1084090D03*
Y1090498D03*
X465861Y1087294D03*
Y1093703D03*
X467712Y1096907D03*
Y1103316D03*
Y1109724D03*
X452912Y1096907D03*
Y1103316D03*
Y1109724D03*
X454761Y1100111D03*
Y1106520D03*
X456612Y1096907D03*
Y1103316D03*
Y1109724D03*
X458461Y1100111D03*
Y1106520D03*
X460312Y1096907D03*
Y1103316D03*
Y1109724D03*
X462161Y1100111D03*
Y1106520D03*
X464012Y1096907D03*
Y1103316D03*
Y1109724D03*
X465861Y1100111D03*
Y1106520D03*
Y1112929D03*
X454761D03*
X458461D03*
X462161D03*
X467712Y1116133D03*
Y1122541D03*
Y1128950D03*
X452912Y1116133D03*
Y1122541D03*
Y1128950D03*
X454761Y1119337D03*
Y1125746D03*
X456612Y1116133D03*
Y1122541D03*
Y1128950D03*
X458461Y1119337D03*
Y1125746D03*
X460312Y1116133D03*
Y1122541D03*
Y1128950D03*
X462161Y1119337D03*
Y1125746D03*
X464012Y1116133D03*
Y1122541D03*
Y1128950D03*
X465861Y1119337D03*
Y1125746D03*
X467712Y1135359D03*
X454761Y1132154D03*
X456612Y1135359D03*
X458461Y1132154D03*
X460312Y1135359D03*
X462161Y1132154D03*
X464012Y1135359D03*
X465861Y1132154D03*
X469128Y847081D03*
X470979Y850286D03*
X472828Y847081D03*
X474679Y850286D03*
X476528Y847081D03*
X478379Y850286D03*
X480228Y847081D03*
X482079Y850286D03*
X483928Y847081D03*
X469128Y853490D03*
Y859899D03*
Y866307D03*
X470979Y856694D03*
Y863103D03*
X472828Y853490D03*
Y859899D03*
Y866307D03*
X474679Y856694D03*
Y863103D03*
X476528Y853490D03*
Y859899D03*
Y866307D03*
X478379Y856694D03*
Y863103D03*
X480228Y853490D03*
Y859899D03*
Y866307D03*
X482079Y856694D03*
Y863103D03*
X483928Y853490D03*
Y859899D03*
Y866307D03*
X469128Y872716D03*
X470979Y869511D03*
X472828Y872716D03*
X474679Y869511D03*
X476528Y872716D03*
X478379Y869511D03*
X480228Y872716D03*
X482079Y869511D03*
X483928Y872716D03*
X469128Y879124D03*
X470979Y875920D03*
Y882329D03*
X472828Y879124D03*
X474679Y875920D03*
Y882329D03*
X476528Y879124D03*
X478379Y875920D03*
Y882329D03*
X480228Y879124D03*
X482079Y875920D03*
Y882329D03*
X483928Y879124D03*
X469128Y885533D03*
Y891942D03*
Y898350D03*
X470979Y888737D03*
Y895146D03*
Y901555D03*
X472828Y885533D03*
Y891942D03*
Y898350D03*
X474679Y888737D03*
Y895146D03*
Y901555D03*
X476528Y885533D03*
Y891942D03*
Y898350D03*
X478379Y888737D03*
Y895146D03*
Y901555D03*
X480228Y885533D03*
Y891942D03*
Y898350D03*
X482079Y888737D03*
Y895146D03*
Y901555D03*
X483928Y885533D03*
Y891942D03*
Y898350D03*
X469128Y904759D03*
Y911167D03*
Y917576D03*
X470979Y907963D03*
Y914372D03*
X472828Y904759D03*
Y911167D03*
Y917576D03*
X474679Y907963D03*
Y914372D03*
X476528Y904759D03*
Y911167D03*
Y917576D03*
X478379Y907963D03*
Y914372D03*
X480228Y904759D03*
Y911167D03*
Y917576D03*
X482079Y907963D03*
Y914372D03*
X483928Y904759D03*
Y911167D03*
Y917576D03*
X469128Y923985D03*
X470979Y920780D03*
X472828Y923985D03*
X474679Y920780D03*
X476528Y923985D03*
X478379Y920780D03*
Y927189D03*
X480228Y923985D03*
Y930393D03*
X482079Y920780D03*
Y927189D03*
X483928Y923985D03*
Y930393D03*
X478379Y933598D03*
X482079D03*
X478379Y940006D03*
Y946414D03*
X480228Y936801D03*
Y943210D03*
Y949619D03*
X482079Y940006D03*
Y946414D03*
X483928Y936801D03*
Y943210D03*
Y949619D03*
X478379Y952823D03*
Y959232D03*
X480228Y956027D03*
Y962436D03*
X482079Y952823D03*
Y959232D03*
X483928Y956027D03*
Y962436D03*
X478379Y965640D03*
X482079D03*
X478379Y972049D03*
Y978457D03*
X480228Y968845D03*
Y975253D03*
Y981662D03*
X482079Y972049D03*
Y978457D03*
X483928Y968845D03*
Y975253D03*
Y981662D03*
X478379Y984866D03*
X482079D03*
X480661Y997574D03*
X484361D03*
X478812Y1000778D03*
Y1007187D03*
Y1013595D03*
X480661Y1003983D03*
Y1010391D03*
X482512Y1000778D03*
Y1007187D03*
Y1013595D03*
X484361Y1003983D03*
Y1010391D03*
X478812Y1020004D03*
X480661Y1016800D03*
X482512Y1020004D03*
X484361Y1016800D03*
X478812Y1026413D03*
X480661Y1023208D03*
Y1029617D03*
X482512Y1026413D03*
X484361Y1023208D03*
Y1029617D03*
X469561Y1042434D03*
X471412Y1039230D03*
Y1045639D03*
X473261Y1042434D03*
X475112Y1039230D03*
Y1045639D03*
X476961Y1042434D03*
X478812Y1032821D03*
Y1039230D03*
Y1045639D03*
X480661Y1036026D03*
Y1042434D03*
X482512Y1032821D03*
Y1039230D03*
Y1045639D03*
X484361Y1036026D03*
Y1042434D03*
X469561Y1048842D03*
X471412Y1052047D03*
X473261Y1048842D03*
X475112Y1052047D03*
X476961Y1048842D03*
X478812Y1052047D03*
X480661Y1048842D03*
X482512Y1052047D03*
X484361Y1048842D03*
X469561Y1055251D03*
Y1061660D03*
X471412Y1058455D03*
X473261Y1055251D03*
Y1061660D03*
X475112Y1058455D03*
X476961Y1055251D03*
Y1061660D03*
X478812Y1058455D03*
X480661Y1055251D03*
Y1061660D03*
X482512Y1058455D03*
X484361Y1055251D03*
Y1061660D03*
X469561Y1068068D03*
Y1074477D03*
X471412Y1064864D03*
Y1071273D03*
Y1077681D03*
X473261Y1068068D03*
Y1074477D03*
X475112Y1064864D03*
Y1071273D03*
Y1077681D03*
X476961Y1068068D03*
Y1074477D03*
X478812Y1064864D03*
Y1071273D03*
Y1077681D03*
X480661Y1068068D03*
Y1074477D03*
X482512Y1064864D03*
Y1071273D03*
Y1077681D03*
X484361Y1068068D03*
Y1074477D03*
X469561Y1080885D03*
X473261D03*
X476961D03*
X480661D03*
X484361D03*
X469561Y1087294D03*
Y1093703D03*
X471412Y1084090D03*
Y1090498D03*
X473261Y1087294D03*
Y1093703D03*
X475112Y1084090D03*
Y1090498D03*
X476961Y1087294D03*
Y1093703D03*
X478812Y1084090D03*
Y1090498D03*
X480661Y1087294D03*
Y1093703D03*
X482512Y1084090D03*
Y1090498D03*
X484361Y1087294D03*
Y1093703D03*
X469561Y1100111D03*
Y1106520D03*
X471412Y1096907D03*
Y1103316D03*
Y1109724D03*
X473261Y1100111D03*
Y1106520D03*
X475112Y1096907D03*
Y1103316D03*
Y1109724D03*
X476961Y1100111D03*
Y1106520D03*
X478812Y1096907D03*
Y1103316D03*
Y1109724D03*
X480661Y1100111D03*
Y1106520D03*
X482512Y1096907D03*
Y1103316D03*
Y1109724D03*
X484361Y1100111D03*
Y1106520D03*
X469561Y1112929D03*
X473261D03*
X476961D03*
X480661D03*
X484361D03*
X469561Y1119337D03*
Y1125746D03*
X471412Y1116133D03*
Y1122541D03*
Y1128950D03*
X473261Y1119337D03*
Y1125746D03*
X475112Y1116133D03*
Y1122541D03*
Y1128950D03*
X476961Y1119337D03*
Y1125746D03*
X478812Y1116133D03*
Y1122541D03*
Y1128950D03*
X480661Y1119337D03*
Y1125746D03*
X482512Y1116133D03*
Y1122541D03*
Y1128950D03*
X484361Y1119337D03*
Y1125746D03*
X469561Y1132154D03*
X471412Y1135359D03*
X473261Y1132154D03*
X475112Y1135359D03*
X476961Y1132154D03*
X478812Y1135359D03*
X480661Y1132154D03*
X482512Y1135359D03*
X484361Y1132154D03*
X496879Y850286D03*
X498728Y847081D03*
X500579Y850286D03*
X485779D03*
X487628Y847081D03*
X489479Y850286D03*
X491328Y847081D03*
X493179Y850286D03*
X495028Y847081D03*
X496879Y856694D03*
Y863103D03*
X498728Y853490D03*
Y859899D03*
Y866307D03*
X500579Y856694D03*
Y863103D03*
X485779Y856694D03*
Y863103D03*
X487628Y853490D03*
Y859899D03*
Y866307D03*
X489479Y856694D03*
Y863103D03*
X491328Y853490D03*
Y859899D03*
Y866307D03*
X493179Y856694D03*
Y863103D03*
X495028Y853490D03*
Y859899D03*
Y866307D03*
X496879Y869511D03*
X498728Y872716D03*
X500579Y869511D03*
X485779D03*
X487628Y872716D03*
X489479Y869511D03*
X491328Y872716D03*
X493179Y869511D03*
X495028Y872716D03*
X496879Y875920D03*
Y882329D03*
X498728Y879124D03*
X500579Y875920D03*
Y882329D03*
X485779Y875920D03*
Y882329D03*
X487628Y879124D03*
X489479Y875920D03*
Y882329D03*
X491328Y879124D03*
X493179Y875920D03*
Y882329D03*
X495028Y879124D03*
X496879Y888737D03*
Y895146D03*
Y901555D03*
X498728Y885533D03*
Y891942D03*
Y898350D03*
X500579Y888737D03*
Y895146D03*
Y901555D03*
X485779Y888737D03*
Y895146D03*
Y901555D03*
X487628Y885533D03*
Y891942D03*
Y898350D03*
X489479Y888737D03*
Y895146D03*
Y901555D03*
X491328Y885533D03*
Y891942D03*
Y898350D03*
X493179Y888737D03*
Y895146D03*
Y901555D03*
X495028Y885533D03*
Y891942D03*
Y898350D03*
X496879Y907963D03*
Y914372D03*
X498728Y904759D03*
Y911167D03*
Y917576D03*
X500579Y907963D03*
Y914372D03*
X485779Y907963D03*
Y914372D03*
X487628Y904759D03*
Y911167D03*
Y917576D03*
X489479Y907963D03*
Y914372D03*
X491328Y904759D03*
Y911167D03*
Y917576D03*
X493179Y907963D03*
Y914372D03*
X495028Y904759D03*
Y911167D03*
Y917576D03*
X496879Y920780D03*
Y927189D03*
X498728Y923985D03*
Y930393D03*
X500579Y920780D03*
Y927189D03*
X485779Y920780D03*
Y927189D03*
X487628Y923985D03*
Y930393D03*
X489479Y920780D03*
Y927189D03*
X491328Y923985D03*
Y930393D03*
X493179Y920780D03*
Y927189D03*
X495028Y923985D03*
Y930393D03*
X496879Y933598D03*
X500579D03*
X485779D03*
X489479D03*
X493179D03*
X496879Y940006D03*
Y946414D03*
X498728Y936801D03*
Y943210D03*
Y949619D03*
X500579Y940006D03*
Y946414D03*
X485779Y940006D03*
Y946414D03*
X487628Y936801D03*
Y943210D03*
Y949619D03*
X489479Y940006D03*
Y946414D03*
X491328Y936801D03*
Y943210D03*
Y949619D03*
X493179Y940006D03*
Y946414D03*
X495028Y936801D03*
Y943210D03*
Y949619D03*
X496879Y952823D03*
Y959232D03*
X498728Y956027D03*
Y962436D03*
X500579Y952823D03*
Y959232D03*
X485779Y952823D03*
Y959232D03*
X487628Y956027D03*
Y962436D03*
X489479Y952823D03*
Y959232D03*
X491328Y956027D03*
Y962436D03*
X493179Y952823D03*
Y959232D03*
X495028Y956027D03*
Y962436D03*
X496879Y965640D03*
X500579D03*
X485779D03*
X489479D03*
X493179D03*
X496879Y972049D03*
Y978457D03*
X498728Y968845D03*
Y975253D03*
Y981662D03*
X500579Y972049D03*
Y978457D03*
X485779Y972049D03*
Y978457D03*
X487628Y968845D03*
Y975253D03*
Y981662D03*
X489479Y972049D03*
Y978457D03*
X491328Y968845D03*
Y975253D03*
Y981662D03*
X493179Y972049D03*
Y978457D03*
X495028Y968845D03*
Y975253D03*
Y981662D03*
X496879Y984866D03*
X500579D03*
X485779D03*
X489479D03*
X493179D03*
X499161Y997574D03*
X488061D03*
X491761D03*
X495461D03*
X497312Y1000778D03*
Y1007187D03*
Y1013595D03*
X499161Y1003983D03*
Y1010391D03*
X501012Y1000778D03*
Y1007187D03*
Y1013595D03*
X486212Y1000778D03*
Y1007187D03*
Y1013595D03*
X488061Y1003983D03*
Y1010391D03*
X489912Y1000778D03*
Y1007187D03*
Y1013595D03*
X491761Y1003983D03*
Y1010391D03*
X493612Y1000778D03*
Y1007187D03*
Y1013595D03*
X495461Y1003983D03*
Y1010391D03*
X497312Y1020004D03*
X499161Y1016800D03*
X501012Y1020004D03*
X486212D03*
X488061Y1016800D03*
X489912Y1020004D03*
X491761Y1016800D03*
X493612Y1020004D03*
X495461Y1016800D03*
X497312Y1026413D03*
X499161Y1023208D03*
Y1029617D03*
X501012Y1026413D03*
X486212D03*
X488061Y1023208D03*
Y1029617D03*
X489912Y1026413D03*
X491761Y1023208D03*
Y1029617D03*
X493612Y1026413D03*
X495461Y1023208D03*
Y1029617D03*
X497312Y1032821D03*
Y1039230D03*
Y1045639D03*
X499161Y1036026D03*
Y1042434D03*
X501012Y1032821D03*
Y1039230D03*
Y1045639D03*
X486212Y1032821D03*
Y1039230D03*
Y1045639D03*
X488061Y1036026D03*
Y1042434D03*
X489912Y1032821D03*
Y1039230D03*
Y1045639D03*
X491761Y1036026D03*
Y1042434D03*
X493612Y1032821D03*
Y1039230D03*
Y1045639D03*
X495461Y1036026D03*
Y1042434D03*
X497312Y1052047D03*
X499161Y1048842D03*
X501012Y1052047D03*
X486212D03*
X488061Y1048842D03*
X489912Y1052047D03*
X491761Y1048842D03*
X493612Y1052047D03*
X495461Y1048842D03*
X497312Y1058455D03*
X499161Y1055251D03*
Y1061660D03*
X501012Y1058455D03*
X486212D03*
X488061Y1055251D03*
Y1061660D03*
X489912Y1058455D03*
X491761Y1055251D03*
Y1061660D03*
X493612Y1058455D03*
X495461Y1055251D03*
Y1061660D03*
X497312Y1064864D03*
Y1071273D03*
Y1077681D03*
X499161Y1068068D03*
Y1074477D03*
X501012Y1064864D03*
Y1071273D03*
Y1077681D03*
X486212Y1064864D03*
Y1071273D03*
Y1077681D03*
X488061Y1068068D03*
Y1074477D03*
X489912Y1064864D03*
Y1071273D03*
Y1077681D03*
X491761Y1068068D03*
Y1074477D03*
X493612Y1064864D03*
Y1071273D03*
Y1077681D03*
X495461Y1068068D03*
Y1074477D03*
X499161Y1080885D03*
X488061D03*
X491761D03*
X495461D03*
X497312Y1084090D03*
Y1090498D03*
X499161Y1087294D03*
Y1093703D03*
X501012Y1084090D03*
Y1090498D03*
X486212Y1084090D03*
Y1090498D03*
X488061Y1087294D03*
Y1093703D03*
X489912Y1084090D03*
Y1090498D03*
X491761Y1087294D03*
Y1093703D03*
X493612Y1084090D03*
Y1090498D03*
X495461Y1087294D03*
Y1093703D03*
X497312Y1096907D03*
Y1103316D03*
Y1109724D03*
X499161Y1100111D03*
Y1106520D03*
X501012Y1096907D03*
Y1103316D03*
Y1109724D03*
X486212Y1096907D03*
Y1103316D03*
Y1109724D03*
X488061Y1100111D03*
Y1106520D03*
X489912Y1096907D03*
Y1103316D03*
Y1109724D03*
X491761Y1100111D03*
Y1106520D03*
X493612Y1096907D03*
Y1103316D03*
Y1109724D03*
X495461Y1100111D03*
Y1106520D03*
X499161Y1112929D03*
X488061D03*
X491761D03*
X495461D03*
X497312Y1116133D03*
Y1122541D03*
Y1128950D03*
X499161Y1119337D03*
Y1125746D03*
X501012Y1116133D03*
Y1122541D03*
Y1128950D03*
X486212Y1116133D03*
Y1122541D03*
Y1128950D03*
X488061Y1119337D03*
Y1125746D03*
X489912Y1116133D03*
Y1122541D03*
Y1128950D03*
X491761Y1119337D03*
Y1125746D03*
X493612Y1116133D03*
Y1122541D03*
Y1128950D03*
X495461Y1119337D03*
Y1125746D03*
X497312Y1135359D03*
X499161Y1132154D03*
X501012Y1135359D03*
X486212D03*
X488061Y1132154D03*
X489912Y1135359D03*
X491761Y1132154D03*
X493612Y1135359D03*
X495461Y1132154D03*
X502428Y847081D03*
X504279Y850286D03*
X506128Y847081D03*
X507979Y850286D03*
X509828Y847081D03*
X511679Y850286D03*
X513528Y847081D03*
X515379Y850286D03*
X517228Y847081D03*
X502428Y853490D03*
Y859899D03*
Y866307D03*
X504279Y856694D03*
Y863103D03*
X506128Y853490D03*
Y859899D03*
Y866307D03*
X507979Y856694D03*
Y863103D03*
X509828Y853490D03*
Y859899D03*
Y866307D03*
X511679Y856694D03*
Y863103D03*
X513528Y853490D03*
Y859899D03*
Y866307D03*
X515379Y856694D03*
Y863103D03*
X517228Y853490D03*
Y859899D03*
Y866307D03*
X502428Y872716D03*
X504279Y869511D03*
X506128Y872716D03*
X507979Y869511D03*
X509828Y872716D03*
X511679Y869511D03*
X513528Y872716D03*
X515379Y869511D03*
X517228Y872716D03*
X502428Y879124D03*
X504279Y875920D03*
Y882329D03*
X506128Y879124D03*
X507979Y875920D03*
Y882329D03*
X509828Y879124D03*
X511679Y875920D03*
Y882329D03*
X513528Y879124D03*
X515379Y875920D03*
Y882329D03*
X517228Y879124D03*
X502428Y885533D03*
Y891942D03*
Y898350D03*
X504279Y888737D03*
Y895146D03*
Y901555D03*
X506128Y885533D03*
Y891942D03*
Y898350D03*
X507979Y888737D03*
Y895146D03*
Y901555D03*
X509828Y885533D03*
Y891942D03*
Y898350D03*
X511679Y888737D03*
Y895146D03*
Y901555D03*
X513528Y885533D03*
Y891942D03*
Y898350D03*
X515379Y888737D03*
Y895146D03*
Y901555D03*
X517228Y885533D03*
Y891942D03*
Y898350D03*
X502428Y904759D03*
Y911167D03*
Y917576D03*
X504279Y907963D03*
Y914372D03*
X506128Y904759D03*
Y911167D03*
Y917576D03*
X507979Y907963D03*
Y914372D03*
X509828Y904759D03*
Y911167D03*
Y917576D03*
X511679Y907963D03*
Y914372D03*
X513528Y904759D03*
Y911167D03*
Y917576D03*
X515379Y907963D03*
Y914372D03*
X517228Y904759D03*
Y911167D03*
Y917576D03*
X502428Y923985D03*
Y930393D03*
X504279Y920780D03*
Y927189D03*
X506128Y923985D03*
Y930393D03*
X507979Y920780D03*
Y927189D03*
X509828Y923985D03*
Y930393D03*
X511679Y920780D03*
Y927189D03*
X513528Y923985D03*
Y930393D03*
X515379Y920780D03*
Y927189D03*
X517228Y923985D03*
Y930393D03*
X504279Y933598D03*
X507979D03*
X511679D03*
X515379D03*
X502428Y936801D03*
Y943210D03*
Y949619D03*
X504279Y940006D03*
Y946414D03*
X506128Y936801D03*
Y943210D03*
Y949619D03*
X507979Y940006D03*
Y946414D03*
X509828Y936801D03*
Y943210D03*
Y949619D03*
X511679Y940006D03*
Y946414D03*
X513528Y936801D03*
Y943210D03*
Y949619D03*
X515379Y940006D03*
Y946414D03*
X517228Y936801D03*
Y943210D03*
Y949619D03*
X502428Y956027D03*
Y962436D03*
X504279Y952823D03*
Y959232D03*
X506128Y956027D03*
Y962436D03*
X507979Y952823D03*
Y959232D03*
X509828Y956027D03*
Y962436D03*
X511679Y952823D03*
Y959232D03*
X513528Y956027D03*
Y962436D03*
X515379Y952823D03*
Y959232D03*
X517228Y956027D03*
Y962436D03*
X504279Y965640D03*
X507979D03*
X511679D03*
X515379D03*
X502428Y968845D03*
Y975253D03*
Y981662D03*
X504279Y972049D03*
Y978457D03*
X506128Y968845D03*
Y975253D03*
Y981662D03*
X507979Y972049D03*
Y978457D03*
X509828Y968845D03*
Y975253D03*
Y981662D03*
X511679Y972049D03*
Y978457D03*
X513528Y968845D03*
Y975253D03*
Y981662D03*
X515379Y972049D03*
Y978457D03*
X517228Y968845D03*
Y975253D03*
Y981662D03*
X504279Y984866D03*
X507979D03*
X511679D03*
X515379D03*
X502861Y997574D03*
X506561D03*
X510261D03*
X513961D03*
X517661D03*
X502861Y1003983D03*
Y1010391D03*
X504712Y1000778D03*
Y1007187D03*
Y1013595D03*
X506561Y1003983D03*
Y1010391D03*
X508412Y1000778D03*
Y1007187D03*
Y1013595D03*
X510261Y1003983D03*
Y1010391D03*
X512112Y1000778D03*
Y1007187D03*
Y1013595D03*
X513961Y1003983D03*
Y1010391D03*
X515812Y1000778D03*
Y1007187D03*
Y1013595D03*
X517661Y1003983D03*
Y1010391D03*
X502862Y1006093D03*
X502861Y1016800D03*
X504712Y1020004D03*
X506561Y1016800D03*
X508412Y1020004D03*
X510261Y1016800D03*
X512112Y1020004D03*
X513961Y1016800D03*
X515812Y1020004D03*
X517661Y1016800D03*
X502861Y1023208D03*
Y1029617D03*
X504712Y1026413D03*
X506561Y1023208D03*
Y1029617D03*
X508412Y1026413D03*
X510261Y1023208D03*
Y1029617D03*
X512112Y1026413D03*
X513961Y1023208D03*
Y1029617D03*
X515812Y1026413D03*
X517661Y1023208D03*
Y1029617D03*
X502861Y1036026D03*
Y1042434D03*
X504712Y1032821D03*
Y1039230D03*
Y1045639D03*
X506561Y1036026D03*
Y1042434D03*
X508412Y1032821D03*
Y1039230D03*
Y1045639D03*
X510261Y1036026D03*
Y1042434D03*
X512112Y1032821D03*
Y1039230D03*
Y1045639D03*
X513961Y1036026D03*
Y1042434D03*
X515812Y1032821D03*
Y1039230D03*
Y1045639D03*
X517661Y1036026D03*
Y1042434D03*
X502861Y1048842D03*
X504712Y1052047D03*
X506561Y1048842D03*
X508412Y1052047D03*
X510261Y1048842D03*
X512112Y1052047D03*
X513961Y1048842D03*
X515812Y1052047D03*
X517661Y1048842D03*
X502861Y1055251D03*
Y1061660D03*
X504712Y1058455D03*
X506561Y1055251D03*
Y1061660D03*
X508412Y1058455D03*
X510261Y1055251D03*
Y1061660D03*
X512112Y1058455D03*
X513961Y1055251D03*
Y1061660D03*
X515812Y1058455D03*
X517661Y1055251D03*
Y1061660D03*
X502861Y1068068D03*
Y1074477D03*
X504712Y1064864D03*
Y1071273D03*
Y1077681D03*
X506561Y1068068D03*
Y1074477D03*
X508412Y1064864D03*
Y1071273D03*
Y1077681D03*
X510261Y1068068D03*
Y1074477D03*
X512112Y1064864D03*
Y1071273D03*
Y1077681D03*
X513961Y1068068D03*
Y1074477D03*
X515812Y1064864D03*
Y1071273D03*
Y1077681D03*
X517661Y1068068D03*
Y1074477D03*
X502861Y1080885D03*
X506561D03*
X510261D03*
X513961D03*
X517661D03*
X502861Y1087294D03*
Y1093703D03*
X504712Y1084090D03*
Y1090498D03*
X506561Y1087294D03*
Y1093703D03*
X508412Y1084090D03*
Y1090498D03*
X510261Y1087294D03*
Y1093703D03*
X512112Y1084090D03*
Y1090498D03*
X513961Y1087294D03*
Y1093703D03*
X515812Y1084090D03*
Y1090498D03*
X517661Y1087294D03*
Y1093703D03*
X502861Y1100111D03*
Y1106520D03*
X504712Y1096907D03*
Y1103316D03*
Y1109724D03*
X506561Y1100111D03*
Y1106520D03*
X508412Y1096907D03*
Y1103316D03*
Y1109724D03*
X510261Y1100111D03*
Y1106520D03*
X512112Y1096907D03*
Y1103316D03*
Y1109724D03*
X513961Y1100111D03*
Y1106520D03*
X515812Y1096907D03*
Y1103316D03*
Y1109724D03*
X517661Y1100111D03*
Y1106520D03*
X502861Y1112929D03*
X506561D03*
X510261D03*
X513961D03*
X517661D03*
X502861Y1119337D03*
Y1125746D03*
X504712Y1116133D03*
Y1122541D03*
Y1128950D03*
X506561Y1119337D03*
Y1125746D03*
X508412Y1116133D03*
Y1122541D03*
Y1128950D03*
X510261Y1119337D03*
Y1125746D03*
X512112Y1116133D03*
Y1122541D03*
Y1128950D03*
X513961Y1119337D03*
Y1125746D03*
X515812Y1116133D03*
Y1122541D03*
Y1128950D03*
X517661Y1119337D03*
Y1125746D03*
X502861Y1132154D03*
X504712Y1135359D03*
X506561Y1132154D03*
X508412Y1135359D03*
X510261Y1132154D03*
X512112Y1135359D03*
X513961Y1132154D03*
X515812Y1135359D03*
X517661Y1132154D03*
X526479Y850286D03*
X530179D03*
X519079D03*
X520928Y847081D03*
X522779Y850286D03*
X526479Y856694D03*
Y863103D03*
X528329Y853490D03*
Y859899D03*
Y866307D03*
X530179Y856694D03*
Y863103D03*
X532028Y853490D03*
Y859899D03*
Y866307D03*
X533879Y856694D03*
Y863103D03*
X519079Y856694D03*
Y863103D03*
X520928Y853490D03*
Y859899D03*
Y866307D03*
X522779Y856694D03*
Y863103D03*
X524628Y853490D03*
Y859899D03*
Y866307D03*
X526479Y869511D03*
X528329Y872716D03*
X530179Y869511D03*
X532028Y872716D03*
X533879Y869511D03*
X519079D03*
X520928Y872716D03*
X522779Y869511D03*
X524628Y872716D03*
X526479Y875920D03*
Y882329D03*
X528329Y879124D03*
X530179Y875920D03*
Y882329D03*
X532028Y879124D03*
X533879Y875920D03*
Y882329D03*
X519079Y875920D03*
Y882329D03*
X520928Y879124D03*
X522779Y875920D03*
Y882329D03*
X524628Y879124D03*
X526479Y888737D03*
Y895146D03*
Y901555D03*
X528329Y885533D03*
Y891942D03*
Y898350D03*
X530179Y888737D03*
Y895146D03*
Y901555D03*
X532028Y885533D03*
Y891942D03*
Y898350D03*
X533879Y888737D03*
Y895146D03*
Y901555D03*
X519079Y888737D03*
Y895146D03*
Y901555D03*
X520928Y885533D03*
Y891942D03*
Y898350D03*
X522779Y888737D03*
Y895146D03*
Y901555D03*
X524628Y885533D03*
Y891942D03*
Y898350D03*
X526479Y907963D03*
Y914372D03*
X528329Y904759D03*
Y911167D03*
Y917576D03*
X530179Y907963D03*
Y914372D03*
X532028Y904759D03*
Y911167D03*
Y917576D03*
X533879Y907963D03*
Y914372D03*
X519079Y907963D03*
Y914372D03*
X520928Y904759D03*
Y911167D03*
Y917576D03*
X522779Y907963D03*
Y914372D03*
X524628Y904759D03*
Y911167D03*
Y917576D03*
X526479Y920780D03*
Y927189D03*
X528329Y923985D03*
Y930393D03*
X530179Y920780D03*
Y927189D03*
X532028Y923985D03*
Y930393D03*
X533879Y920780D03*
Y927189D03*
X519079Y920780D03*
Y927189D03*
X520928Y923985D03*
Y930393D03*
X522779Y920780D03*
Y927189D03*
X524628Y923985D03*
Y930393D03*
X526479Y933598D03*
X530179D03*
X533879D03*
X519079D03*
X522779D03*
X526479Y940006D03*
Y946414D03*
X528329Y936801D03*
Y943210D03*
Y949619D03*
X530179Y940006D03*
Y946414D03*
X532028Y936801D03*
Y943210D03*
Y949619D03*
X533879Y940006D03*
Y946414D03*
X519079Y940006D03*
Y946414D03*
X520928Y936801D03*
Y943210D03*
Y949619D03*
X522779Y940006D03*
Y946414D03*
X524628Y936801D03*
Y943210D03*
Y949619D03*
X526479Y952823D03*
Y959232D03*
X528329Y956027D03*
Y962436D03*
X530179Y952823D03*
Y959232D03*
X532028Y956027D03*
Y962436D03*
X533879Y952823D03*
Y959232D03*
X519079Y952823D03*
Y959232D03*
X520928Y956027D03*
Y962436D03*
X522779Y952823D03*
Y959232D03*
X524628Y956027D03*
Y962436D03*
X526479Y965640D03*
X530179D03*
X533879D03*
X519079D03*
X522779D03*
X526479Y972049D03*
Y978457D03*
X528329Y968845D03*
Y975253D03*
Y981662D03*
X530179Y972049D03*
Y978457D03*
X532028Y968845D03*
Y975253D03*
Y981662D03*
X533879Y972049D03*
Y978457D03*
X519079Y972049D03*
Y978457D03*
X520928Y968845D03*
Y975253D03*
Y981662D03*
X522779Y972049D03*
Y978457D03*
X524628Y968845D03*
Y975253D03*
Y981662D03*
X526479Y984866D03*
X530179D03*
X533879D03*
X519079D03*
X522779D03*
X528761Y997574D03*
X532461D03*
X521361D03*
X525061D03*
X526912Y1000778D03*
Y1007187D03*
Y1013595D03*
X528761Y1003983D03*
Y1010391D03*
X530612Y1000778D03*
Y1007187D03*
Y1013595D03*
X532461Y1003983D03*
Y1010391D03*
X519512Y1000778D03*
Y1007187D03*
Y1013595D03*
X521361Y1003983D03*
Y1010391D03*
X523212Y1000778D03*
Y1007187D03*
Y1013595D03*
X525061Y1003983D03*
Y1010391D03*
X526912Y1020004D03*
X528761Y1016800D03*
X530612Y1020004D03*
X532461Y1016800D03*
X519512Y1020004D03*
X521361Y1016800D03*
X523212Y1020004D03*
X525061Y1016800D03*
X526912Y1026413D03*
X528761Y1023208D03*
Y1029617D03*
X530612Y1026413D03*
X532461Y1023208D03*
Y1029617D03*
X519512Y1026413D03*
X521361Y1023208D03*
Y1029617D03*
X523212Y1026413D03*
X525061Y1023208D03*
Y1029617D03*
X526912Y1032821D03*
Y1039230D03*
Y1045639D03*
X528761Y1036026D03*
Y1042434D03*
X530612Y1032821D03*
Y1039230D03*
Y1045639D03*
X532461Y1036026D03*
Y1042434D03*
X519512Y1032821D03*
Y1039230D03*
Y1045639D03*
X521361Y1036026D03*
Y1042434D03*
X523212Y1032821D03*
Y1039230D03*
Y1045639D03*
X525061Y1036026D03*
Y1042434D03*
X526912Y1052047D03*
X528761Y1048842D03*
X530612Y1052047D03*
X532461Y1048842D03*
X519512Y1052047D03*
X521361Y1048842D03*
X523212Y1052047D03*
X525061Y1048842D03*
X526912Y1058455D03*
X528761Y1055251D03*
Y1061660D03*
X530612Y1058455D03*
X532461Y1055251D03*
Y1061660D03*
X519512Y1058455D03*
X521361Y1055251D03*
Y1061660D03*
X523212Y1058455D03*
X525061Y1055251D03*
Y1061660D03*
X526912Y1064864D03*
Y1071273D03*
Y1077681D03*
X528761Y1068068D03*
Y1074477D03*
X530612Y1064864D03*
Y1071273D03*
Y1077681D03*
X532461Y1068068D03*
Y1074477D03*
X519512Y1064864D03*
Y1071273D03*
Y1077681D03*
X521361Y1068068D03*
Y1074477D03*
X523212Y1064864D03*
Y1071273D03*
Y1077681D03*
X525061Y1068068D03*
Y1074477D03*
X528761Y1080885D03*
X532461D03*
X521361D03*
X525061D03*
X526912Y1084090D03*
Y1090498D03*
X528761Y1087294D03*
Y1093703D03*
X530612Y1084090D03*
Y1090498D03*
X532461Y1087294D03*
Y1093703D03*
X519512Y1084090D03*
Y1090498D03*
X521361Y1087294D03*
Y1093703D03*
X523212Y1084090D03*
Y1090498D03*
X525061Y1087294D03*
Y1093703D03*
X526912Y1096907D03*
Y1103316D03*
Y1109724D03*
X528761Y1100111D03*
Y1106520D03*
X530612Y1096907D03*
Y1103316D03*
Y1109724D03*
X532461Y1100111D03*
Y1106520D03*
X519512Y1096907D03*
Y1103316D03*
Y1109724D03*
X521361Y1100111D03*
Y1106520D03*
X523212Y1096907D03*
Y1103316D03*
Y1109724D03*
X525061Y1100111D03*
Y1106520D03*
X528761Y1112929D03*
X532461D03*
X521361D03*
X525061D03*
X526912Y1116133D03*
Y1122541D03*
Y1128950D03*
X528761Y1119337D03*
Y1125746D03*
X530612Y1116133D03*
Y1122541D03*
Y1128950D03*
X532461Y1119337D03*
Y1125746D03*
X519512Y1116133D03*
Y1122541D03*
Y1128950D03*
X521361Y1119337D03*
Y1125746D03*
X523212Y1116133D03*
Y1122541D03*
Y1128950D03*
X525061Y1119337D03*
Y1125746D03*
X528761Y1132154D03*
X519512Y1135359D03*
X521361Y1132154D03*
X523212Y1135359D03*
X525061Y1132154D03*
X535729Y859899D03*
Y866307D03*
X537579Y863103D03*
X539428Y866307D03*
X535729Y872716D03*
X537579Y869511D03*
X539428Y872716D03*
X541279Y869511D03*
X543129Y872716D03*
X535729Y879124D03*
X537579Y875920D03*
Y882329D03*
X539428Y879124D03*
X541279Y875920D03*
Y882329D03*
X543129Y879124D03*
X544979Y875920D03*
Y882329D03*
X535729Y885533D03*
Y891942D03*
Y898350D03*
X537579Y888737D03*
Y895146D03*
Y901555D03*
X539428Y885533D03*
Y891942D03*
Y898350D03*
X541279Y888737D03*
Y895146D03*
Y901555D03*
X543129Y885533D03*
Y891942D03*
Y898350D03*
X544979Y888737D03*
Y895146D03*
Y901555D03*
X537579Y893036D03*
Y899445D03*
X535729Y904759D03*
Y911167D03*
Y917576D03*
X537579Y907963D03*
Y914372D03*
X539428Y904759D03*
Y911167D03*
Y917576D03*
X541279Y907963D03*
Y914372D03*
X543129Y904759D03*
Y911167D03*
Y917576D03*
X544979Y907963D03*
Y914372D03*
X537579Y912262D03*
X539429Y909057D03*
X543129D03*
X535729Y923985D03*
Y930393D03*
X537579Y920780D03*
Y927189D03*
X539428Y923985D03*
Y930393D03*
X541279Y920780D03*
Y927189D03*
X543129Y923985D03*
Y930393D03*
X544979Y920780D03*
Y927189D03*
X537579Y933598D03*
X541279D03*
X544979D03*
X543129Y928283D03*
X539429D03*
X537579Y918670D03*
X537578Y931488D03*
X535729Y936801D03*
Y943210D03*
Y949619D03*
X537579Y940006D03*
Y946414D03*
X539428Y936801D03*
Y943210D03*
Y949619D03*
X541279Y940006D03*
Y946414D03*
X543129Y936801D03*
Y943210D03*
Y949619D03*
X544979Y940006D03*
Y946414D03*
X537579Y937896D03*
X539429Y947509D03*
X535729Y956027D03*
Y962436D03*
X537579Y952823D03*
Y959232D03*
X539428Y956027D03*
Y962436D03*
X541279Y952823D03*
Y959232D03*
X543129Y956027D03*
Y962436D03*
X544979Y952823D03*
Y959232D03*
X537579Y965640D03*
X541279D03*
X544979D03*
X537579Y957122D03*
Y950713D03*
X535729Y968845D03*
Y975253D03*
Y981662D03*
X537579Y972049D03*
Y978457D03*
X539428Y968845D03*
Y975253D03*
Y981662D03*
X541279Y972049D03*
Y978457D03*
X543129Y968845D03*
Y975253D03*
X544979Y972049D03*
X539429Y979552D03*
X535729Y973143D03*
X537579Y984866D03*
X536161Y997574D03*
X539861D03*
X534311Y1000778D03*
Y1007187D03*
Y1013595D03*
X536161Y1003983D03*
Y1010391D03*
X538012Y1000778D03*
Y1007187D03*
Y1013595D03*
X539861Y1003983D03*
Y1010391D03*
X541711Y1000778D03*
Y1007187D03*
Y1013595D03*
X543561Y1003983D03*
Y1010391D03*
X545412Y1007187D03*
Y1013595D03*
X539862Y1006092D03*
X539861Y999684D03*
X536161Y1006093D03*
X543563Y1006092D03*
X534311Y1020004D03*
X536161Y1016800D03*
X538012Y1020004D03*
X539861Y1016800D03*
X541711Y1020004D03*
X543561Y1016800D03*
X545412Y1020004D03*
X534311Y1026413D03*
X536161Y1023208D03*
Y1029617D03*
X538012Y1026413D03*
X539861Y1023208D03*
Y1029617D03*
X541711Y1026413D03*
X543561Y1023208D03*
Y1029617D03*
X545412Y1026413D03*
X536161Y1025318D03*
X539861Y1018910D03*
X534311Y1032821D03*
Y1039230D03*
Y1045639D03*
X536161Y1036026D03*
Y1042434D03*
X538012Y1032821D03*
Y1039230D03*
Y1045639D03*
X539861Y1036026D03*
Y1042434D03*
X541711Y1032821D03*
Y1039230D03*
Y1045639D03*
X543561Y1036026D03*
Y1042434D03*
X545412Y1032821D03*
Y1039230D03*
X539862Y1044544D03*
X539861Y1038136D03*
X534311Y1052047D03*
X536161Y1048842D03*
X538012Y1052047D03*
X539861Y1048842D03*
X541711Y1052047D03*
X543561Y1048842D03*
X534311Y1058455D03*
X536161Y1055251D03*
Y1061660D03*
X538012Y1058455D03*
X539861Y1055251D03*
Y1061660D03*
X541711Y1058455D03*
X543561Y1055251D03*
Y1061660D03*
X538011Y1060565D03*
X534311Y1064864D03*
Y1071273D03*
Y1077681D03*
X536161Y1068068D03*
Y1074477D03*
X538012Y1064864D03*
Y1071273D03*
Y1077681D03*
X539861Y1068068D03*
Y1074477D03*
X541711Y1064864D03*
Y1071273D03*
Y1077681D03*
X543561Y1068068D03*
Y1074477D03*
X538011Y1066974D03*
X541711Y1073383D03*
X539861Y1076587D03*
X536161Y1080885D03*
X539861D03*
X543561D03*
X534311Y1084090D03*
Y1090498D03*
X536161Y1087294D03*
Y1093703D03*
X538012Y1084090D03*
Y1090498D03*
X539861Y1087294D03*
Y1093703D03*
X541711Y1084090D03*
Y1090498D03*
X543561Y1087294D03*
Y1093703D03*
X536162Y1082996D03*
X534311Y1096907D03*
Y1103316D03*
Y1109724D03*
X536161Y1100111D03*
Y1106520D03*
X538012Y1096907D03*
Y1103316D03*
Y1109724D03*
X539861Y1100111D03*
Y1106520D03*
X541711Y1096907D03*
Y1103316D03*
Y1109724D03*
X543561Y1100111D03*
Y1106520D03*
X536161Y1112929D03*
X539861D03*
X534311Y1116133D03*
Y1122541D03*
X536161Y1119337D03*
X538012Y1116133D03*
X1312070Y879124D03*
X1313921Y875920D03*
Y882329D03*
X1312070Y885533D03*
Y891942D03*
Y898350D03*
X1313921Y888737D03*
Y895146D03*
Y901555D03*
X1312070Y904759D03*
Y911167D03*
Y917576D03*
X1313921Y907963D03*
Y914372D03*
X1312070Y923985D03*
Y930393D03*
X1313921Y920780D03*
Y927189D03*
Y933598D03*
X1312070Y936801D03*
Y943210D03*
Y949619D03*
X1313921Y940006D03*
Y946414D03*
X1312070Y956027D03*
Y962436D03*
X1313921Y952823D03*
Y959232D03*
Y965640D03*
X1312070Y968845D03*
Y975253D03*
X1313921Y972049D03*
Y978457D03*
X1312503Y1010391D03*
X1314353Y1007187D03*
Y1013595D03*
X1312503Y1016800D03*
Y1023208D03*
X1314353Y1020004D03*
X1312503Y1029617D03*
X1314353Y1026413D03*
Y1022114D03*
X1312503Y1036026D03*
Y1042434D03*
X1314353Y1032821D03*
Y1039230D03*
Y1045639D03*
Y1041340D03*
X1312503Y1048842D03*
X1314353Y1052047D03*
Y1058455D03*
Y1060565D03*
Y1064864D03*
Y1071273D03*
Y1077681D03*
Y1084090D03*
Y1090498D03*
Y1096907D03*
Y1103316D03*
Y1109724D03*
Y1105426D03*
X1328721Y850286D03*
X1323171Y859899D03*
Y866307D03*
X1325021Y856694D03*
Y863103D03*
X1326870Y853490D03*
Y859899D03*
Y866307D03*
X1328721Y856694D03*
Y863103D03*
X1330570Y853490D03*
Y859899D03*
Y866307D03*
X1319470D03*
X1321321Y863103D03*
X1317621Y867401D03*
X1323171Y872716D03*
X1325021Y869511D03*
X1326870Y872716D03*
X1328721Y869511D03*
X1330570Y872716D03*
X1315771D03*
X1317621Y869511D03*
X1319470Y872716D03*
X1321321Y869511D03*
X1323171Y879124D03*
X1325021Y875920D03*
Y882329D03*
X1326870Y879124D03*
X1328721Y875920D03*
Y882329D03*
X1330570Y879124D03*
X1315771D03*
X1317621Y875920D03*
Y882329D03*
X1319470Y879124D03*
X1321321Y875920D03*
Y882329D03*
X1317621Y873810D03*
X1323171Y885533D03*
Y891942D03*
Y898350D03*
X1325021Y888737D03*
Y895146D03*
Y901555D03*
X1326870Y885533D03*
Y891942D03*
Y898350D03*
X1328721Y888737D03*
Y895146D03*
Y901555D03*
X1330570Y885533D03*
Y891942D03*
Y898350D03*
X1315771Y885533D03*
Y891942D03*
Y898350D03*
X1317621Y888737D03*
Y895146D03*
Y901555D03*
X1319470Y885533D03*
Y891942D03*
Y898350D03*
X1321321Y888737D03*
Y895146D03*
Y901555D03*
X1323171Y904759D03*
Y911167D03*
Y917576D03*
X1325021Y907963D03*
Y914372D03*
X1326870Y904759D03*
Y911167D03*
Y917576D03*
X1328721Y907963D03*
Y914372D03*
X1330570Y904759D03*
Y911167D03*
Y917576D03*
X1315771Y904759D03*
Y911167D03*
Y917576D03*
X1317621Y907963D03*
Y914372D03*
X1319470Y904759D03*
Y911167D03*
Y917576D03*
X1321321Y907963D03*
Y914372D03*
X1317621Y912262D03*
X1317620Y905853D03*
X1323171Y923985D03*
Y930393D03*
X1325021Y920780D03*
Y927189D03*
Y933598D03*
X1326870Y923985D03*
Y930393D03*
X1328721Y920780D03*
Y927189D03*
Y933598D03*
X1330570Y923985D03*
Y930393D03*
X1315771Y923985D03*
Y930393D03*
X1317621Y920780D03*
Y927189D03*
Y933598D03*
X1319470Y923985D03*
Y930393D03*
X1321321Y920780D03*
Y927189D03*
Y933598D03*
X1317620Y925079D03*
X1317621Y931488D03*
X1323171Y936801D03*
Y943210D03*
Y949619D03*
X1325021Y940006D03*
Y946414D03*
X1326870Y936801D03*
Y943210D03*
Y949619D03*
X1328721Y940006D03*
Y946414D03*
X1330570Y936801D03*
Y943210D03*
Y949619D03*
X1315771Y936801D03*
Y943210D03*
Y949619D03*
X1317621Y940006D03*
Y946414D03*
X1319470Y936801D03*
Y943210D03*
Y949619D03*
X1321321Y940006D03*
Y946414D03*
X1317620Y944304D03*
X1323171Y956027D03*
Y962436D03*
X1325021Y952823D03*
Y959232D03*
X1326870Y956027D03*
Y962436D03*
X1328721Y952823D03*
Y959232D03*
X1330570Y956027D03*
Y962436D03*
X1315771Y956027D03*
Y962436D03*
X1317621Y952823D03*
Y959232D03*
X1319470Y956027D03*
Y962436D03*
X1321321Y952823D03*
Y959232D03*
X1325021Y965640D03*
X1328721D03*
X1317621D03*
X1321321D03*
X1319471Y966735D03*
X1319470Y960326D03*
X1317621Y950713D03*
X1323171Y968845D03*
Y975253D03*
Y981662D03*
X1325021Y972049D03*
Y978457D03*
X1326870Y968845D03*
Y975253D03*
Y981662D03*
X1328721Y972049D03*
Y978457D03*
X1330570Y968845D03*
Y975253D03*
Y981662D03*
X1315771Y968845D03*
Y975253D03*
Y981662D03*
X1317621Y972049D03*
Y978457D03*
X1319470Y968845D03*
Y975253D03*
Y981662D03*
X1321321Y972049D03*
Y978457D03*
X1325021Y984866D03*
X1328721D03*
X1317621D03*
X1321321D03*
X1323603Y997574D03*
X1327303D03*
X1331003D03*
X1319903D03*
X1323603Y1003983D03*
Y1010391D03*
X1325454Y1000778D03*
Y1007187D03*
Y1013595D03*
X1327303Y1003983D03*
Y1010391D03*
X1329153Y1000778D03*
Y1007187D03*
Y1013595D03*
X1331003Y1003983D03*
Y1010391D03*
X1316203Y1003983D03*
Y1010391D03*
X1318054Y1000778D03*
Y1007187D03*
Y1013595D03*
X1319903Y1003983D03*
Y1010391D03*
X1321753Y1000778D03*
Y1007187D03*
Y1013595D03*
X1318053Y1009297D03*
Y1002888D03*
X1323603Y1016800D03*
Y1023208D03*
X1325454Y1020004D03*
X1327303Y1016800D03*
Y1023208D03*
X1329153Y1020004D03*
X1331003Y1016800D03*
Y1023208D03*
X1316203Y1016800D03*
Y1023208D03*
X1318054Y1020004D03*
X1319903Y1016800D03*
Y1023208D03*
X1321753Y1020004D03*
X1323603Y1029617D03*
X1325454Y1026413D03*
X1327303Y1029617D03*
X1329153Y1026413D03*
X1331003Y1029617D03*
X1316203D03*
X1318054Y1026413D03*
X1319903Y1029617D03*
X1321753Y1026413D03*
X1318053Y1022114D03*
X1319903Y1018910D03*
X1321753Y1015705D03*
X1319903Y1031727D03*
X1323603Y1036026D03*
Y1042434D03*
X1325454Y1032821D03*
Y1039230D03*
Y1045639D03*
X1327303Y1036026D03*
Y1042434D03*
X1329153Y1032821D03*
Y1039230D03*
Y1045639D03*
X1331003Y1036026D03*
Y1042434D03*
X1316203Y1036026D03*
Y1042434D03*
X1318054Y1032821D03*
Y1039230D03*
Y1045639D03*
X1319903Y1036026D03*
Y1042434D03*
X1321753Y1032821D03*
Y1039230D03*
Y1045639D03*
X1318053Y1041340D03*
X1319903Y1038136D03*
X1323603Y1048842D03*
X1325454Y1052047D03*
X1327303Y1048842D03*
X1329153Y1052047D03*
X1331003Y1048842D03*
X1316203D03*
X1318054Y1052047D03*
X1319903Y1048842D03*
X1321753Y1052047D03*
X1323603Y1055251D03*
Y1061660D03*
X1325454Y1058455D03*
X1327303Y1055251D03*
Y1061660D03*
X1329153Y1058455D03*
X1331003Y1055251D03*
Y1061660D03*
X1316203Y1055251D03*
Y1061660D03*
X1318054Y1058455D03*
X1319903Y1055251D03*
Y1061660D03*
X1321753Y1058455D03*
X1319903Y1057361D03*
Y1050952D03*
X1323603Y1068068D03*
Y1074477D03*
X1325454Y1064864D03*
Y1071273D03*
Y1077681D03*
X1327303Y1068068D03*
Y1074477D03*
X1329153Y1064864D03*
Y1071273D03*
Y1077681D03*
X1331003Y1068068D03*
Y1074477D03*
X1316203Y1068068D03*
Y1074477D03*
X1318054Y1064864D03*
Y1071273D03*
Y1077681D03*
X1319903Y1068068D03*
Y1074477D03*
X1321753Y1064864D03*
Y1071273D03*
Y1077681D03*
X1319903Y1076587D03*
Y1070178D03*
X1318053Y1079791D03*
X1323603Y1080885D03*
X1327303D03*
X1331003D03*
X1316203D03*
X1319903D03*
X1323603Y1087294D03*
Y1093703D03*
X1325454Y1084090D03*
Y1090498D03*
X1327303Y1087294D03*
Y1093703D03*
X1329153Y1084090D03*
Y1090498D03*
X1331003Y1087294D03*
Y1093703D03*
X1316203Y1087294D03*
Y1093703D03*
X1318054Y1084090D03*
Y1090498D03*
X1319903Y1087294D03*
Y1093703D03*
X1321753Y1084090D03*
Y1090498D03*
X1316202Y1082995D03*
X1316203Y1095813D03*
X1323603Y1100111D03*
Y1106520D03*
Y1112929D03*
X1325454Y1096907D03*
Y1103316D03*
Y1109724D03*
X1327303Y1100111D03*
Y1106520D03*
Y1112929D03*
X1329153Y1096907D03*
Y1103316D03*
Y1109724D03*
X1331003Y1100111D03*
Y1106520D03*
Y1112929D03*
X1316203Y1100111D03*
Y1106520D03*
Y1112929D03*
X1318054Y1096907D03*
Y1103316D03*
Y1109724D03*
X1319903Y1100111D03*
Y1106520D03*
Y1112929D03*
X1321753Y1096907D03*
Y1103316D03*
Y1109724D03*
X1323603Y1119337D03*
Y1125746D03*
X1325454Y1116133D03*
Y1122541D03*
Y1128950D03*
X1327303Y1119337D03*
Y1125746D03*
X1329153Y1116133D03*
Y1122541D03*
Y1128950D03*
X1331003Y1119337D03*
Y1125746D03*
X1318054Y1116133D03*
X1319903Y1119337D03*
X1321753Y1116133D03*
Y1122541D03*
X1327303Y1132154D03*
X1331003D03*
X1347221Y850286D03*
X1332421D03*
X1334270Y847081D03*
X1336121Y850286D03*
X1337970Y847081D03*
X1339821Y850286D03*
X1341670Y847081D03*
X1343521Y850286D03*
X1345370Y847081D03*
X1347221Y856694D03*
Y863103D03*
X1332421Y856694D03*
Y863103D03*
X1334270Y853490D03*
Y859899D03*
Y866307D03*
X1336121Y856694D03*
Y863103D03*
X1337970Y853490D03*
Y859899D03*
Y866307D03*
X1339821Y856694D03*
Y863103D03*
X1341670Y853490D03*
Y859899D03*
Y866307D03*
X1343521Y856694D03*
Y863103D03*
X1345370Y853490D03*
Y859899D03*
Y866307D03*
X1347221Y869511D03*
X1332421D03*
X1334270Y872716D03*
X1336121Y869511D03*
X1337970Y872716D03*
X1339821Y869511D03*
X1341670Y872716D03*
X1343521Y869511D03*
X1345370Y872716D03*
X1347221Y875920D03*
Y882329D03*
X1332421Y875920D03*
Y882329D03*
X1334270Y879124D03*
X1336121Y875920D03*
Y882329D03*
X1337970Y879124D03*
X1339821Y875920D03*
Y882329D03*
X1341670Y879124D03*
X1343521Y875920D03*
Y882329D03*
X1345370Y879124D03*
X1347221Y888737D03*
Y895146D03*
Y901555D03*
X1332421Y888737D03*
Y895146D03*
Y901555D03*
X1334270Y885533D03*
Y891942D03*
Y898350D03*
X1336121Y888737D03*
Y895146D03*
Y901555D03*
X1337970Y885533D03*
Y891942D03*
Y898350D03*
X1339821Y888737D03*
Y895146D03*
Y901555D03*
X1341670Y885533D03*
Y891942D03*
Y898350D03*
X1343521Y888737D03*
Y895146D03*
Y901555D03*
X1345370Y885533D03*
Y891942D03*
Y898350D03*
X1347221Y907963D03*
Y914372D03*
X1332421Y907963D03*
Y914372D03*
X1334270Y904759D03*
Y911167D03*
Y917576D03*
X1336121Y907963D03*
Y914372D03*
X1337970Y904759D03*
Y911167D03*
Y917576D03*
X1339821Y907963D03*
Y914372D03*
X1341670Y904759D03*
Y911167D03*
Y917576D03*
X1343521Y907963D03*
Y914372D03*
X1345370Y904759D03*
Y911167D03*
Y917576D03*
X1347221Y920780D03*
Y927189D03*
X1332421Y920780D03*
Y927189D03*
Y933598D03*
X1334270Y923985D03*
Y930393D03*
X1336121Y920780D03*
Y927189D03*
Y933598D03*
X1337970Y923985D03*
Y930393D03*
X1339821Y920780D03*
Y927189D03*
Y933598D03*
X1341670Y923985D03*
Y930393D03*
X1343521Y920780D03*
Y927189D03*
Y933598D03*
X1345370Y923985D03*
Y930393D03*
X1347221Y933598D03*
Y940006D03*
Y946414D03*
X1332421Y940006D03*
Y946414D03*
X1334270Y936801D03*
Y943210D03*
Y949619D03*
X1336121Y940006D03*
Y946414D03*
X1337970Y936801D03*
Y943210D03*
Y949619D03*
X1339821Y940006D03*
Y946414D03*
X1341670Y936801D03*
Y943210D03*
Y949619D03*
X1343521Y940006D03*
Y946414D03*
X1345370Y936801D03*
Y943210D03*
Y949619D03*
X1347221Y952823D03*
Y959232D03*
X1332421Y952823D03*
Y959232D03*
X1334270Y956027D03*
Y962436D03*
X1336121Y952823D03*
Y959232D03*
X1337970Y956027D03*
Y962436D03*
X1339821Y952823D03*
Y959232D03*
X1341670Y956027D03*
Y962436D03*
X1343521Y952823D03*
Y959232D03*
X1345370Y956027D03*
Y962436D03*
X1347221Y965640D03*
X1332421D03*
X1336121D03*
X1339821D03*
X1343521D03*
X1347221Y972049D03*
Y978457D03*
X1332421Y972049D03*
Y978457D03*
X1334270Y968845D03*
Y975253D03*
Y981662D03*
X1336121Y972049D03*
Y978457D03*
X1337970Y968845D03*
Y975253D03*
Y981662D03*
X1339821Y972049D03*
Y978457D03*
X1341670Y968845D03*
Y975253D03*
Y981662D03*
X1343521Y972049D03*
Y978457D03*
X1345370Y968845D03*
Y975253D03*
Y981662D03*
X1347221Y984866D03*
X1332421D03*
X1336121D03*
X1339821D03*
X1343521D03*
X1334703Y997574D03*
X1338403D03*
X1342103D03*
X1345803D03*
X1332854Y1000778D03*
Y1007187D03*
Y1013595D03*
X1334703Y1003983D03*
Y1010391D03*
X1336554Y1000778D03*
Y1007187D03*
Y1013595D03*
X1338403Y1003983D03*
Y1010391D03*
X1340254Y1000778D03*
Y1007187D03*
Y1013595D03*
X1342103Y1003983D03*
Y1010391D03*
X1343954Y1000778D03*
Y1007187D03*
Y1013595D03*
X1345803Y1003983D03*
Y1010391D03*
X1343953Y1002888D03*
X1347653D03*
X1332854Y1020004D03*
X1334703Y1016800D03*
Y1023208D03*
X1336554Y1020004D03*
X1338403Y1016800D03*
Y1023208D03*
X1340254Y1020004D03*
X1342103Y1016800D03*
Y1023208D03*
X1343954Y1020004D03*
X1345803Y1016800D03*
Y1023208D03*
X1332854Y1026413D03*
X1334703Y1029617D03*
X1336554Y1026413D03*
X1338403Y1029617D03*
X1340254Y1026413D03*
X1342103Y1029617D03*
X1343954Y1026413D03*
X1345803Y1029617D03*
X1332854Y1032821D03*
Y1039230D03*
Y1045639D03*
X1334703Y1036026D03*
Y1042434D03*
X1336554Y1032821D03*
Y1039230D03*
Y1045639D03*
X1338403Y1036026D03*
Y1042434D03*
X1340254Y1032821D03*
Y1039230D03*
Y1045639D03*
X1342103Y1036026D03*
Y1042434D03*
X1343954Y1032821D03*
Y1039230D03*
Y1045639D03*
X1345803Y1036026D03*
Y1042434D03*
X1332854Y1052047D03*
X1334703Y1048842D03*
X1336554Y1052047D03*
X1338403Y1048842D03*
X1340254Y1052047D03*
X1342103Y1048842D03*
X1343954Y1052047D03*
X1345803Y1048842D03*
X1332854Y1058455D03*
X1334703Y1055251D03*
Y1061660D03*
X1336554Y1058455D03*
X1338403Y1055251D03*
Y1061660D03*
X1340254Y1058455D03*
X1342103Y1055251D03*
Y1061660D03*
X1343954Y1058455D03*
X1345803Y1055251D03*
Y1061660D03*
X1332854Y1064864D03*
Y1071273D03*
Y1077681D03*
X1334703Y1068068D03*
Y1074477D03*
X1336554Y1064864D03*
Y1071273D03*
Y1077681D03*
X1338403Y1068068D03*
Y1074477D03*
X1340254Y1064864D03*
Y1071273D03*
Y1077681D03*
X1342103Y1068068D03*
Y1074477D03*
X1343954Y1064864D03*
Y1071273D03*
Y1077681D03*
X1345803Y1068068D03*
Y1074477D03*
X1334703Y1080885D03*
X1338403D03*
X1342103D03*
X1345803D03*
X1332854Y1084090D03*
Y1090498D03*
X1334703Y1087294D03*
Y1093703D03*
X1336554Y1084090D03*
Y1090498D03*
X1338403Y1087294D03*
Y1093703D03*
X1340254Y1084090D03*
Y1090498D03*
X1342103Y1087294D03*
Y1093703D03*
X1343954Y1084090D03*
Y1090498D03*
X1345803Y1087294D03*
Y1093703D03*
X1332854Y1096907D03*
Y1103316D03*
Y1109724D03*
X1334703Y1100111D03*
Y1106520D03*
Y1112929D03*
X1336554Y1096907D03*
Y1103316D03*
Y1109724D03*
X1338403Y1100111D03*
Y1106520D03*
Y1112929D03*
X1340254Y1096907D03*
Y1103316D03*
Y1109724D03*
X1342103Y1100111D03*
Y1106520D03*
Y1112929D03*
X1343954Y1096907D03*
Y1103316D03*
Y1109724D03*
X1345803Y1100111D03*
Y1106520D03*
Y1112929D03*
X1332854Y1116133D03*
Y1122541D03*
Y1128950D03*
X1334703Y1119337D03*
Y1125746D03*
X1336554Y1116133D03*
Y1122541D03*
Y1128950D03*
X1338403Y1119337D03*
Y1125746D03*
X1340254Y1116133D03*
Y1122541D03*
Y1128950D03*
X1342103Y1119337D03*
Y1125746D03*
X1343954Y1116133D03*
Y1122541D03*
Y1128950D03*
X1345803Y1119337D03*
Y1125746D03*
X1334703Y1132154D03*
X1336554Y1135359D03*
X1338403Y1132154D03*
X1340254Y1135359D03*
X1342103Y1132154D03*
X1343954Y1135359D03*
X1345803Y1132154D03*
X1352770Y847081D03*
X1354621Y850286D03*
X1356470Y847081D03*
X1358321Y850286D03*
X1360170Y847081D03*
X1362021Y850286D03*
X1349070Y847081D03*
X1350921Y850286D03*
X1352770Y853490D03*
Y859899D03*
Y866307D03*
X1354621Y856694D03*
Y863103D03*
X1356470Y853490D03*
Y859899D03*
Y866307D03*
X1358321Y856694D03*
Y863103D03*
X1360170Y853490D03*
Y859899D03*
Y866307D03*
X1362021Y856694D03*
Y863103D03*
X1349070Y853490D03*
Y859899D03*
Y866307D03*
X1350921Y856694D03*
Y863103D03*
X1352770Y872716D03*
X1354621Y869511D03*
X1356470Y872716D03*
X1358321Y869511D03*
X1360170Y872716D03*
X1362021Y869511D03*
X1349070Y872716D03*
X1350921Y869511D03*
X1352770Y879124D03*
X1354621Y875920D03*
Y882329D03*
X1356470Y879124D03*
X1358321Y875920D03*
Y882329D03*
X1360170Y879124D03*
X1362021Y875920D03*
Y882329D03*
X1349070Y879124D03*
X1350921Y875920D03*
Y882329D03*
X1352770Y885533D03*
Y891942D03*
Y898350D03*
X1354621Y888737D03*
Y895146D03*
Y901555D03*
X1356470Y885533D03*
Y891942D03*
Y898350D03*
X1358321Y888737D03*
Y895146D03*
Y901555D03*
X1360170Y885533D03*
Y891942D03*
Y898350D03*
X1362021Y888737D03*
Y895146D03*
Y901555D03*
X1349070Y885533D03*
Y891942D03*
Y898350D03*
X1350921Y888737D03*
Y895146D03*
Y901555D03*
X1352770Y904759D03*
Y911167D03*
Y917576D03*
X1354621Y907963D03*
Y914372D03*
X1356470Y904759D03*
Y911167D03*
Y917576D03*
X1358321Y907963D03*
Y914372D03*
X1360170Y904759D03*
Y911167D03*
Y917576D03*
X1362021Y907963D03*
Y914372D03*
X1349070Y904759D03*
Y911167D03*
Y917576D03*
X1350921Y907963D03*
Y914372D03*
X1352770Y923985D03*
Y930393D03*
X1354621Y920780D03*
Y927189D03*
X1356470Y923985D03*
Y930393D03*
X1358321Y920780D03*
Y927189D03*
X1360170Y923985D03*
Y930393D03*
X1362021Y920780D03*
Y927189D03*
X1349070Y923985D03*
Y930393D03*
X1350921Y920780D03*
Y927189D03*
X1354621Y933598D03*
X1358321D03*
X1362021D03*
X1350921D03*
X1352770Y936801D03*
Y943210D03*
Y949619D03*
X1354621Y940006D03*
Y946414D03*
X1356470Y936801D03*
Y943210D03*
Y949619D03*
X1358321Y940006D03*
Y946414D03*
X1360170Y936801D03*
Y943210D03*
Y949619D03*
X1362021Y940006D03*
Y946414D03*
X1349070Y936801D03*
Y943210D03*
Y949619D03*
X1350921Y940006D03*
Y946414D03*
X1352770Y956027D03*
Y962436D03*
X1354621Y952823D03*
Y959232D03*
X1356470Y956027D03*
Y962436D03*
X1358321Y952823D03*
Y959232D03*
X1360170Y956027D03*
Y962436D03*
X1362021Y952823D03*
Y959232D03*
X1349070Y956027D03*
Y962436D03*
X1350921Y952823D03*
Y959232D03*
X1354621Y965640D03*
X1358321D03*
X1362021D03*
X1350921D03*
X1352770Y968845D03*
Y975253D03*
Y981662D03*
X1354621Y972049D03*
Y978457D03*
X1356470Y968845D03*
Y975253D03*
Y981662D03*
X1358321Y972049D03*
Y978457D03*
X1360170Y968845D03*
Y975253D03*
Y981662D03*
X1362021Y972049D03*
Y978457D03*
X1349070Y968845D03*
Y975253D03*
Y981662D03*
X1350921Y972049D03*
Y978457D03*
X1354621Y984866D03*
X1358321D03*
X1362021D03*
X1350921D03*
X1353203Y997574D03*
X1356903D03*
X1360603D03*
X1349503D03*
X1353203Y1003983D03*
Y1010391D03*
X1355054Y1000778D03*
Y1007187D03*
Y1013595D03*
X1356903Y1003983D03*
Y1010391D03*
X1358754Y1000778D03*
Y1007187D03*
Y1013595D03*
X1360603Y1003983D03*
Y1010391D03*
X1362454Y1000778D03*
Y1007187D03*
Y1013595D03*
X1347654Y1000778D03*
Y1007187D03*
Y1013595D03*
X1349503Y1003983D03*
Y1010391D03*
X1351354Y1000778D03*
Y1007187D03*
Y1013595D03*
X1353203Y1016800D03*
X1355054Y1020004D03*
X1356903Y1016800D03*
X1358754Y1020004D03*
X1360603Y1016800D03*
X1362454Y1020004D03*
X1347654D03*
X1349503Y1016800D03*
X1351354Y1020004D03*
X1353203Y1023208D03*
Y1029617D03*
X1355054Y1026413D03*
X1356903Y1023208D03*
Y1029617D03*
X1358754Y1026413D03*
X1360603Y1023208D03*
Y1029617D03*
X1362454Y1026413D03*
X1347654D03*
X1349503Y1023208D03*
Y1029617D03*
X1351354Y1026413D03*
X1353203Y1036026D03*
Y1042434D03*
X1355054Y1032821D03*
Y1039230D03*
Y1045639D03*
X1356903Y1036026D03*
Y1042434D03*
X1358754Y1032821D03*
Y1039230D03*
Y1045639D03*
X1360603Y1036026D03*
Y1042434D03*
X1362454Y1032821D03*
Y1039230D03*
Y1045639D03*
X1347654Y1032821D03*
Y1039230D03*
Y1045639D03*
X1349503Y1036026D03*
Y1042434D03*
X1351354Y1032821D03*
Y1039230D03*
Y1045639D03*
X1353203Y1048842D03*
X1355054Y1052047D03*
X1356903Y1048842D03*
X1358754Y1052047D03*
X1360603Y1048842D03*
X1362454Y1052047D03*
X1347654D03*
X1349503Y1048842D03*
X1351354Y1052047D03*
X1353203Y1055251D03*
Y1061660D03*
X1355054Y1058455D03*
X1356903Y1055251D03*
Y1061660D03*
X1358754Y1058455D03*
X1360603Y1055251D03*
Y1061660D03*
X1362454Y1058455D03*
X1347654D03*
X1349503Y1055251D03*
Y1061660D03*
X1351354Y1058455D03*
X1353203Y1068068D03*
Y1074477D03*
X1355054Y1064864D03*
Y1071273D03*
Y1077681D03*
X1356903Y1068068D03*
Y1074477D03*
X1358754Y1064864D03*
Y1071273D03*
Y1077681D03*
X1360603Y1068068D03*
Y1074477D03*
X1362454Y1064864D03*
Y1071273D03*
Y1077681D03*
X1347654Y1064864D03*
Y1071273D03*
Y1077681D03*
X1349503Y1068068D03*
Y1074477D03*
X1351354Y1064864D03*
Y1071273D03*
Y1077681D03*
X1353203Y1080885D03*
X1356903D03*
X1360603D03*
X1349503D03*
X1353203Y1087294D03*
Y1093703D03*
X1355054Y1084090D03*
Y1090498D03*
X1356903Y1087294D03*
Y1093703D03*
X1358754Y1084090D03*
Y1090498D03*
X1360603Y1087294D03*
Y1093703D03*
X1362454Y1084090D03*
Y1090498D03*
X1347654Y1084090D03*
Y1090498D03*
X1349503Y1087294D03*
Y1093703D03*
X1351354Y1084090D03*
Y1090498D03*
X1353203Y1100111D03*
Y1106520D03*
X1355054Y1096907D03*
Y1103316D03*
Y1109724D03*
X1356903Y1100111D03*
Y1106520D03*
X1358754Y1096907D03*
Y1103316D03*
Y1109724D03*
X1360603Y1100111D03*
Y1106520D03*
X1362454Y1096907D03*
Y1103316D03*
Y1109724D03*
X1347654Y1096907D03*
Y1103316D03*
Y1109724D03*
X1349503Y1100111D03*
Y1106520D03*
X1351354Y1096907D03*
Y1103316D03*
Y1109724D03*
X1353203Y1112929D03*
X1356903D03*
X1360603D03*
X1349503D03*
X1353203Y1119337D03*
Y1125746D03*
X1355054Y1116133D03*
Y1122541D03*
Y1128950D03*
X1356903Y1119337D03*
Y1125746D03*
X1358754Y1116133D03*
Y1122541D03*
Y1128950D03*
X1360603Y1119337D03*
Y1125746D03*
X1362454Y1116133D03*
Y1122541D03*
Y1128950D03*
X1347654Y1116133D03*
Y1122541D03*
Y1128950D03*
X1349503Y1119337D03*
Y1125746D03*
X1351354Y1116133D03*
Y1122541D03*
Y1128950D03*
X1353203Y1132154D03*
X1355054Y1135359D03*
X1356903Y1132154D03*
X1358754Y1135359D03*
X1360603Y1132154D03*
X1362454Y1135359D03*
X1347654D03*
X1349503Y1132154D03*
X1351354Y1135359D03*
X1363870Y847081D03*
X1365721Y850286D03*
X1367570Y847081D03*
X1369421Y850286D03*
X1371270Y847081D03*
X1373121Y850286D03*
X1374970Y847081D03*
X1376821Y850286D03*
X1378670Y847081D03*
X1363870Y853490D03*
Y859899D03*
Y866307D03*
X1365721Y856694D03*
Y863103D03*
X1367570Y853490D03*
Y859899D03*
Y866307D03*
X1369421Y856694D03*
Y863103D03*
X1371270Y853490D03*
Y859899D03*
Y866307D03*
X1373121Y856694D03*
Y863103D03*
X1374970Y853490D03*
Y859899D03*
Y866307D03*
X1376821Y856694D03*
Y863103D03*
X1378670Y853490D03*
Y859899D03*
Y866307D03*
X1363870Y872716D03*
X1365721Y869511D03*
X1367570Y872716D03*
X1369421Y869511D03*
X1371270Y872716D03*
X1373121Y869511D03*
X1374970Y872716D03*
X1376821Y869511D03*
X1378670Y872716D03*
X1363870Y879124D03*
X1365721Y875920D03*
Y882329D03*
X1367570Y879124D03*
X1369421Y875920D03*
Y882329D03*
X1371270Y879124D03*
X1373121Y875920D03*
Y882329D03*
X1374970Y879124D03*
X1376821Y875920D03*
Y882329D03*
X1378670Y879124D03*
X1363870Y885533D03*
Y891942D03*
Y898350D03*
X1365721Y888737D03*
Y895146D03*
Y901555D03*
X1367570Y885533D03*
Y891942D03*
Y898350D03*
X1369421Y888737D03*
Y895146D03*
Y901555D03*
X1371270Y885533D03*
Y891942D03*
Y898350D03*
X1373121Y888737D03*
Y895146D03*
Y901555D03*
X1374970Y885533D03*
Y891942D03*
Y898350D03*
X1376821Y888737D03*
Y895146D03*
Y901555D03*
X1378670Y885533D03*
Y891942D03*
Y898350D03*
X1363870Y904759D03*
Y911167D03*
Y917576D03*
X1365721Y907963D03*
Y914372D03*
X1367570Y904759D03*
Y911167D03*
Y917576D03*
X1369421Y907963D03*
Y914372D03*
X1371270Y904759D03*
Y911167D03*
Y917576D03*
X1373121Y907963D03*
Y914372D03*
X1374970Y904759D03*
Y911167D03*
Y917576D03*
X1376821Y907963D03*
Y914372D03*
X1378670Y904759D03*
Y911167D03*
Y917576D03*
X1363870Y923985D03*
Y930393D03*
X1365721Y920780D03*
Y927189D03*
X1367570Y923985D03*
Y930393D03*
X1369421Y920780D03*
Y927189D03*
X1371270Y923985D03*
Y930393D03*
X1373121Y920780D03*
Y927189D03*
X1374970Y923985D03*
Y930393D03*
X1376821Y920780D03*
Y927189D03*
X1378670Y923985D03*
Y930393D03*
X1365721Y933598D03*
X1369421D03*
X1373121D03*
X1376821D03*
X1363870Y936801D03*
Y943210D03*
Y949619D03*
X1365721Y940006D03*
Y946414D03*
X1367570Y936801D03*
Y943210D03*
Y949619D03*
X1369421Y940006D03*
Y946414D03*
X1371270Y936801D03*
Y943210D03*
Y949619D03*
X1373121Y940006D03*
Y946414D03*
X1374970Y936801D03*
Y943210D03*
Y949619D03*
X1376821Y940006D03*
Y946414D03*
X1378670Y936801D03*
Y943210D03*
Y949619D03*
X1363870Y956027D03*
Y962436D03*
X1365721Y952823D03*
Y959232D03*
X1367570Y956027D03*
Y962436D03*
X1369421Y952823D03*
Y959232D03*
X1371270Y956027D03*
Y962436D03*
X1373121Y952823D03*
Y959232D03*
X1374970Y956027D03*
Y962436D03*
X1376821Y952823D03*
Y959232D03*
X1378670Y956027D03*
Y962436D03*
X1365721Y965640D03*
X1369421D03*
X1373121D03*
X1376821D03*
X1363870Y968845D03*
Y975253D03*
Y981662D03*
X1365721Y972049D03*
Y978457D03*
X1367570Y968845D03*
Y975253D03*
Y981662D03*
X1369421Y972049D03*
Y978457D03*
X1371270Y968845D03*
Y975253D03*
Y981662D03*
X1373121Y972049D03*
Y978457D03*
X1374970Y968845D03*
Y975253D03*
Y981662D03*
X1376821Y972049D03*
Y978457D03*
X1378670Y968845D03*
Y975253D03*
Y981662D03*
X1365721Y984866D03*
X1369421D03*
X1373121D03*
X1376821D03*
X1364303Y997574D03*
X1368003D03*
X1371703D03*
X1375403D03*
X1379103D03*
X1364303Y1003983D03*
Y1010391D03*
X1366154Y1000778D03*
Y1007187D03*
Y1013595D03*
X1368003Y1003983D03*
Y1010391D03*
X1369854Y1000778D03*
Y1007187D03*
Y1013595D03*
X1371703Y1003983D03*
Y1010391D03*
X1373554Y1000778D03*
Y1007187D03*
Y1013595D03*
X1375403Y1003983D03*
Y1010391D03*
X1377254Y1000778D03*
Y1007187D03*
Y1013595D03*
X1379103Y1003983D03*
Y1010391D03*
X1364303Y1016800D03*
X1366154Y1020004D03*
X1368003Y1016800D03*
X1369854Y1020004D03*
X1371703Y1016800D03*
X1373554Y1020004D03*
X1375403Y1016800D03*
X1377254Y1020004D03*
X1379103Y1016800D03*
X1364303Y1023208D03*
Y1029617D03*
X1366154Y1026413D03*
X1368003Y1023208D03*
Y1029617D03*
X1369854Y1026413D03*
X1371703Y1023208D03*
Y1029617D03*
X1373554Y1026413D03*
X1375403Y1023208D03*
Y1029617D03*
X1377254Y1026413D03*
X1379103Y1023208D03*
Y1029617D03*
X1364303Y1036026D03*
Y1042434D03*
X1366154Y1032821D03*
Y1039230D03*
Y1045639D03*
X1368003Y1036026D03*
Y1042434D03*
X1369854Y1032821D03*
Y1039230D03*
Y1045639D03*
X1371703Y1036026D03*
Y1042434D03*
X1373554Y1032821D03*
Y1039230D03*
Y1045639D03*
X1375403Y1036026D03*
Y1042434D03*
X1377254Y1032821D03*
Y1039230D03*
Y1045639D03*
X1379103Y1036026D03*
Y1042434D03*
X1364303Y1048842D03*
X1366154Y1052047D03*
X1368003Y1048842D03*
X1369854Y1052047D03*
X1371703Y1048842D03*
X1373554Y1052047D03*
X1375403Y1048842D03*
X1377254Y1052047D03*
X1379103Y1048842D03*
X1364303Y1055251D03*
Y1061660D03*
X1366154Y1058455D03*
X1368003Y1055251D03*
Y1061660D03*
X1369854Y1058455D03*
X1371703Y1055251D03*
Y1061660D03*
X1373554Y1058455D03*
X1375403Y1055251D03*
Y1061660D03*
X1377254Y1058455D03*
X1379103Y1055251D03*
Y1061660D03*
X1364303Y1068068D03*
Y1074477D03*
X1366154Y1064864D03*
Y1071273D03*
Y1077681D03*
X1368003Y1068068D03*
Y1074477D03*
X1369854Y1064864D03*
Y1071273D03*
Y1077681D03*
X1371703Y1068068D03*
Y1074477D03*
X1373554Y1064864D03*
Y1071273D03*
Y1077681D03*
X1375403Y1068068D03*
Y1074477D03*
X1377254Y1064864D03*
Y1071273D03*
Y1077681D03*
X1379103Y1068068D03*
Y1074477D03*
X1364303Y1080885D03*
X1368003D03*
X1371703D03*
X1375403D03*
X1379103D03*
X1364303Y1087294D03*
Y1093703D03*
X1366154Y1084090D03*
Y1090498D03*
X1368003Y1087294D03*
Y1093703D03*
X1369854Y1084090D03*
Y1090498D03*
X1371703Y1087294D03*
Y1093703D03*
X1373554Y1084090D03*
Y1090498D03*
X1375403Y1087294D03*
Y1093703D03*
X1377254Y1084090D03*
Y1090498D03*
X1379103Y1087294D03*
Y1093703D03*
X1364303Y1100111D03*
Y1106520D03*
X1366154Y1096907D03*
Y1103316D03*
Y1109724D03*
X1368003Y1100111D03*
Y1106520D03*
X1369854Y1096907D03*
Y1103316D03*
Y1109724D03*
X1371703Y1100111D03*
Y1106520D03*
X1373554Y1096907D03*
Y1103316D03*
Y1109724D03*
X1375403Y1100111D03*
Y1106520D03*
X1377254Y1096907D03*
Y1103316D03*
Y1109724D03*
X1379103Y1100111D03*
Y1106520D03*
X1364303Y1112929D03*
X1368003D03*
X1371703D03*
X1375403D03*
X1379103D03*
X1364303Y1119337D03*
Y1125746D03*
X1366154Y1116133D03*
Y1122541D03*
Y1128950D03*
X1368003Y1119337D03*
Y1125746D03*
X1369854Y1116133D03*
Y1122541D03*
Y1128950D03*
X1371703Y1119337D03*
Y1125746D03*
X1373554Y1116133D03*
Y1122541D03*
Y1128950D03*
X1375403Y1119337D03*
Y1125746D03*
X1377254Y1116133D03*
Y1122541D03*
Y1128950D03*
X1379103Y1119337D03*
Y1125746D03*
X1364303Y1132154D03*
X1366154Y1135359D03*
X1368003Y1132154D03*
X1369854Y1135359D03*
X1371703Y1132154D03*
X1373554Y1135359D03*
X1375403Y1132154D03*
X1377254Y1135359D03*
X1379103Y1132154D03*
X1382370Y847081D03*
X1384221Y850286D03*
X1386070Y847081D03*
X1387921Y850286D03*
X1389770Y847081D03*
X1391621Y850286D03*
X1393470Y847081D03*
X1395321Y850286D03*
X1380521D03*
X1382370Y853490D03*
Y859899D03*
Y866307D03*
X1384221Y856694D03*
Y863103D03*
X1386070Y853490D03*
Y859899D03*
Y866307D03*
X1387921Y856694D03*
Y863103D03*
X1389770Y853490D03*
Y859899D03*
Y866307D03*
X1391621Y856694D03*
Y863103D03*
X1393470Y853490D03*
Y859899D03*
Y866307D03*
X1395321Y856694D03*
Y863103D03*
X1380521Y856694D03*
Y863103D03*
X1382370Y872716D03*
X1384221Y869511D03*
X1386070Y872716D03*
X1387921Y869511D03*
X1389770Y872716D03*
X1391621Y869511D03*
X1393470Y872716D03*
X1395321Y869511D03*
X1380521D03*
X1382370Y879124D03*
X1384221Y875920D03*
Y882329D03*
X1386070Y879124D03*
X1387921Y875920D03*
Y882329D03*
X1389770Y879124D03*
X1391621Y875920D03*
Y882329D03*
X1393470Y879124D03*
X1395321Y875920D03*
Y882329D03*
X1380521Y875920D03*
Y882329D03*
X1382370Y885533D03*
Y891942D03*
Y898350D03*
X1384221Y888737D03*
Y895146D03*
Y901555D03*
X1386070Y885533D03*
Y891942D03*
Y898350D03*
X1387921Y888737D03*
Y895146D03*
Y901555D03*
X1389770Y885533D03*
Y891942D03*
Y898350D03*
X1391621Y888737D03*
Y895146D03*
Y901555D03*
X1393470Y885533D03*
Y891942D03*
Y898350D03*
X1395321Y888737D03*
Y895146D03*
Y901555D03*
X1380521Y888737D03*
Y895146D03*
Y901555D03*
X1382370Y904759D03*
Y911167D03*
Y917576D03*
X1384221Y907963D03*
Y914372D03*
X1386070Y904759D03*
Y911167D03*
Y917576D03*
X1387921Y907963D03*
Y914372D03*
X1389770Y904759D03*
Y911167D03*
Y917576D03*
X1391621Y907963D03*
Y914372D03*
X1393470Y904759D03*
Y911167D03*
Y917576D03*
X1395321Y907963D03*
Y914372D03*
X1380521Y907963D03*
Y914372D03*
X1382370Y923985D03*
X1384221Y920780D03*
X1386070Y923985D03*
X1387921Y920780D03*
X1389770Y923985D03*
X1391621Y920780D03*
X1393470Y923985D03*
X1395321Y920780D03*
X1380521D03*
X1382803Y1042434D03*
X1384654Y1039230D03*
Y1045639D03*
X1386503Y1042434D03*
X1388354Y1039230D03*
Y1045639D03*
X1390203Y1042434D03*
X1392054Y1039230D03*
Y1045639D03*
X1393903Y1042434D03*
X1395754Y1039230D03*
Y1045639D03*
X1380954Y1039230D03*
Y1045639D03*
X1382803Y1048842D03*
X1384654Y1052047D03*
X1386503Y1048842D03*
X1388354Y1052047D03*
X1390203Y1048842D03*
X1392054Y1052047D03*
X1393903Y1048842D03*
X1395754Y1052047D03*
X1380954D03*
X1382803Y1055251D03*
Y1061660D03*
X1384654Y1058455D03*
X1386503Y1055251D03*
Y1061660D03*
X1388354Y1058455D03*
X1390203Y1055251D03*
Y1061660D03*
X1392054Y1058455D03*
X1393903Y1055251D03*
Y1061660D03*
X1395754Y1058455D03*
X1380954D03*
X1382803Y1068068D03*
Y1074477D03*
X1384654Y1064864D03*
Y1071273D03*
Y1077681D03*
X1386503Y1068068D03*
Y1074477D03*
X1388354Y1064864D03*
Y1071273D03*
Y1077681D03*
X1390203Y1068068D03*
Y1074477D03*
X1392054Y1064864D03*
Y1071273D03*
Y1077681D03*
X1393903Y1068068D03*
Y1074477D03*
X1395754Y1064864D03*
Y1071273D03*
Y1077681D03*
X1380954Y1064864D03*
Y1071273D03*
Y1077681D03*
X1382803Y1080885D03*
X1386503D03*
X1390203D03*
X1393903D03*
X1382803Y1087294D03*
Y1093703D03*
X1384654Y1084090D03*
Y1090498D03*
X1386503Y1087294D03*
Y1093703D03*
X1388354Y1084090D03*
Y1090498D03*
X1390203Y1087294D03*
Y1093703D03*
X1392054Y1084090D03*
Y1090498D03*
X1393903Y1087294D03*
Y1093703D03*
X1395754Y1084090D03*
Y1090498D03*
X1380954Y1084090D03*
Y1090498D03*
X1382803Y1100111D03*
Y1106520D03*
X1384654Y1096907D03*
Y1103316D03*
Y1109724D03*
X1386503Y1100111D03*
Y1106520D03*
X1388354Y1096907D03*
Y1103316D03*
Y1109724D03*
X1390203Y1100111D03*
Y1106520D03*
X1392054Y1096907D03*
Y1103316D03*
Y1109724D03*
X1393903Y1100111D03*
Y1106520D03*
X1395754Y1096907D03*
Y1103316D03*
Y1109724D03*
X1380954Y1096907D03*
Y1103316D03*
Y1109724D03*
X1382803Y1112929D03*
X1386503D03*
X1390203D03*
X1393903D03*
X1382803Y1119337D03*
Y1125746D03*
X1384654Y1116133D03*
Y1122541D03*
Y1128950D03*
X1386503Y1119337D03*
Y1125746D03*
X1388354Y1116133D03*
Y1122541D03*
Y1128950D03*
X1390203Y1119337D03*
Y1125746D03*
X1392054Y1116133D03*
Y1122541D03*
Y1128950D03*
X1393903Y1119337D03*
Y1125746D03*
X1395754Y1116133D03*
Y1122541D03*
Y1128950D03*
X1380954Y1116133D03*
Y1122541D03*
Y1128950D03*
X1382803Y1132154D03*
X1384654Y1135359D03*
X1386503Y1132154D03*
X1388354Y1135359D03*
X1390203Y1132154D03*
X1392054Y1135359D03*
X1393903Y1132154D03*
X1395754Y1135359D03*
X1380954D03*
X1397170Y847081D03*
X1399021Y850286D03*
X1400870Y847081D03*
X1402721Y850286D03*
X1406421D03*
X1410121D03*
X1397170Y853490D03*
Y859899D03*
Y866307D03*
X1399021Y856694D03*
Y863103D03*
X1400870Y853490D03*
Y859899D03*
Y866307D03*
X1402721Y856694D03*
Y863103D03*
X1404570Y853490D03*
Y859899D03*
Y866307D03*
X1406421Y856694D03*
Y863103D03*
X1408270Y853490D03*
Y859899D03*
Y866307D03*
X1410121Y856694D03*
Y863103D03*
X1411971Y853490D03*
Y859899D03*
Y866307D03*
X1397170Y872716D03*
X1399021Y869511D03*
X1400870Y872716D03*
X1402721Y869511D03*
X1404570Y872716D03*
X1406421Y869511D03*
X1408270Y872716D03*
X1410121Y869511D03*
X1411971Y872716D03*
X1397170Y879124D03*
X1399021Y875920D03*
Y882329D03*
X1400870Y879124D03*
X1402721Y875920D03*
Y882329D03*
X1404570Y879124D03*
X1406421Y875920D03*
Y882329D03*
X1408270Y879124D03*
X1410121Y875920D03*
Y882329D03*
X1411971Y879124D03*
X1397170Y885533D03*
Y891942D03*
Y898350D03*
X1399021Y888737D03*
Y895146D03*
Y901555D03*
X1400870Y885533D03*
Y891942D03*
Y898350D03*
X1402721Y888737D03*
Y895146D03*
Y901555D03*
X1404570Y885533D03*
Y891942D03*
Y898350D03*
X1406421Y888737D03*
Y895146D03*
Y901555D03*
X1408270Y885533D03*
Y891942D03*
Y898350D03*
X1410121Y888737D03*
Y895146D03*
Y901555D03*
X1411971Y885533D03*
Y891942D03*
Y898350D03*
Y904759D03*
X1397170D03*
Y911167D03*
Y917576D03*
X1399021Y907963D03*
Y914372D03*
X1400870Y904759D03*
Y911167D03*
Y917576D03*
X1402721Y907963D03*
Y914372D03*
X1404570Y904759D03*
Y911167D03*
Y917576D03*
X1406421Y907963D03*
Y914372D03*
X1408270Y904759D03*
Y911167D03*
Y917576D03*
X1410121Y907963D03*
Y914372D03*
X1411971Y911167D03*
Y917576D03*
X1397170Y923985D03*
X1399021Y920780D03*
X1400870Y923985D03*
X1402721Y920780D03*
X1404570Y923985D03*
X1406421Y920780D03*
Y927189D03*
X1408270Y923985D03*
Y930393D03*
X1410121Y920780D03*
Y927189D03*
X1411971Y923985D03*
Y930393D03*
X1406421Y933598D03*
X1410121D03*
X1406421Y940006D03*
Y946414D03*
X1408270Y936801D03*
Y943210D03*
Y949619D03*
X1410121Y940006D03*
Y946414D03*
X1411971Y936801D03*
Y943210D03*
Y949619D03*
X1406421Y952823D03*
Y959232D03*
X1408270Y956027D03*
Y962436D03*
X1410121Y952823D03*
Y959232D03*
X1411971Y956027D03*
Y962436D03*
X1406421Y965640D03*
X1410121D03*
X1406421Y972049D03*
Y978457D03*
X1408270Y968845D03*
Y975253D03*
Y981662D03*
X1410121Y972049D03*
Y978457D03*
X1411971Y968845D03*
Y975253D03*
Y981662D03*
X1406421Y984866D03*
X1410121D03*
X1412403Y997574D03*
X1408703D03*
X1412403Y1003983D03*
Y1010391D03*
X1406853Y1000778D03*
Y1007187D03*
Y1013595D03*
X1408703Y1003983D03*
Y1010391D03*
X1410554Y1000778D03*
Y1007187D03*
Y1013595D03*
X1412403Y1016800D03*
X1406853Y1020004D03*
X1408703Y1016800D03*
X1410554Y1020004D03*
X1412403Y1023208D03*
Y1029617D03*
X1406853Y1026413D03*
X1408703Y1023208D03*
Y1029617D03*
X1410554Y1026413D03*
X1412403Y1036026D03*
Y1042434D03*
X1397603D03*
X1399454Y1039230D03*
Y1045639D03*
X1401303Y1042434D03*
X1403154Y1039230D03*
Y1045639D03*
X1405003Y1042434D03*
X1406853Y1032821D03*
Y1039230D03*
Y1045639D03*
X1408703Y1036026D03*
Y1042434D03*
X1410554Y1032821D03*
Y1039230D03*
Y1045639D03*
X1412403Y1048842D03*
X1397603D03*
X1399454Y1052047D03*
X1401303Y1048842D03*
X1403154Y1052047D03*
X1405003Y1048842D03*
X1406853Y1052047D03*
X1408703Y1048842D03*
X1410554Y1052047D03*
X1412403Y1055251D03*
Y1061660D03*
X1397603Y1055251D03*
Y1061660D03*
X1399454Y1058455D03*
X1401303Y1055251D03*
Y1061660D03*
X1403154Y1058455D03*
X1405003Y1055251D03*
Y1061660D03*
X1406853Y1058455D03*
X1408703Y1055251D03*
Y1061660D03*
X1410554Y1058455D03*
X1412403Y1068068D03*
Y1074477D03*
X1397603Y1068068D03*
Y1074477D03*
X1399454Y1064864D03*
Y1071273D03*
Y1077681D03*
X1401303Y1068068D03*
Y1074477D03*
X1403154Y1064864D03*
Y1071273D03*
Y1077681D03*
X1405003Y1068068D03*
Y1074477D03*
X1406853Y1064864D03*
Y1071273D03*
Y1077681D03*
X1408703Y1068068D03*
Y1074477D03*
X1410554Y1064864D03*
Y1071273D03*
Y1077681D03*
X1412403Y1080885D03*
X1397603D03*
X1401303D03*
X1405003D03*
X1408703D03*
X1412403Y1087294D03*
Y1093703D03*
X1397603Y1087294D03*
Y1093703D03*
X1399454Y1084090D03*
Y1090498D03*
X1401303Y1087294D03*
Y1093703D03*
X1403154Y1084090D03*
Y1090498D03*
X1405003Y1087294D03*
Y1093703D03*
X1406853Y1084090D03*
Y1090498D03*
X1408703Y1087294D03*
Y1093703D03*
X1410554Y1084090D03*
Y1090498D03*
X1412403Y1100111D03*
Y1106520D03*
X1397603Y1100111D03*
Y1106520D03*
X1399454Y1096907D03*
Y1103316D03*
Y1109724D03*
X1401303Y1100111D03*
Y1106520D03*
X1403154Y1096907D03*
Y1103316D03*
Y1109724D03*
X1405003Y1100111D03*
Y1106520D03*
X1406853Y1096907D03*
Y1103316D03*
Y1109724D03*
X1408703Y1100111D03*
Y1106520D03*
X1410554Y1096907D03*
Y1103316D03*
Y1109724D03*
X1412403Y1112929D03*
X1397603D03*
X1401303D03*
X1405003D03*
X1408703D03*
X1412403Y1119337D03*
Y1125746D03*
X1397603Y1119337D03*
Y1125746D03*
X1399454Y1116133D03*
Y1122541D03*
Y1128950D03*
X1401303Y1119337D03*
Y1125746D03*
X1403154Y1116133D03*
Y1122541D03*
Y1128950D03*
X1405003Y1119337D03*
Y1125746D03*
X1406853Y1116133D03*
Y1122541D03*
Y1128950D03*
X1408703Y1119337D03*
Y1125746D03*
X1410554Y1116133D03*
Y1122541D03*
Y1128950D03*
X1412403Y1132154D03*
X1397603D03*
X1399454Y1135359D03*
X1401303Y1132154D03*
X1403154Y1135359D03*
X1405003Y1132154D03*
X1408703D03*
X1413821Y850286D03*
X1417521D03*
X1421221D03*
X1424921D03*
X1428621D03*
X1413821Y856694D03*
Y863103D03*
X1415670Y853490D03*
Y859899D03*
Y866307D03*
X1417521Y856694D03*
Y863103D03*
X1419370Y853490D03*
Y859899D03*
Y866307D03*
X1421221Y856694D03*
Y863103D03*
X1423070Y853490D03*
Y859899D03*
Y866307D03*
X1424921Y856694D03*
Y863103D03*
X1426771Y853490D03*
Y859899D03*
Y866307D03*
X1428621Y856694D03*
Y863103D03*
X1413821Y869511D03*
X1415670Y872716D03*
X1417521Y869511D03*
X1419370Y872716D03*
X1421221Y869511D03*
X1423070Y872716D03*
X1424921Y869511D03*
X1426771Y872716D03*
X1428621Y869511D03*
X1413821Y875920D03*
Y882329D03*
X1415670Y879124D03*
X1417521Y875920D03*
Y882329D03*
X1419370Y879124D03*
X1421221Y875920D03*
Y882329D03*
X1423070Y879124D03*
X1424921Y875920D03*
Y882329D03*
X1426771Y879124D03*
X1428621Y875920D03*
Y882329D03*
X1413821Y888737D03*
Y895146D03*
Y901555D03*
X1415670Y885533D03*
Y891942D03*
Y898350D03*
X1417521Y888737D03*
Y895146D03*
Y901555D03*
X1419370Y885533D03*
Y891942D03*
Y898350D03*
X1421221Y888737D03*
Y895146D03*
Y901555D03*
X1423070Y885533D03*
Y891942D03*
Y898350D03*
X1424921Y888737D03*
Y895146D03*
Y901555D03*
X1426771Y885533D03*
Y891942D03*
Y898350D03*
X1428621Y888737D03*
Y895146D03*
Y901555D03*
X1413821Y907963D03*
Y914372D03*
X1415670Y904759D03*
Y911167D03*
Y917576D03*
X1417521Y907963D03*
Y914372D03*
X1419370Y904759D03*
Y911167D03*
Y917576D03*
X1421221Y907963D03*
Y914372D03*
X1423070Y904759D03*
Y911167D03*
Y917576D03*
X1424921Y907963D03*
Y914372D03*
X1426771Y904759D03*
Y911167D03*
Y917576D03*
X1428621Y907963D03*
Y914372D03*
X1413821Y920780D03*
Y927189D03*
X1415670Y923985D03*
Y930393D03*
X1417521Y920780D03*
Y927189D03*
X1419370Y923985D03*
Y930393D03*
X1421221Y920780D03*
Y927189D03*
X1423070Y923985D03*
Y930393D03*
X1424921Y920780D03*
Y927189D03*
X1426771Y923985D03*
Y930393D03*
X1428621Y920780D03*
X1413821Y933598D03*
X1417521D03*
X1421221D03*
X1424921D03*
X1413821Y940006D03*
Y946414D03*
X1415670Y936801D03*
Y943210D03*
Y949619D03*
X1417521Y940006D03*
Y946414D03*
X1419370Y936801D03*
Y943210D03*
Y949619D03*
X1421221Y940006D03*
Y946414D03*
X1423070Y936801D03*
Y943210D03*
Y949619D03*
X1424921Y940006D03*
Y946414D03*
X1426771Y936801D03*
Y943210D03*
Y949619D03*
X1413821Y952823D03*
Y959232D03*
X1415670Y956027D03*
Y962436D03*
X1417521Y952823D03*
Y959232D03*
X1419370Y956027D03*
Y962436D03*
X1421221Y952823D03*
Y959232D03*
X1423070Y956027D03*
Y962436D03*
X1424921Y952823D03*
Y959232D03*
X1426771Y956027D03*
Y962436D03*
X1413821Y965640D03*
X1417521D03*
X1421221D03*
X1424921D03*
X1413821Y972049D03*
Y978457D03*
X1415670Y968845D03*
Y975253D03*
Y981662D03*
X1417521Y972049D03*
Y978457D03*
X1419370Y968845D03*
Y975253D03*
Y981662D03*
X1421221Y972049D03*
Y978457D03*
X1423070Y968845D03*
Y975253D03*
Y981662D03*
X1424921Y972049D03*
Y978457D03*
X1426771Y968845D03*
Y975253D03*
Y981662D03*
X1413821Y984866D03*
X1417521D03*
X1421221D03*
X1424921D03*
X1416103Y997574D03*
X1419803D03*
X1423503D03*
X1427203D03*
X1414254Y1000778D03*
Y1007187D03*
Y1013595D03*
X1416103Y1003983D03*
Y1010391D03*
X1417954Y1000778D03*
Y1007187D03*
Y1013595D03*
X1419803Y1003983D03*
Y1010391D03*
X1421653Y1000778D03*
Y1007187D03*
Y1013595D03*
X1423503Y1003983D03*
Y1010391D03*
X1425354Y1000778D03*
Y1007187D03*
Y1013595D03*
X1427203Y1003983D03*
Y1010391D03*
X1414254Y1020004D03*
X1416103Y1016800D03*
X1417954Y1020004D03*
X1419803Y1016800D03*
X1421653Y1020004D03*
X1423503Y1016800D03*
X1425354Y1020004D03*
X1427203Y1016800D03*
X1414254Y1026413D03*
X1416103Y1023208D03*
Y1029617D03*
X1417954Y1026413D03*
X1419803Y1023208D03*
Y1029617D03*
X1421653Y1026413D03*
X1423503Y1023208D03*
Y1029617D03*
X1425354Y1026413D03*
X1427203Y1023208D03*
Y1029617D03*
X1414254Y1032821D03*
Y1039230D03*
Y1045639D03*
X1416103Y1036026D03*
Y1042434D03*
X1417954Y1032821D03*
Y1039230D03*
Y1045639D03*
X1419803Y1036026D03*
Y1042434D03*
X1421653Y1032821D03*
Y1039230D03*
Y1045639D03*
X1423503Y1036026D03*
Y1042434D03*
X1425354Y1032821D03*
Y1039230D03*
Y1045639D03*
X1427203Y1036026D03*
Y1042434D03*
X1414254Y1052047D03*
X1416103Y1048842D03*
X1417954Y1052047D03*
X1419803Y1048842D03*
X1421653Y1052047D03*
X1423503Y1048842D03*
X1425354Y1052047D03*
X1427203Y1048842D03*
X1414254Y1058455D03*
X1416103Y1055251D03*
Y1061660D03*
X1417954Y1058455D03*
X1419803Y1055251D03*
Y1061660D03*
X1421653Y1058455D03*
X1423503Y1055251D03*
Y1061660D03*
X1425354Y1058455D03*
X1427203Y1055251D03*
Y1061660D03*
X1414254Y1064864D03*
Y1071273D03*
Y1077681D03*
X1416103Y1068068D03*
Y1074477D03*
X1417954Y1064864D03*
Y1071273D03*
Y1077681D03*
X1419803Y1068068D03*
Y1074477D03*
X1421653Y1064864D03*
Y1071273D03*
Y1077681D03*
X1423503Y1068068D03*
Y1074477D03*
X1425354Y1064864D03*
Y1071273D03*
Y1077681D03*
X1427203Y1068068D03*
Y1074477D03*
X1416103Y1080885D03*
X1419803D03*
X1423503D03*
X1427203D03*
X1414254Y1084090D03*
Y1090498D03*
X1416103Y1087294D03*
Y1093703D03*
X1417954Y1084090D03*
Y1090498D03*
X1419803Y1087294D03*
Y1093703D03*
X1421653Y1084090D03*
Y1090498D03*
X1423503Y1087294D03*
Y1093703D03*
X1425354Y1084090D03*
Y1090498D03*
X1427203Y1087294D03*
Y1093703D03*
X1414254Y1096907D03*
Y1103316D03*
Y1109724D03*
X1416103Y1100111D03*
Y1106520D03*
X1417954Y1096907D03*
Y1103316D03*
Y1109724D03*
X1419803Y1100111D03*
Y1106520D03*
X1421653Y1096907D03*
Y1103316D03*
Y1109724D03*
X1423503Y1100111D03*
Y1106520D03*
X1425354Y1096907D03*
Y1103316D03*
Y1109724D03*
X1427203Y1100111D03*
Y1106520D03*
X1416103Y1112929D03*
X1419803D03*
X1423503D03*
X1427203D03*
X1414254Y1116133D03*
Y1122541D03*
Y1128950D03*
X1416103Y1119337D03*
Y1125746D03*
X1417954Y1116133D03*
Y1122541D03*
Y1128950D03*
X1419803Y1119337D03*
Y1125746D03*
X1421653Y1116133D03*
Y1122541D03*
Y1128950D03*
X1423503Y1119337D03*
Y1125746D03*
X1425354Y1116133D03*
Y1122541D03*
Y1128950D03*
X1427203Y1119337D03*
Y1125746D03*
X1416103Y1132154D03*
X1419803D03*
X1423503D03*
X1427203D03*
X1443421Y850286D03*
X1430470Y847081D03*
X1432321Y850286D03*
X1434170Y847081D03*
X1436021Y850286D03*
X1437870Y847081D03*
X1439721Y850286D03*
X1441570Y847081D03*
X1443421Y856694D03*
Y863103D03*
X1430470Y853490D03*
Y859899D03*
Y866307D03*
X1432321Y856694D03*
Y863103D03*
X1434170Y853490D03*
Y859899D03*
Y866307D03*
X1436021Y856694D03*
Y863103D03*
X1437870Y853490D03*
Y859899D03*
Y866307D03*
X1439721Y856694D03*
Y863103D03*
X1441570Y853490D03*
Y859899D03*
Y866307D03*
X1443421Y869511D03*
X1430470Y872716D03*
X1432321Y869511D03*
X1434170Y872716D03*
X1436021Y869511D03*
X1437870Y872716D03*
X1439721Y869511D03*
X1441570Y872716D03*
X1443421Y875920D03*
Y882329D03*
X1430470Y879124D03*
X1432321Y875920D03*
Y882329D03*
X1434170Y879124D03*
X1436021Y875920D03*
Y882329D03*
X1437870Y879124D03*
X1439721Y875920D03*
Y882329D03*
X1441570Y879124D03*
X1443421Y888737D03*
Y895146D03*
Y901555D03*
X1430470Y885533D03*
Y891942D03*
Y898350D03*
X1432321Y888737D03*
Y895146D03*
Y901555D03*
X1434170Y885533D03*
Y891942D03*
Y898350D03*
X1436021Y888737D03*
Y895146D03*
Y901555D03*
X1437870Y885533D03*
Y891942D03*
Y898350D03*
X1439721Y888737D03*
Y895146D03*
Y901555D03*
X1441570Y885533D03*
Y891942D03*
Y898350D03*
X1443421Y907963D03*
Y914372D03*
X1430470Y904759D03*
Y911167D03*
Y917576D03*
X1432321Y907963D03*
Y914372D03*
X1434170Y904759D03*
Y911167D03*
Y917576D03*
X1436021Y907963D03*
Y914372D03*
X1437870Y904759D03*
Y911167D03*
Y917576D03*
X1439721Y907963D03*
Y914372D03*
X1441570Y904759D03*
Y911167D03*
Y917576D03*
X1443421Y920780D03*
X1430470Y923985D03*
X1432321Y920780D03*
X1434170Y923985D03*
X1436021Y920780D03*
X1437870Y923985D03*
X1439721Y920780D03*
X1441570Y923985D03*
X1443854Y1039230D03*
Y1045639D03*
X1429054Y1039230D03*
Y1045639D03*
X1430903Y1042434D03*
X1432754Y1039230D03*
Y1045639D03*
X1434603Y1042434D03*
X1436454Y1039230D03*
Y1045639D03*
X1438303Y1042434D03*
X1440154Y1039230D03*
Y1045639D03*
X1442003Y1042434D03*
X1443854Y1052047D03*
X1429054D03*
X1430903Y1048842D03*
X1432754Y1052047D03*
X1434603Y1048842D03*
X1436454Y1052047D03*
X1438303Y1048842D03*
X1440154Y1052047D03*
X1442003Y1048842D03*
Y1055251D03*
X1443854Y1058455D03*
X1429054D03*
X1430903Y1055251D03*
Y1061660D03*
X1432754Y1058455D03*
X1434603Y1055251D03*
Y1061660D03*
X1436454Y1058455D03*
X1438303Y1055251D03*
Y1061660D03*
X1440154Y1058455D03*
X1442003Y1061660D03*
X1443854Y1064864D03*
Y1071273D03*
Y1077681D03*
X1429054Y1064864D03*
Y1071273D03*
Y1077681D03*
X1430903Y1068068D03*
Y1074477D03*
X1432754Y1064864D03*
Y1071273D03*
Y1077681D03*
X1434603Y1068068D03*
Y1074477D03*
X1436454Y1064864D03*
Y1071273D03*
Y1077681D03*
X1438303Y1068068D03*
Y1074477D03*
X1440154Y1064864D03*
Y1071273D03*
Y1077681D03*
X1442003Y1068068D03*
Y1074477D03*
X1430903Y1080885D03*
X1434603D03*
X1438303D03*
X1442003D03*
X1443854Y1084090D03*
Y1090498D03*
X1429054Y1084090D03*
Y1090498D03*
X1430903Y1087294D03*
Y1093703D03*
X1432754Y1084090D03*
Y1090498D03*
X1434603Y1087294D03*
Y1093703D03*
X1436454Y1084090D03*
Y1090498D03*
X1438303Y1087294D03*
Y1093703D03*
X1440154Y1084090D03*
Y1090498D03*
X1442003Y1087294D03*
Y1093703D03*
X1443854Y1096907D03*
Y1103316D03*
Y1109724D03*
X1429054Y1096907D03*
Y1103316D03*
Y1109724D03*
X1430903Y1100111D03*
Y1106520D03*
X1432754Y1096907D03*
Y1103316D03*
Y1109724D03*
X1434603Y1100111D03*
Y1106520D03*
X1436454Y1096907D03*
Y1103316D03*
Y1109724D03*
X1438303Y1100111D03*
Y1106520D03*
X1440154Y1096907D03*
Y1103316D03*
Y1109724D03*
X1442003Y1100111D03*
Y1106520D03*
Y1112929D03*
X1430903D03*
X1434603D03*
X1438303D03*
X1443854Y1116133D03*
Y1122541D03*
Y1128950D03*
X1429054Y1116133D03*
Y1122541D03*
Y1128950D03*
X1430903Y1119337D03*
Y1125746D03*
X1432754Y1116133D03*
Y1122541D03*
Y1128950D03*
X1434603Y1119337D03*
Y1125746D03*
X1436454Y1116133D03*
Y1122541D03*
Y1128950D03*
X1438303Y1119337D03*
Y1125746D03*
X1440154Y1116133D03*
Y1122541D03*
Y1128950D03*
X1442003Y1119337D03*
Y1125746D03*
X1443854Y1135359D03*
X1430903Y1132154D03*
X1432754Y1135359D03*
X1434603Y1132154D03*
X1436454Y1135359D03*
X1438303Y1132154D03*
X1440154Y1135359D03*
X1442003Y1132154D03*
X1445270Y847081D03*
X1447121Y850286D03*
X1448970Y847081D03*
X1450821Y850286D03*
X1452670Y847081D03*
X1454521Y850286D03*
X1456370Y847081D03*
X1458221Y850286D03*
X1460070Y847081D03*
X1445270Y853490D03*
Y859899D03*
Y866307D03*
X1447121Y856694D03*
Y863103D03*
X1448970Y853490D03*
Y859899D03*
Y866307D03*
X1450821Y856694D03*
Y863103D03*
X1452670Y853490D03*
Y859899D03*
Y866307D03*
X1454521Y856694D03*
Y863103D03*
X1456370Y853490D03*
Y859899D03*
Y866307D03*
X1458221Y856694D03*
Y863103D03*
X1460070Y853490D03*
Y859899D03*
Y866307D03*
X1445270Y872716D03*
X1447121Y869511D03*
X1448970Y872716D03*
X1450821Y869511D03*
X1452670Y872716D03*
X1454521Y869511D03*
X1456370Y872716D03*
X1458221Y869511D03*
X1460070Y872716D03*
X1445270Y879124D03*
X1447121Y875920D03*
Y882329D03*
X1448970Y879124D03*
X1450821Y875920D03*
Y882329D03*
X1452670Y879124D03*
X1454521Y875920D03*
Y882329D03*
X1456370Y879124D03*
X1458221Y875920D03*
Y882329D03*
X1460070Y879124D03*
X1445270Y885533D03*
Y891942D03*
Y898350D03*
X1447121Y888737D03*
Y895146D03*
Y901555D03*
X1448970Y885533D03*
Y891942D03*
Y898350D03*
X1450821Y888737D03*
Y895146D03*
Y901555D03*
X1452670Y885533D03*
Y891942D03*
Y898350D03*
X1454521Y888737D03*
Y895146D03*
Y901555D03*
X1456370Y885533D03*
Y891942D03*
Y898350D03*
X1458221Y888737D03*
Y895146D03*
Y901555D03*
X1460070Y885533D03*
Y891942D03*
Y898350D03*
X1445270Y904759D03*
Y911167D03*
Y917576D03*
X1447121Y907963D03*
Y914372D03*
X1448970Y904759D03*
Y911167D03*
Y917576D03*
X1450821Y907963D03*
Y914372D03*
X1452670Y904759D03*
Y911167D03*
Y917576D03*
X1454521Y907963D03*
Y914372D03*
X1456370Y904759D03*
Y911167D03*
Y917576D03*
X1458221Y907963D03*
Y914372D03*
X1460070Y904759D03*
Y911167D03*
Y917576D03*
X1445270Y923985D03*
X1447121Y920780D03*
X1448970Y923985D03*
X1450821Y920780D03*
X1452670Y923985D03*
X1454521Y920780D03*
Y927189D03*
X1456370Y923985D03*
Y930393D03*
X1458221Y920780D03*
Y927189D03*
X1460070Y923985D03*
Y930393D03*
X1454521Y933598D03*
X1458221D03*
X1454521Y940006D03*
Y946414D03*
X1456370Y936801D03*
Y943210D03*
Y949619D03*
X1458221Y940006D03*
Y946414D03*
X1460070Y936801D03*
Y943210D03*
Y949619D03*
X1454521Y952823D03*
Y959232D03*
X1456370Y956027D03*
Y962436D03*
X1458221Y952823D03*
Y959232D03*
X1460070Y956027D03*
Y962436D03*
X1454521Y965640D03*
X1458221D03*
X1454521Y972049D03*
Y978457D03*
X1456370Y968845D03*
Y975253D03*
Y981662D03*
X1458221Y972049D03*
Y978457D03*
X1460070Y968845D03*
Y975253D03*
Y981662D03*
X1454521Y984866D03*
X1458221D03*
X1456803Y997574D03*
X1460503D03*
X1454954Y1000778D03*
Y1007187D03*
Y1013595D03*
X1456803Y1003983D03*
Y1010391D03*
X1458654Y1000778D03*
Y1007187D03*
Y1013595D03*
X1460503Y1003983D03*
Y1010391D03*
X1454954Y1020004D03*
X1456803Y1016800D03*
X1458654Y1020004D03*
X1460503Y1016800D03*
X1454954Y1026413D03*
X1456803Y1023208D03*
Y1029617D03*
X1458654Y1026413D03*
X1460503Y1023208D03*
Y1029617D03*
X1445703Y1042434D03*
X1447554Y1039230D03*
Y1045639D03*
X1449403Y1042434D03*
X1451254Y1039230D03*
Y1045639D03*
X1453103Y1042434D03*
X1454954Y1032821D03*
Y1039230D03*
Y1045639D03*
X1456803Y1036026D03*
Y1042434D03*
X1458654Y1032821D03*
Y1039230D03*
Y1045639D03*
X1460503Y1036026D03*
Y1042434D03*
X1445703Y1048842D03*
X1447554Y1052047D03*
X1449403Y1048842D03*
X1451254Y1052047D03*
X1453103Y1048842D03*
X1454954Y1052047D03*
X1456803Y1048842D03*
X1458654Y1052047D03*
X1460503Y1048842D03*
X1445703Y1055251D03*
Y1061660D03*
X1447554Y1058455D03*
X1449403Y1055251D03*
Y1061660D03*
X1451254Y1058455D03*
X1453103Y1055251D03*
Y1061660D03*
X1454954Y1058455D03*
X1456803Y1055251D03*
Y1061660D03*
X1458654Y1058455D03*
X1460503Y1055251D03*
Y1061660D03*
X1445703Y1068068D03*
Y1074477D03*
X1447554Y1064864D03*
Y1071273D03*
Y1077681D03*
X1449403Y1068068D03*
Y1074477D03*
X1451254Y1064864D03*
Y1071273D03*
Y1077681D03*
X1453103Y1068068D03*
Y1074477D03*
X1454954Y1064864D03*
Y1071273D03*
Y1077681D03*
X1456803Y1068068D03*
Y1074477D03*
X1458654Y1064864D03*
Y1071273D03*
Y1077681D03*
X1460503Y1068068D03*
Y1074477D03*
X1445703Y1080885D03*
X1449403D03*
X1453103D03*
X1456803D03*
X1460503D03*
X1445703Y1087294D03*
Y1093703D03*
X1447554Y1084090D03*
Y1090498D03*
X1449403Y1087294D03*
Y1093703D03*
X1451254Y1084090D03*
Y1090498D03*
X1453103Y1087294D03*
Y1093703D03*
X1454954Y1084090D03*
Y1090498D03*
X1456803Y1087294D03*
Y1093703D03*
X1458654Y1084090D03*
Y1090498D03*
X1460503Y1087294D03*
Y1093703D03*
X1445703Y1100111D03*
Y1106520D03*
X1447554Y1096907D03*
Y1103316D03*
Y1109724D03*
X1449403Y1100111D03*
Y1106520D03*
X1451254Y1096907D03*
Y1103316D03*
Y1109724D03*
X1453103Y1100111D03*
Y1106520D03*
X1454954Y1096907D03*
Y1103316D03*
Y1109724D03*
X1456803Y1100111D03*
Y1106520D03*
X1458654Y1096907D03*
Y1103316D03*
Y1109724D03*
X1460503Y1100111D03*
Y1106520D03*
X1445703Y1112929D03*
X1449403D03*
X1453103D03*
X1456803D03*
X1460503D03*
X1445703Y1119337D03*
Y1125746D03*
X1447554Y1116133D03*
Y1122541D03*
Y1128950D03*
X1449403Y1119337D03*
Y1125746D03*
X1451254Y1116133D03*
Y1122541D03*
Y1128950D03*
X1453103Y1119337D03*
Y1125746D03*
X1454954Y1116133D03*
Y1122541D03*
Y1128950D03*
X1456803Y1119337D03*
Y1125746D03*
X1458654Y1116133D03*
Y1122541D03*
Y1128950D03*
X1460503Y1119337D03*
Y1125746D03*
X1445703Y1132154D03*
X1447554Y1135359D03*
X1449403Y1132154D03*
X1451254Y1135359D03*
X1453103Y1132154D03*
X1454954Y1135359D03*
X1456803Y1132154D03*
X1458654Y1135359D03*
X1460503Y1132154D03*
X1473021Y850286D03*
X1474870Y847081D03*
X1476721Y850286D03*
X1461921D03*
X1463770Y847081D03*
X1465621Y850286D03*
X1467470Y847081D03*
X1469321Y850286D03*
X1471170Y847081D03*
X1473021Y856694D03*
Y863103D03*
X1474870Y853490D03*
Y859899D03*
Y866307D03*
X1476721Y856694D03*
Y863103D03*
X1461921Y856694D03*
Y863103D03*
X1463770Y853490D03*
Y859899D03*
Y866307D03*
X1465621Y856694D03*
Y863103D03*
X1467470Y853490D03*
Y859899D03*
Y866307D03*
X1469321Y856694D03*
Y863103D03*
X1471170Y853490D03*
Y859899D03*
Y866307D03*
X1473021Y869511D03*
X1474870Y872716D03*
X1476721Y869511D03*
X1461921D03*
X1463770Y872716D03*
X1465621Y869511D03*
X1467470Y872716D03*
X1469321Y869511D03*
X1471170Y872716D03*
X1473021Y875920D03*
Y882329D03*
X1474870Y879124D03*
X1476721Y875920D03*
Y882329D03*
X1461921Y875920D03*
Y882329D03*
X1463770Y879124D03*
X1465621Y875920D03*
Y882329D03*
X1467470Y879124D03*
X1469321Y875920D03*
Y882329D03*
X1471170Y879124D03*
X1473021Y888737D03*
Y895146D03*
Y901555D03*
X1474870Y885533D03*
Y891942D03*
Y898350D03*
X1476721Y888737D03*
Y895146D03*
Y901555D03*
X1461921Y888737D03*
Y895146D03*
Y901555D03*
X1463770Y885533D03*
Y891942D03*
Y898350D03*
X1465621Y888737D03*
Y895146D03*
Y901555D03*
X1467470Y885533D03*
Y891942D03*
Y898350D03*
X1469321Y888737D03*
Y895146D03*
Y901555D03*
X1471170Y885533D03*
Y891942D03*
Y898350D03*
X1473021Y907963D03*
Y914372D03*
X1474870Y904759D03*
Y911167D03*
Y917576D03*
X1476721Y907963D03*
Y914372D03*
X1461921Y907963D03*
Y914372D03*
X1463770Y904759D03*
Y911167D03*
Y917576D03*
X1465621Y907963D03*
Y914372D03*
X1467470Y904759D03*
Y911167D03*
Y917576D03*
X1469321Y907963D03*
Y914372D03*
X1471170Y904759D03*
Y911167D03*
Y917576D03*
X1473021Y920780D03*
Y927189D03*
X1474870Y923985D03*
Y930393D03*
X1476721Y920780D03*
Y927189D03*
X1461921Y920780D03*
Y927189D03*
X1463770Y923985D03*
Y930393D03*
X1465621Y920780D03*
Y927189D03*
X1467470Y923985D03*
Y930393D03*
X1469321Y920780D03*
Y927189D03*
X1471170Y923985D03*
Y930393D03*
X1473021Y933598D03*
X1476721D03*
X1461921D03*
X1465621D03*
X1469321D03*
X1473021Y940006D03*
Y946414D03*
X1474870Y936801D03*
Y943210D03*
Y949619D03*
X1476721Y940006D03*
Y946414D03*
X1461921Y940006D03*
Y946414D03*
X1463770Y936801D03*
Y943210D03*
Y949619D03*
X1465621Y940006D03*
Y946414D03*
X1467470Y936801D03*
Y943210D03*
Y949619D03*
X1469321Y940006D03*
Y946414D03*
X1471170Y936801D03*
Y943210D03*
Y949619D03*
X1473021Y952823D03*
Y959232D03*
X1474870Y956027D03*
Y962436D03*
X1476721Y952823D03*
Y959232D03*
X1461921Y952823D03*
Y959232D03*
X1463770Y956027D03*
Y962436D03*
X1465621Y952823D03*
Y959232D03*
X1467470Y956027D03*
Y962436D03*
X1469321Y952823D03*
Y959232D03*
X1471170Y956027D03*
Y962436D03*
X1473021Y965640D03*
X1476721D03*
X1461921D03*
X1465621D03*
X1469321D03*
X1473021Y972049D03*
Y978457D03*
X1474870Y968845D03*
Y975253D03*
Y981662D03*
X1476721Y972049D03*
Y978457D03*
X1461921Y972049D03*
Y978457D03*
X1463770Y968845D03*
Y975253D03*
Y981662D03*
X1465621Y972049D03*
Y978457D03*
X1467470Y968845D03*
Y975253D03*
Y981662D03*
X1469321Y972049D03*
Y978457D03*
X1471170Y968845D03*
Y975253D03*
Y981662D03*
X1473021Y984866D03*
X1476721D03*
X1461921D03*
X1465621D03*
X1469321D03*
X1475303Y997574D03*
X1464203D03*
X1467903D03*
X1471603D03*
X1473454Y1000778D03*
Y1007187D03*
Y1013595D03*
X1475303Y1003983D03*
Y1010391D03*
X1477154Y1000778D03*
Y1007187D03*
Y1013595D03*
X1462354Y1000778D03*
Y1007187D03*
Y1013595D03*
X1464203Y1003983D03*
Y1010391D03*
X1466054Y1000778D03*
Y1007187D03*
Y1013595D03*
X1467903Y1003983D03*
Y1010391D03*
X1469754Y1000778D03*
Y1007187D03*
Y1013595D03*
X1471603Y1003983D03*
Y1010391D03*
X1473454Y1020004D03*
X1475303Y1016800D03*
X1477154Y1020004D03*
X1462354D03*
X1464203Y1016800D03*
X1466054Y1020004D03*
X1467903Y1016800D03*
X1469754Y1020004D03*
X1471603Y1016800D03*
X1473454Y1026413D03*
X1475303Y1023208D03*
Y1029617D03*
X1477154Y1026413D03*
X1462354D03*
X1464203Y1023208D03*
Y1029617D03*
X1466054Y1026413D03*
X1467903Y1023208D03*
Y1029617D03*
X1469754Y1026413D03*
X1471603Y1023208D03*
Y1029617D03*
X1473454Y1032821D03*
Y1039230D03*
Y1045639D03*
X1475303Y1036026D03*
Y1042434D03*
X1477154Y1032821D03*
Y1039230D03*
Y1045639D03*
X1462354Y1032821D03*
Y1039230D03*
Y1045639D03*
X1464203Y1036026D03*
Y1042434D03*
X1466054Y1032821D03*
Y1039230D03*
Y1045639D03*
X1467903Y1036026D03*
Y1042434D03*
X1469754Y1032821D03*
Y1039230D03*
Y1045639D03*
X1471603Y1036026D03*
Y1042434D03*
X1473454Y1052047D03*
X1475303Y1048842D03*
X1477154Y1052047D03*
X1462354D03*
X1464203Y1048842D03*
X1466054Y1052047D03*
X1467903Y1048842D03*
X1469754Y1052047D03*
X1471603Y1048842D03*
X1473454Y1058455D03*
X1475303Y1055251D03*
Y1061660D03*
X1477154Y1058455D03*
X1462354D03*
X1464203Y1055251D03*
Y1061660D03*
X1466054Y1058455D03*
X1467903Y1055251D03*
Y1061660D03*
X1469754Y1058455D03*
X1471603Y1055251D03*
Y1061660D03*
X1473454Y1064864D03*
Y1071273D03*
Y1077681D03*
X1475303Y1068068D03*
Y1074477D03*
X1477154Y1064864D03*
Y1071273D03*
Y1077681D03*
X1462354Y1064864D03*
Y1071273D03*
Y1077681D03*
X1464203Y1068068D03*
Y1074477D03*
X1466054Y1064864D03*
Y1071273D03*
Y1077681D03*
X1467903Y1068068D03*
Y1074477D03*
X1469754Y1064864D03*
Y1071273D03*
Y1077681D03*
X1471603Y1068068D03*
Y1074477D03*
X1475303Y1080885D03*
X1464203D03*
X1467903D03*
X1471603D03*
X1473454Y1084090D03*
Y1090498D03*
X1475303Y1087294D03*
Y1093703D03*
X1477154Y1084090D03*
Y1090498D03*
X1462354Y1084090D03*
Y1090498D03*
X1464203Y1087294D03*
Y1093703D03*
X1466054Y1084090D03*
Y1090498D03*
X1467903Y1087294D03*
Y1093703D03*
X1469754Y1084090D03*
Y1090498D03*
X1471603Y1087294D03*
Y1093703D03*
X1473454Y1096907D03*
Y1103316D03*
Y1109724D03*
X1475303Y1100111D03*
Y1106520D03*
X1477154Y1096907D03*
Y1103316D03*
Y1109724D03*
X1462354Y1096907D03*
Y1103316D03*
Y1109724D03*
X1464203Y1100111D03*
Y1106520D03*
X1466054Y1096907D03*
Y1103316D03*
Y1109724D03*
X1467903Y1100111D03*
Y1106520D03*
X1469754Y1096907D03*
Y1103316D03*
Y1109724D03*
X1471603Y1100111D03*
Y1106520D03*
X1475303Y1112929D03*
X1464203D03*
X1467903D03*
X1471603D03*
X1473454Y1116133D03*
Y1122541D03*
Y1128950D03*
X1475303Y1119337D03*
Y1125746D03*
X1477154Y1116133D03*
Y1122541D03*
Y1128950D03*
X1462354Y1116133D03*
Y1122541D03*
Y1128950D03*
X1464203Y1119337D03*
Y1125746D03*
X1466054Y1116133D03*
Y1122541D03*
Y1128950D03*
X1467903Y1119337D03*
Y1125746D03*
X1469754Y1116133D03*
Y1122541D03*
Y1128950D03*
X1471603Y1119337D03*
Y1125746D03*
X1473454Y1135359D03*
X1475303Y1132154D03*
X1477154Y1135359D03*
X1462354D03*
X1464203Y1132154D03*
X1466054Y1135359D03*
X1467903Y1132154D03*
X1469754Y1135359D03*
X1471603Y1132154D03*
X1478570Y847081D03*
X1480421Y850286D03*
X1482270Y847081D03*
X1484121Y850286D03*
X1485970Y847081D03*
X1487821Y850286D03*
X1489670Y847081D03*
X1491521Y850286D03*
X1493370Y847081D03*
X1478570Y853490D03*
Y859899D03*
Y866307D03*
X1480421Y856694D03*
Y863103D03*
X1482270Y853490D03*
Y859899D03*
Y866307D03*
X1484121Y856694D03*
Y863103D03*
X1485970Y853490D03*
Y859899D03*
Y866307D03*
X1487821Y856694D03*
Y863103D03*
X1489670Y853490D03*
Y859899D03*
Y866307D03*
X1491521Y856694D03*
Y863103D03*
X1493370Y853490D03*
Y859899D03*
Y866307D03*
X1478570Y872716D03*
X1480421Y869511D03*
X1482270Y872716D03*
X1484121Y869511D03*
X1485970Y872716D03*
X1487821Y869511D03*
X1489670Y872716D03*
X1491521Y869511D03*
X1493370Y872716D03*
X1478570Y879124D03*
X1480421Y875920D03*
Y882329D03*
X1482270Y879124D03*
X1484121Y875920D03*
Y882329D03*
X1485970Y879124D03*
X1487821Y875920D03*
Y882329D03*
X1489670Y879124D03*
X1491521Y875920D03*
Y882329D03*
X1493370Y879124D03*
X1478570Y885533D03*
Y891942D03*
Y898350D03*
X1480421Y888737D03*
Y895146D03*
Y901555D03*
X1482270Y885533D03*
Y891942D03*
Y898350D03*
X1484121Y888737D03*
Y895146D03*
Y901555D03*
X1485970Y885533D03*
Y891942D03*
Y898350D03*
X1487821Y888737D03*
Y895146D03*
Y901555D03*
X1489670Y885533D03*
Y891942D03*
Y898350D03*
X1491521Y888737D03*
Y895146D03*
Y901555D03*
X1493370Y885533D03*
Y891942D03*
Y898350D03*
X1478570Y904759D03*
Y911167D03*
Y917576D03*
X1480421Y907963D03*
Y914372D03*
X1482270Y904759D03*
Y911167D03*
Y917576D03*
X1484121Y907963D03*
Y914372D03*
X1485970Y904759D03*
Y911167D03*
Y917576D03*
X1487821Y907963D03*
Y914372D03*
X1489670Y904759D03*
Y911167D03*
Y917576D03*
X1491521Y907963D03*
Y914372D03*
X1493370Y904759D03*
Y911167D03*
Y917576D03*
X1478570Y923985D03*
Y930393D03*
X1480421Y920780D03*
Y927189D03*
X1482270Y923985D03*
Y930393D03*
X1484121Y920780D03*
Y927189D03*
X1485970Y923985D03*
Y930393D03*
X1487821Y920780D03*
Y927189D03*
X1489670Y923985D03*
Y930393D03*
X1491521Y920780D03*
Y927189D03*
X1493370Y923985D03*
Y930393D03*
X1480421Y933598D03*
X1484121D03*
X1487821D03*
X1491521D03*
X1478570Y936801D03*
Y943210D03*
Y949619D03*
X1480421Y940006D03*
Y946414D03*
X1482270Y936801D03*
Y943210D03*
Y949619D03*
X1484121Y940006D03*
Y946414D03*
X1485970Y936801D03*
Y943210D03*
Y949619D03*
X1487821Y940006D03*
Y946414D03*
X1489670Y936801D03*
Y943210D03*
Y949619D03*
X1491521Y940006D03*
Y946414D03*
X1493370Y936801D03*
Y943210D03*
Y949619D03*
X1478570Y956027D03*
Y962436D03*
X1480421Y952823D03*
Y959232D03*
X1482270Y956027D03*
Y962436D03*
X1484121Y952823D03*
Y959232D03*
X1485970Y956027D03*
Y962436D03*
X1487821Y952823D03*
Y959232D03*
X1489670Y956027D03*
Y962436D03*
X1491521Y952823D03*
Y959232D03*
X1493370Y956027D03*
Y962436D03*
X1480421Y965640D03*
X1484121D03*
X1487821D03*
X1491521D03*
X1478570Y968845D03*
Y975253D03*
Y981662D03*
X1480421Y972049D03*
Y978457D03*
X1482270Y968845D03*
Y975253D03*
Y981662D03*
X1484121Y972049D03*
Y978457D03*
X1485970Y968845D03*
Y975253D03*
Y981662D03*
X1487821Y972049D03*
Y978457D03*
X1489670Y968845D03*
Y975253D03*
Y981662D03*
X1491521Y972049D03*
Y978457D03*
X1493370Y968845D03*
Y975253D03*
Y981662D03*
X1480421Y984866D03*
X1484121D03*
X1487821D03*
X1491521D03*
X1479003Y997574D03*
X1482703D03*
X1486403D03*
X1490103D03*
X1493803D03*
X1479003Y1003983D03*
Y1010391D03*
X1480854Y1000778D03*
Y1007187D03*
Y1013595D03*
X1482703Y1003983D03*
Y1010391D03*
X1484554Y1000778D03*
Y1007187D03*
Y1013595D03*
X1486403Y1003983D03*
Y1010391D03*
X1488254Y1000778D03*
Y1007187D03*
Y1013595D03*
X1490103Y1003983D03*
Y1010391D03*
X1491954Y1000778D03*
Y1007187D03*
Y1013595D03*
X1493803Y1003983D03*
Y1010391D03*
X1479004Y1006093D03*
X1479003Y1016800D03*
X1480854Y1020004D03*
X1482703Y1016800D03*
X1484554Y1020004D03*
X1486403Y1016800D03*
X1488254Y1020004D03*
X1490103Y1016800D03*
X1491954Y1020004D03*
X1493803Y1016800D03*
X1479003Y1023208D03*
Y1029617D03*
X1480854Y1026413D03*
X1482703Y1023208D03*
Y1029617D03*
X1484554Y1026413D03*
X1486403Y1023208D03*
Y1029617D03*
X1488254Y1026413D03*
X1490103Y1023208D03*
Y1029617D03*
X1491954Y1026413D03*
X1493803Y1023208D03*
Y1029617D03*
X1479003Y1036026D03*
Y1042434D03*
X1480854Y1032821D03*
Y1039230D03*
Y1045639D03*
X1482703Y1036026D03*
Y1042434D03*
X1484554Y1032821D03*
Y1039230D03*
Y1045639D03*
X1486403Y1036026D03*
Y1042434D03*
X1488254Y1032821D03*
Y1039230D03*
Y1045639D03*
X1490103Y1036026D03*
Y1042434D03*
X1491954Y1032821D03*
Y1039230D03*
Y1045639D03*
X1493803Y1036026D03*
Y1042434D03*
X1479003Y1048842D03*
X1480854Y1052047D03*
X1482703Y1048842D03*
X1484554Y1052047D03*
X1486403Y1048842D03*
X1488254Y1052047D03*
X1490103Y1048842D03*
X1491954Y1052047D03*
X1493803Y1048842D03*
X1479003Y1055251D03*
Y1061660D03*
X1480854Y1058455D03*
X1482703Y1055251D03*
Y1061660D03*
X1484554Y1058455D03*
X1486403Y1055251D03*
Y1061660D03*
X1488254Y1058455D03*
X1490103Y1055251D03*
Y1061660D03*
X1491954Y1058455D03*
X1493803Y1055251D03*
Y1061660D03*
X1479003Y1068068D03*
Y1074477D03*
X1480854Y1064864D03*
Y1071273D03*
Y1077681D03*
X1482703Y1068068D03*
Y1074477D03*
X1484554Y1064864D03*
Y1071273D03*
Y1077681D03*
X1486403Y1068068D03*
Y1074477D03*
X1488254Y1064864D03*
Y1071273D03*
Y1077681D03*
X1490103Y1068068D03*
Y1074477D03*
X1491954Y1064864D03*
Y1071273D03*
Y1077681D03*
X1493803Y1068068D03*
Y1074477D03*
X1479003Y1080885D03*
X1482703D03*
X1486403D03*
X1490103D03*
X1493803D03*
X1479003Y1087294D03*
Y1093703D03*
X1480854Y1084090D03*
Y1090498D03*
X1482703Y1087294D03*
Y1093703D03*
X1484554Y1084090D03*
Y1090498D03*
X1486403Y1087294D03*
Y1093703D03*
X1488254Y1084090D03*
Y1090498D03*
X1490103Y1087294D03*
Y1093703D03*
X1491954Y1084090D03*
Y1090498D03*
X1493803Y1087294D03*
Y1093703D03*
X1479003Y1100111D03*
Y1106520D03*
X1480854Y1096907D03*
Y1103316D03*
Y1109724D03*
X1482703Y1100111D03*
Y1106520D03*
X1484554Y1096907D03*
Y1103316D03*
Y1109724D03*
X1486403Y1100111D03*
Y1106520D03*
X1488254Y1096907D03*
Y1103316D03*
Y1109724D03*
X1490103Y1100111D03*
Y1106520D03*
X1491954Y1096907D03*
Y1103316D03*
Y1109724D03*
X1493803Y1100111D03*
Y1106520D03*
X1479003Y1112929D03*
X1482703D03*
X1486403D03*
X1490103D03*
X1493803D03*
X1479003Y1119337D03*
Y1125746D03*
X1480854Y1116133D03*
Y1122541D03*
Y1128950D03*
X1482703Y1119337D03*
Y1125746D03*
X1484554Y1116133D03*
Y1122541D03*
Y1128950D03*
X1486403Y1119337D03*
Y1125746D03*
X1488254Y1116133D03*
Y1122541D03*
Y1128950D03*
X1490103Y1119337D03*
Y1125746D03*
X1491954Y1116133D03*
Y1122541D03*
Y1128950D03*
X1493803Y1119337D03*
Y1125746D03*
X1479003Y1132154D03*
X1480854Y1135359D03*
X1482703Y1132154D03*
X1484554Y1135359D03*
X1486403Y1132154D03*
X1488254Y1135359D03*
X1490103Y1132154D03*
X1491954Y1135359D03*
X1493803Y1132154D03*
X1502621Y850286D03*
X1506321D03*
X1495221D03*
X1497070Y847081D03*
X1498921Y850286D03*
X1502621Y856694D03*
Y863103D03*
X1504471Y853490D03*
Y859899D03*
Y866307D03*
X1506321Y856694D03*
Y863103D03*
X1508170Y853490D03*
Y859899D03*
Y866307D03*
X1510021Y856694D03*
Y863103D03*
X1495221Y856694D03*
Y863103D03*
X1497070Y853490D03*
Y859899D03*
Y866307D03*
X1498921Y856694D03*
Y863103D03*
X1500770Y853490D03*
Y859899D03*
Y866307D03*
X1502621Y869511D03*
X1504471Y872716D03*
X1506321Y869511D03*
X1508170Y872716D03*
X1510021Y869511D03*
X1495221D03*
X1497070Y872716D03*
X1498921Y869511D03*
X1500770Y872716D03*
X1502621Y875920D03*
Y882329D03*
X1504471Y879124D03*
X1506321Y875920D03*
Y882329D03*
X1508170Y879124D03*
X1510021Y875920D03*
Y882329D03*
X1495221Y875920D03*
Y882329D03*
X1497070Y879124D03*
X1498921Y875920D03*
Y882329D03*
X1500770Y879124D03*
X1502621Y888737D03*
Y895146D03*
Y901555D03*
X1504471Y885533D03*
Y891942D03*
Y898350D03*
X1506321Y888737D03*
Y895146D03*
Y901555D03*
X1508170Y885533D03*
Y891942D03*
Y898350D03*
X1510021Y888737D03*
Y895146D03*
Y901555D03*
X1495221Y888737D03*
Y895146D03*
Y901555D03*
X1497070Y885533D03*
Y891942D03*
Y898350D03*
X1498921Y888737D03*
Y895146D03*
Y901555D03*
X1500770Y885533D03*
Y891942D03*
Y898350D03*
X1502621Y907963D03*
Y914372D03*
X1504471Y904759D03*
Y911167D03*
Y917576D03*
X1506321Y907963D03*
Y914372D03*
X1508170Y904759D03*
Y911167D03*
Y917576D03*
X1510021Y907963D03*
Y914372D03*
X1495221Y907963D03*
Y914372D03*
X1497070Y904759D03*
Y911167D03*
Y917576D03*
X1498921Y907963D03*
Y914372D03*
X1500770Y904759D03*
Y911167D03*
Y917576D03*
X1502621Y920780D03*
Y927189D03*
X1504471Y923985D03*
Y930393D03*
X1506321Y920780D03*
Y927189D03*
X1508170Y923985D03*
Y930393D03*
X1510021Y920780D03*
Y927189D03*
X1495221Y920780D03*
Y927189D03*
X1497070Y923985D03*
Y930393D03*
X1498921Y920780D03*
Y927189D03*
X1500770Y923985D03*
Y930393D03*
X1502621Y933598D03*
X1506321D03*
X1510021D03*
X1495221D03*
X1498921D03*
X1502621Y940006D03*
Y946414D03*
X1504471Y936801D03*
Y943210D03*
Y949619D03*
X1506321Y940006D03*
Y946414D03*
X1508170Y936801D03*
Y943210D03*
Y949619D03*
X1510021Y940006D03*
Y946414D03*
X1495221Y940006D03*
Y946414D03*
X1497070Y936801D03*
Y943210D03*
Y949619D03*
X1498921Y940006D03*
Y946414D03*
X1500770Y936801D03*
Y943210D03*
Y949619D03*
X1502621Y952823D03*
Y959232D03*
X1504471Y956027D03*
Y962436D03*
X1506321Y952823D03*
Y959232D03*
X1508170Y956027D03*
Y962436D03*
X1510021Y952823D03*
Y959232D03*
X1495221Y952823D03*
Y959232D03*
X1497070Y956027D03*
Y962436D03*
X1498921Y952823D03*
Y959232D03*
X1500770Y956027D03*
Y962436D03*
X1502621Y965640D03*
X1506321D03*
X1510021D03*
X1495221D03*
X1498921D03*
X1502621Y972049D03*
Y978457D03*
X1504471Y968845D03*
Y975253D03*
Y981662D03*
X1506321Y972049D03*
Y978457D03*
X1508170Y968845D03*
Y975253D03*
Y981662D03*
X1510021Y972049D03*
Y978457D03*
X1495221Y972049D03*
Y978457D03*
X1497070Y968845D03*
Y975253D03*
Y981662D03*
X1498921Y972049D03*
Y978457D03*
X1500770Y968845D03*
Y975253D03*
Y981662D03*
X1502621Y984866D03*
X1506321D03*
X1510021D03*
X1495221D03*
X1498921D03*
X1504903Y997574D03*
X1508603D03*
X1497503D03*
X1501203D03*
X1503054Y1000778D03*
Y1007187D03*
Y1013595D03*
X1504903Y1003983D03*
Y1010391D03*
X1506754Y1000778D03*
Y1007187D03*
Y1013595D03*
X1508603Y1003983D03*
Y1010391D03*
X1495654Y1000778D03*
Y1007187D03*
Y1013595D03*
X1497503Y1003983D03*
Y1010391D03*
X1499354Y1000778D03*
Y1007187D03*
Y1013595D03*
X1501203Y1003983D03*
Y1010391D03*
X1503054Y1020004D03*
X1504903Y1016800D03*
X1506754Y1020004D03*
X1508603Y1016800D03*
X1495654Y1020004D03*
X1497503Y1016800D03*
X1499354Y1020004D03*
X1501203Y1016800D03*
X1503054Y1026413D03*
X1504903Y1023208D03*
Y1029617D03*
X1506754Y1026413D03*
X1508603Y1023208D03*
Y1029617D03*
X1495654Y1026413D03*
X1497503Y1023208D03*
Y1029617D03*
X1499354Y1026413D03*
X1501203Y1023208D03*
Y1029617D03*
X1503054Y1032821D03*
Y1039230D03*
Y1045639D03*
X1504903Y1036026D03*
Y1042434D03*
X1506754Y1032821D03*
Y1039230D03*
Y1045639D03*
X1508603Y1036026D03*
Y1042434D03*
X1495654Y1032821D03*
Y1039230D03*
Y1045639D03*
X1497503Y1036026D03*
Y1042434D03*
X1499354Y1032821D03*
Y1039230D03*
Y1045639D03*
X1501203Y1036026D03*
Y1042434D03*
X1503054Y1052047D03*
X1504903Y1048842D03*
X1506754Y1052047D03*
X1508603Y1048842D03*
X1495654Y1052047D03*
X1497503Y1048842D03*
X1499354Y1052047D03*
X1501203Y1048842D03*
X1503054Y1058455D03*
X1504903Y1055251D03*
Y1061660D03*
X1506754Y1058455D03*
X1508603Y1055251D03*
Y1061660D03*
X1495654Y1058455D03*
X1497503Y1055251D03*
Y1061660D03*
X1499354Y1058455D03*
X1501203Y1055251D03*
Y1061660D03*
X1503054Y1064864D03*
Y1071273D03*
Y1077681D03*
X1504903Y1068068D03*
Y1074477D03*
X1506754Y1064864D03*
Y1071273D03*
Y1077681D03*
X1508603Y1068068D03*
Y1074477D03*
X1495654Y1064864D03*
Y1071273D03*
Y1077681D03*
X1497503Y1068068D03*
Y1074477D03*
X1499354Y1064864D03*
Y1071273D03*
Y1077681D03*
X1501203Y1068068D03*
Y1074477D03*
X1504903Y1080885D03*
X1508603D03*
X1497503D03*
X1501203D03*
X1503054Y1084090D03*
Y1090498D03*
X1504903Y1087294D03*
Y1093703D03*
X1506754Y1084090D03*
Y1090498D03*
X1508603Y1087294D03*
Y1093703D03*
X1495654Y1084090D03*
Y1090498D03*
X1497503Y1087294D03*
Y1093703D03*
X1499354Y1084090D03*
Y1090498D03*
X1501203Y1087294D03*
Y1093703D03*
X1503054Y1096907D03*
Y1103316D03*
Y1109724D03*
X1504903Y1100111D03*
Y1106520D03*
X1506754Y1096907D03*
Y1103316D03*
Y1109724D03*
X1508603Y1100111D03*
Y1106520D03*
X1495654Y1096907D03*
Y1103316D03*
Y1109724D03*
X1497503Y1100111D03*
Y1106520D03*
X1499354Y1096907D03*
Y1103316D03*
Y1109724D03*
X1501203Y1100111D03*
Y1106520D03*
X1504903Y1112929D03*
X1508603D03*
X1497503D03*
X1501203D03*
X1503054Y1116133D03*
Y1122541D03*
Y1128950D03*
X1504903Y1119337D03*
Y1125746D03*
X1506754Y1116133D03*
Y1122541D03*
Y1128950D03*
X1508603Y1119337D03*
Y1125746D03*
X1495654Y1116133D03*
Y1122541D03*
Y1128950D03*
X1497503Y1119337D03*
Y1125746D03*
X1499354Y1116133D03*
Y1122541D03*
Y1128950D03*
X1501203Y1119337D03*
Y1125746D03*
X1504903Y1132154D03*
X1495654Y1135359D03*
X1497503Y1132154D03*
X1499354Y1135359D03*
X1501203Y1132154D03*
X1511871Y859899D03*
Y866307D03*
X1513721Y863103D03*
X1515570Y866307D03*
X1511871Y872716D03*
X1513721Y869511D03*
X1515570Y872716D03*
X1517421Y869511D03*
X1519271Y872716D03*
X1511871Y879124D03*
X1513721Y875920D03*
Y882329D03*
X1515570Y879124D03*
X1517421Y875920D03*
Y882329D03*
X1519271Y879124D03*
X1521121Y875920D03*
Y882329D03*
X1511871Y885533D03*
Y891942D03*
Y898350D03*
X1513721Y888737D03*
Y895146D03*
Y901555D03*
X1515570Y885533D03*
Y891942D03*
Y898350D03*
X1517421Y888737D03*
Y895146D03*
Y901555D03*
X1519271Y885533D03*
Y891942D03*
Y898350D03*
X1521121Y888737D03*
Y895146D03*
Y901555D03*
X1513721Y893036D03*
Y899445D03*
X1511871Y904759D03*
Y911167D03*
Y917576D03*
X1513721Y907963D03*
Y914372D03*
X1515570Y904759D03*
Y911167D03*
Y917576D03*
X1517421Y907963D03*
Y914372D03*
X1519271Y904759D03*
Y911167D03*
Y917576D03*
X1521121Y907963D03*
Y914372D03*
X1513721Y912262D03*
X1515571Y909057D03*
X1519271D03*
X1511871Y923985D03*
Y930393D03*
X1513721Y920780D03*
Y927189D03*
X1515570Y923985D03*
Y930393D03*
X1517421Y920780D03*
Y927189D03*
X1519271Y923985D03*
Y930393D03*
X1521121Y920780D03*
Y927189D03*
X1513721Y933598D03*
X1517421D03*
X1521121D03*
X1519271Y928283D03*
X1515571D03*
X1513721Y918670D03*
X1513720Y931488D03*
X1511871Y936801D03*
Y943210D03*
Y949619D03*
X1513721Y940006D03*
Y946414D03*
X1515570Y936801D03*
Y943210D03*
Y949619D03*
X1517421Y940006D03*
Y946414D03*
X1519271Y936801D03*
Y943210D03*
Y949619D03*
X1521121Y940006D03*
Y946414D03*
X1513721Y937896D03*
X1519271Y947509D03*
X1515571D03*
X1511871Y956027D03*
Y962436D03*
X1513721Y952823D03*
Y959232D03*
X1515570Y956027D03*
Y962436D03*
X1517421Y952823D03*
Y959232D03*
X1519271Y956027D03*
Y962436D03*
X1521121Y952823D03*
Y959232D03*
X1513721Y965640D03*
X1517421D03*
X1521121D03*
X1513721Y957122D03*
Y950713D03*
X1511871Y968845D03*
Y975253D03*
Y981662D03*
X1513721Y972049D03*
Y978457D03*
X1515570Y968845D03*
Y975253D03*
Y981662D03*
X1517421Y972049D03*
Y978457D03*
X1519271Y968845D03*
Y975253D03*
X1521121Y972049D03*
X1515571Y979552D03*
X1511871Y973143D03*
X1513721Y984866D03*
X1512303Y997574D03*
X1516003D03*
X1510453Y1000778D03*
Y1007187D03*
Y1013595D03*
X1512303Y1003983D03*
Y1010391D03*
X1514154Y1000778D03*
Y1007187D03*
Y1013595D03*
X1516003Y1003983D03*
Y1010391D03*
X1517853Y1000778D03*
Y1007187D03*
Y1013595D03*
X1519703Y1003983D03*
Y1010391D03*
X1521554Y1007187D03*
Y1013595D03*
X1516004Y1006092D03*
X1516003Y999684D03*
X1512303Y1006093D03*
X1519705Y1006092D03*
X1510453Y1020004D03*
X1512303Y1016800D03*
X1514154Y1020004D03*
X1516003Y1016800D03*
X1517853Y1020004D03*
X1519703Y1016800D03*
X1521554Y1020004D03*
X1510453Y1026413D03*
X1512303Y1023208D03*
Y1029617D03*
X1514154Y1026413D03*
X1516003Y1023208D03*
Y1029617D03*
X1517853Y1026413D03*
X1519703Y1023208D03*
Y1029617D03*
X1521554Y1026413D03*
X1512303Y1025318D03*
X1516003Y1018910D03*
X1510453Y1032821D03*
Y1039230D03*
Y1045639D03*
X1512303Y1036026D03*
Y1042434D03*
X1514154Y1032821D03*
Y1039230D03*
Y1045639D03*
X1516003Y1036026D03*
Y1042434D03*
X1517853Y1032821D03*
Y1039230D03*
Y1045639D03*
X1519703Y1036026D03*
Y1042434D03*
X1521554Y1032821D03*
Y1039230D03*
X1516004Y1044544D03*
X1516003Y1038136D03*
X1510453Y1052047D03*
X1512303Y1048842D03*
X1514154Y1052047D03*
X1516003Y1048842D03*
X1517853Y1052047D03*
X1519703Y1048842D03*
X1510453Y1058455D03*
X1512303Y1055251D03*
Y1061660D03*
X1514154Y1058455D03*
X1516003Y1055251D03*
Y1061660D03*
X1517853Y1058455D03*
X1519703Y1055251D03*
Y1061660D03*
X1514153Y1060565D03*
X1510453Y1064864D03*
Y1071273D03*
Y1077681D03*
X1512303Y1068068D03*
Y1074477D03*
X1514154Y1064864D03*
Y1071273D03*
Y1077681D03*
X1516003Y1068068D03*
Y1074477D03*
X1517853Y1064864D03*
Y1071273D03*
Y1077681D03*
X1519703Y1068068D03*
Y1074477D03*
X1514153Y1066974D03*
X1517853Y1073383D03*
X1516003Y1076587D03*
X1512303Y1080885D03*
X1516003D03*
X1519703D03*
X1510453Y1084090D03*
Y1090498D03*
X1512303Y1087294D03*
Y1093703D03*
X1514154Y1084090D03*
Y1090498D03*
X1516003Y1087294D03*
Y1093703D03*
X1517853Y1084090D03*
Y1090498D03*
X1519703Y1087294D03*
Y1093703D03*
X1512304Y1082996D03*
X1510453Y1096907D03*
Y1103316D03*
Y1109724D03*
X1512303Y1100111D03*
Y1106520D03*
X1514154Y1096907D03*
Y1103316D03*
Y1109724D03*
X1516003Y1100111D03*
Y1106520D03*
X1517853Y1096907D03*
Y1103316D03*
Y1109724D03*
X1519703Y1100111D03*
Y1106520D03*
X1512303Y1112929D03*
X1516003D03*
X1510453Y1116133D03*
Y1122541D03*
X1512303Y1119337D03*
X1514154Y1116133D03*
G54D42*
X70472Y173228D03*
Y236220D03*
G54D261*
X1029250Y275752D03*
G54D343*
G01X984691Y389467D02*
X983766Y390392D01*
X982220D01*
X980856Y391756D01*
Y392502D01*
G01X991369Y392965D02*
X989892D01*
X989055Y393802D01*
X986535D01*
X984313Y394722D01*
X976740D01*
X975330Y396132D01*
G01X991369Y394934D02*
X986866D01*
X984792Y395792D01*
X981700D01*
X979559Y397933D01*
Y399362D01*
G01X991369Y389028D02*
X989080D01*
X988654Y388602D01*
X984057D01*
X983267Y389392D01*
X980667D01*
X977861Y392198D01*
X975805D01*
X975670Y392063D01*
G01X991369Y390997D02*
X988482D01*
X987801Y390316D01*
X985143D01*
X984490Y390969D01*
Y392042D01*
X983970Y392562D01*
G01X1347210Y199999D02*
X1346147Y198149D01*
G01X1347210Y203699D02*
X1346147Y201849D01*
G01X1350414D02*
X1349361Y199998D01*
G01X1353620Y203699D02*
X1352561Y201848D01*
G01X1398984Y234392D02*
X1394634D01*
X1387637Y227395D01*
X1385001D01*
X1376004Y218398D01*
X1371244D01*
G01X1391443Y223513D02*
Y221901D01*
X1388119Y218577D01*
X1379960D01*
X1377735Y216352D01*
X1370884D01*
G01X1394493Y230962D02*
X1393581D01*
X1390293Y227674D01*
Y226462D01*
X1388924Y225093D01*
Y221633D01*
X1386814Y219523D01*
X1379445D01*
X1377260Y217338D01*
X1370664D01*
G54D334*
G01X82715Y303262D02*
Y307951D01*
X77804Y312862D01*
X14720D01*
X9320Y307462D01*
Y300362D01*
X11475Y298207D01*
X14092D01*
G01X93400Y297703D02*
X95260D01*
X96020Y298463D01*
Y305763D01*
X86973Y314810D01*
X12771D01*
X6765Y308804D01*
Y299120D01*
X10433Y295452D01*
X14092D01*
G01X32049Y1252034D02*
X21950D01*
X19664Y1249748D01*
Y1207339D01*
X22503Y1204500D01*
Y779625D01*
X12760Y769882D01*
Y759893D01*
X19370Y753283D01*
Y690092D01*
X43850Y665612D01*
X52636D01*
X67490Y650758D01*
X72600Y638420D01*
Y593922D01*
X112850Y553672D01*
X294760D01*
G01X16925Y200362D02*
Y203366D01*
G01X17061Y196368D02*
Y193498D01*
X16925Y193362D01*
G01X33500Y200862D02*
X23579D01*
X23079Y200362D01*
X20075D01*
G01X33670Y192862D02*
X23579D01*
X23079Y193362D01*
X20075D01*
G01X27645Y216362D02*
X24720D01*
G01X27645D02*
X29595Y218312D01*
X34195D01*
X36145Y216362D01*
G01X27645Y232362D02*
X24720D01*
G01X36145Y224342D02*
X34065Y222262D01*
X29745D01*
X27645Y224362D01*
G01D02*
X24720D01*
G01X27645Y240362D02*
X24720D01*
G01X28068Y295452D02*
X23330D01*
X21720Y297062D01*
Y304062D01*
X26420Y308762D01*
X45680D01*
X49594Y304848D01*
G01X19360Y304152D02*
Y294402D01*
X17850Y292892D01*
X14092D01*
G01X82715Y286262D02*
X78670Y282217D01*
X41298D01*
X33378Y290137D01*
X28068D01*
G01Y292892D02*
X34520D01*
X42440Y284972D01*
X71180D01*
X75570Y289362D01*
X93720D01*
X96220Y286862D01*
Y281363D01*
X95060Y280203D01*
X93400D01*
G01X58668Y293392D02*
X55990D01*
X52420Y296962D01*
Y305462D01*
X47520Y310362D01*
X23720D01*
X19360Y306002D01*
Y304152D01*
G01X181266Y234993D02*
X196593D01*
X202590Y240990D01*
Y317890D01*
X261606Y376906D01*
Y395654D01*
X258370Y398890D01*
X249164D01*
X222855Y372581D01*
X153344D01*
X99907Y319144D01*
X24966D01*
X13888Y330222D01*
Y440137D01*
X48400Y474649D01*
Y586000D01*
G01X36524Y392196D02*
X34074D01*
X33460Y391582D01*
X28874D01*
X25981Y394475D01*
G01X306144Y602225D02*
X297783D01*
X295247Y599689D01*
Y575340D01*
X300971Y569616D01*
Y564543D01*
X292953Y556525D01*
X114032D01*
X75326Y595231D01*
Y638800D01*
X69720Y652336D01*
X52164Y669892D01*
X43605D01*
X22030Y691467D01*
Y754315D01*
X15390Y760955D01*
Y768631D01*
X25356Y778597D01*
Y1205682D01*
X22517Y1208521D01*
Y1244629D01*
X23050Y1245162D01*
X27520D01*
G01X27699Y1255381D02*
X32049D01*
G01Y1262074D02*
X27699D01*
G01X46720Y200787D02*
X41306D01*
X41231Y200862D01*
X39575D01*
G01X46720Y192913D02*
X41282D01*
X41231Y192862D01*
X39575D01*
G01X36425Y200862D02*
X33500D01*
G01X36425Y192862D02*
X33670D01*
G01X36145Y208362D02*
X33670D01*
G01X46745Y208661D02*
X41250D01*
X40951Y208362D01*
X39295D01*
G01X46720Y216535D02*
X41124D01*
X40951Y216362D01*
X39295D01*
G01X30795D02*
Y213358D01*
G01Y232362D02*
X33670D01*
G01D02*
X36145D01*
G01X62106Y224409D02*
X42500D01*
G01D02*
X42433Y224342D01*
X39295D01*
G01X46720Y232283D02*
X41030D01*
X40951Y232362D01*
X39295D01*
G01X30795Y224362D02*
Y227366D01*
G01Y240362D02*
X33670D01*
G01D02*
X36145D01*
G01X46359Y240157D02*
X41156D01*
X40951Y240362D01*
X39295D01*
G01X44692Y298707D02*
X40000D01*
G01X44692Y295952D02*
X36000D01*
G01X44692Y293392D02*
X40000D01*
G01X39008Y363337D02*
X35740D01*
G01X39008Y366487D02*
X42809D01*
G01X46834D02*
X42809D01*
G01X39600Y378562D02*
X40400Y379362D01*
X48999D01*
X49468Y379831D01*
Y380803D01*
G01X44700Y375262D02*
X47300Y377862D01*
X49800D01*
X51437Y379499D01*
Y380803D01*
G01X45876Y392269D02*
X39320D01*
G01D02*
X36597D01*
X36524Y392196D01*
G01X36595Y388127D02*
X34860Y386392D01*
X32490D01*
X31099Y387783D01*
G01X36595Y388127D02*
X37420Y387302D01*
X40940D01*
G01D02*
X43939Y390301D01*
X45876D01*
G01Y396207D02*
X45056D01*
X40800Y400463D01*
Y400962D01*
G01D02*
X36098D01*
X36060Y401000D01*
G01X34356Y412914D02*
X44749Y402521D01*
X49949D01*
X51437Y401033D01*
Y399799D01*
G01X49468D02*
Y400977D01*
X49209Y401236D01*
X43954D01*
X38628Y406562D01*
X34440D01*
G01X48191Y994357D02*
X43841D01*
G01X61749Y1252034D02*
X55355D01*
X53664Y1250343D01*
X51394D01*
G01X45039D02*
X40339D01*
X38648Y1252034D01*
X32049D01*
G01X48191Y1255381D02*
X43841D01*
G01X48191Y1252034D02*
X43841D01*
G01X48191Y1248688D02*
X43841D01*
G01X48191Y1258727D02*
X43841D01*
G01X43450Y1638102D02*
X65220D01*
X69449Y1633873D01*
Y1631013D01*
G01X156070Y1695702D02*
Y1682470D01*
X150200Y1676600D01*
Y1667200D01*
X131172Y1648172D01*
X48980D01*
X41660Y1655492D01*
Y1674460D01*
X46464Y1679264D01*
X50896Y1681100D01*
X54232D01*
X62441Y1684500D01*
X66700D01*
X67641Y1683559D01*
X69833D01*
G01X70657Y44370D02*
Y40639D01*
X68160Y38142D01*
X64909D01*
X62340Y40711D01*
Y48211D01*
X56970Y53581D01*
Y59982D01*
X57650Y60662D01*
Y65272D01*
X56370Y66552D01*
G01X68295Y44370D02*
Y41618D01*
X67181Y40504D01*
X64832D01*
X63860Y41476D01*
Y49142D01*
X58260Y54742D01*
Y55902D01*
X59410Y57052D01*
G01X62106Y200787D02*
X46720D01*
G01X62106Y192913D02*
X46720D01*
G01X62106Y208661D02*
X46745D01*
G01X62106Y216535D02*
X46720D01*
G01X62106Y232283D02*
X46720D01*
G01X62106Y240157D02*
X46359D01*
G01X58668Y295952D02*
X62020D01*
G01X49594Y304848D02*
Y297388D01*
X56345Y290637D01*
X58668D01*
G01X51114Y366487D02*
X46834D01*
G01X53406Y380803D02*
Y378468D01*
X50200Y375262D01*
G01D02*
X51114Y374348D01*
Y366487D01*
G01X61280Y380803D02*
Y378342D01*
X63580Y376042D01*
X65710D01*
G01X59311Y380803D02*
Y376451D01*
X63350Y372412D01*
Y371362D01*
G01X57342Y380803D02*
Y375262D01*
G01D02*
Y371019D01*
X59322Y369039D01*
Y366487D01*
G01X55374Y380803D02*
Y378036D01*
X53500Y376162D01*
Y371362D01*
G01D02*
X55190Y369672D01*
Y366487D01*
G01X57299Y766798D02*
X61749D01*
G01X48191Y957546D02*
X52541D01*
G01X48191Y954200D02*
X52541D01*
G01X48191Y1057940D02*
X51461D01*
X52427Y1056974D01*
X53907D01*
X55369Y1058436D01*
Y1059066D01*
X56079Y1059776D01*
X57820D01*
X58316Y1059613D01*
G01X66521D02*
X68696D01*
X69207Y1059102D01*
Y1058429D01*
X69875Y1057761D01*
X71107D01*
X72103Y1058757D01*
X73261D01*
X74078Y1057940D01*
X77891D01*
G01X52820Y1253862D02*
Y1254170D01*
X54031Y1255381D01*
X61749D01*
G01Y1262074D02*
X57399D01*
G01X59833Y1615759D02*
Y1609909D01*
G01D02*
X65120D01*
G01X54333Y1618909D02*
X56833Y1616409D01*
Y1612334D01*
X54408Y1609909D01*
X54333D01*
G01X59212Y1631013D02*
Y1627955D01*
X60333Y1626834D01*
Y1623834D01*
G01D02*
Y1619409D01*
X59833Y1618909D01*
G01X50333D02*
Y1623834D01*
G01D02*
Y1627645D01*
X53701Y1631013D01*
G01X54333Y1618909D02*
X55333Y1619909D01*
Y1623834D01*
G01D02*
Y1626334D01*
X56653Y1627654D01*
Y1631013D01*
G01X47940Y1635504D02*
X65027D01*
X66889Y1633642D01*
Y1631013D01*
G01X57833Y1666259D02*
X59054D01*
X62075Y1663238D01*
Y1661030D01*
G01X53333Y1666259D02*
Y1664814D01*
X54478Y1663669D01*
G01D02*
X59212Y1658935D01*
Y1654045D01*
G01X56653D02*
Y1656329D01*
X54535Y1658447D01*
G01D02*
X49333Y1663649D01*
Y1666259D01*
G01X57833D02*
X56748D01*
X55219Y1667788D01*
Y1673190D01*
X53784Y1674625D01*
X53700D01*
G01X53333Y1669409D02*
Y1671862D01*
G01X48269Y1672771D02*
Y1670473D01*
X49333Y1669409D01*
G01X61000Y1679275D02*
X58325D01*
G01X61000Y1676125D02*
Y1673167D01*
X62833Y1671334D01*
G01X65933Y32756D02*
X65934Y32755D01*
Y32753D01*
X65937Y32750D01*
Y28403D01*
G01X65933Y44370D02*
X65937Y44374D01*
Y48720D01*
G01X94585Y164327D02*
X72275D01*
X67311Y169291D01*
X62106D01*
G01X65710Y376042D02*
Y372232D01*
X67580Y370362D01*
Y366588D01*
X67681Y366487D01*
G01X63350Y371362D02*
Y366566D01*
X63429Y366487D01*
G01X81799Y395865D02*
X76200D01*
G01D02*
X73263D01*
X67699Y390301D01*
X64872D01*
G01Y388333D02*
X69071D01*
X71136Y390398D01*
G01D02*
X72129Y391391D01*
X81799D01*
G01X64872Y386364D02*
X76600D01*
G01D02*
X81661D01*
X81799Y386502D01*
G01Y382219D02*
X80556Y383462D01*
X76100D01*
X74200Y381562D01*
X70500D01*
G01D02*
X67667Y384395D01*
X64872D01*
G01X71480Y399442D02*
Y396052D01*
X67697Y392269D01*
X64872D01*
G01X107591Y1057940D02*
X101242D01*
X99568Y1056266D01*
X94807D01*
G01X88030D02*
X85752D01*
X84077Y1057941D01*
X77892D01*
X77891Y1057940D01*
G01X91449Y1252034D02*
X87022D01*
X85331Y1250343D01*
X81094D01*
G01X74739D02*
X69857D01*
X68166Y1252034D01*
X61749D01*
G01X73541Y1255381D02*
X77891D01*
G01X73541Y1252034D02*
X77891D01*
G01X73541Y1258727D02*
X77891D01*
G01X78456Y1560677D02*
X77625D01*
X75922Y1558974D01*
G01X73389Y1560672D02*
X73439D01*
X73767Y1561000D01*
X74950D01*
X75922Y1561972D01*
Y1562374D01*
G01X77040Y1601102D02*
X72198D01*
X70333Y1602967D01*
Y1615759D01*
G01X65520Y1615972D02*
X63300Y1618192D01*
Y1626482D01*
X61771Y1628011D01*
Y1631013D01*
G01X74100Y1615725D02*
Y1613300D01*
G01X66000Y1623800D02*
Y1626182D01*
X64330Y1627852D01*
Y1631013D01*
G01X70333Y1618909D02*
X67191D01*
X66000Y1620100D01*
Y1623800D01*
G01X74567Y1631013D02*
Y1625233D01*
X76000Y1623800D01*
G01X78000Y1618875D02*
Y1621800D01*
X76000Y1623800D01*
G01X77126Y1631013D02*
Y1626274D01*
X79600Y1623800D01*
X81000D01*
G01X72008Y1631013D02*
Y1628109D01*
X71000Y1627101D01*
Y1623800D01*
G01X74100Y1618875D02*
Y1620700D01*
X71000Y1623800D01*
G01X62075Y1661030D02*
Y1657386D01*
X61771Y1657082D01*
Y1654045D01*
G01X77126D02*
Y1656668D01*
X80550Y1660092D01*
X82211D01*
X83333Y1661214D01*
G01X74567Y1654045D02*
Y1657568D01*
X78333Y1661334D01*
G01X72008Y1654045D02*
Y1660009D01*
X73333Y1661334D01*
G01D02*
X73833Y1661834D01*
Y1666259D01*
G01X69449Y1654045D02*
Y1657218D01*
X68088Y1658579D01*
Y1660691D01*
G01D02*
Y1664514D01*
X69833Y1666259D01*
G01X65088Y1666334D02*
X65833Y1665589D01*
Y1657890D01*
X66889Y1656834D01*
Y1654045D01*
G01X62833Y1671334D02*
Y1665270D01*
X64330Y1663773D01*
Y1654045D01*
G01X77833Y1683559D02*
Y1678902D01*
G01D02*
Y1669409D01*
G01X78333Y1661334D02*
Y1665759D01*
X77833Y1666259D01*
G01X73833Y1683659D02*
Y1674252D01*
G01D02*
Y1669409D01*
G01X69833Y1683559D02*
Y1678582D01*
G01D02*
Y1669409D01*
G01X65000Y1679275D02*
Y1681900D01*
G01X65088Y1666334D02*
X65500Y1666746D01*
Y1673901D01*
X65000Y1674401D01*
Y1676125D01*
G01X78838Y177165D02*
X99480D01*
G01X116920Y207462D02*
X94497Y185039D01*
X78838D01*
G01Y216535D02*
X96880D01*
G01X78838Y232283D02*
X96540D01*
G01X82715Y278798D02*
X87845D01*
G01D02*
X89250Y280203D01*
X93400D01*
G01X82715Y295798D02*
X87845D01*
G01D02*
X89750Y297703D01*
X93400D01*
G01Y285321D02*
X87620D01*
G01D02*
X83656D01*
X82715Y286262D01*
G01X93400Y302821D02*
X87820D01*
G01D02*
X83156D01*
X82715Y303262D01*
G01X81799Y382219D02*
X81816Y382202D01*
Y376026D01*
G01X91376Y424319D02*
X89440Y422383D01*
X83002D01*
X81066Y424319D01*
G01X91376D02*
X94812Y420883D01*
X98896D01*
G01X91376Y420319D02*
X95312Y416383D01*
X96396D01*
G01X91376Y420319D02*
X88440Y417383D01*
X84002D01*
X81066Y420319D01*
G01X88226Y428319D02*
X85826D01*
G01X88226Y438519D02*
X84410D01*
G01X83320Y445212D02*
X86013Y442519D01*
X88226D01*
G01X91376Y446519D02*
Y445669D01*
X88226Y442519D01*
G01X97096Y436383D02*
X94960Y438519D01*
X91376D01*
G01Y442519D02*
X96260D01*
X97396Y441383D01*
G01X91376Y450519D02*
X94001D01*
X94439Y450081D01*
G01X81505Y447377D02*
X87368D01*
X88226Y446519D01*
G01X80300Y641862D02*
X80900Y642462D01*
X83877D01*
X85565Y644150D01*
Y644564D01*
G01X99460Y643414D02*
X97605D01*
X96129Y641938D01*
X92365D01*
X91027Y643276D01*
G01D02*
Y644124D01*
X90587Y644564D01*
X88715D01*
G01X85565Y652564D02*
X83165D01*
G01D02*
X80765D01*
G01X88715D02*
Y651947D01*
X91078Y649584D01*
G01D02*
X93270Y647392D01*
X96484D01*
X97312Y646564D01*
X99460D01*
G01X83208Y646436D02*
Y646271D01*
X81501Y644564D01*
X80765D01*
G01X85565Y648564D02*
Y648327D01*
X83674Y646436D01*
X83208D01*
G01X88715Y648564D02*
X89985Y647294D01*
X90668D01*
X93222Y644740D01*
X94408D01*
G01X99460Y651288D02*
X96393D01*
X93870Y653811D01*
Y656840D01*
X94160Y657130D01*
G01X83250Y665428D02*
X84964Y663714D01*
X85565D01*
G01X89461Y663706D02*
X85573D01*
X85565Y663714D01*
G01X95860Y659622D02*
Y664332D01*
X92458Y667734D01*
X90715D01*
G01X89461Y660556D02*
X91564D01*
X94160Y657960D01*
Y657130D01*
G01X84035Y697604D02*
Y702104D01*
X86373Y704442D01*
X87225D01*
G01X87619Y706411D02*
X84274D01*
X83004Y705141D01*
G01D02*
X82014Y704151D01*
Y702667D01*
G01X86999Y766798D02*
X91449D01*
G01X77891Y957546D02*
X82241D01*
G01X77891Y954200D02*
X82241D01*
G01X77891Y994357D02*
X82241D01*
G01X121149Y1252034D02*
X115196D01*
X113505Y1250343D01*
X110794D01*
G01X104439D02*
X98247D01*
X96556Y1252034D01*
X91449D01*
G01X82241Y1248688D02*
X77891D01*
G01X91449Y1255381D02*
X86407D01*
X85289Y1254263D01*
X84334D01*
G01X91449Y1262074D02*
X87099D01*
G01X88426Y1517237D02*
X89298D01*
X90998Y1518937D01*
G01X93571Y1517237D02*
X92698D01*
X90998Y1515537D01*
G01X87213Y1589872D02*
X89255Y1587830D01*
X94241D01*
X96263Y1589852D01*
G01X106818Y1617262D02*
X102862D01*
X102400Y1616800D01*
Y1614600D01*
X97300Y1609500D01*
X79400D01*
X78000Y1610900D01*
Y1615725D01*
G01X81900D02*
Y1613300D01*
G01X85800Y1615725D02*
Y1613300D01*
G01X100020Y1615821D02*
X97941Y1617900D01*
X89000D01*
X88500Y1618400D01*
Y1625700D01*
X89000Y1626200D01*
X96000D01*
X99900Y1630100D01*
X108300D01*
X113200Y1625200D01*
X138300D01*
G01X81900Y1618875D02*
Y1622900D01*
X81000Y1623800D01*
G01X79685Y1631013D02*
Y1627400D01*
X80185Y1626900D01*
X81600D01*
X84700Y1623800D01*
X86000D01*
G01D02*
Y1621000D01*
X85800Y1620800D01*
Y1618875D01*
G01X90407Y1656672D02*
X91297Y1657562D01*
Y1665305D01*
X90297Y1666305D01*
G01X88333Y1661334D02*
Y1663759D01*
X85833Y1666259D01*
G01X83333Y1661214D02*
Y1664759D01*
X81833Y1666259D01*
G01X90100Y1650862D02*
X88200D01*
X85200Y1653862D01*
Y1656062D01*
X84700Y1656562D01*
X83300D01*
X82637Y1655899D01*
Y1654045D01*
G01X96425Y1651800D02*
X91038D01*
X90100Y1650862D01*
G01X79685Y1654045D02*
Y1656247D01*
X81700Y1658262D01*
X86500D01*
X87600Y1657162D01*
Y1655562D01*
G01D02*
X88562Y1654600D01*
X93100D01*
X94300Y1655800D01*
X96425D01*
G01X99600Y1668332D02*
X98477Y1669455D01*
X90297D01*
G01X99645Y1663217D02*
X101760Y1665332D01*
Y1668862D01*
X98680Y1671942D01*
X88366D01*
X85833Y1669409D01*
G01X81833Y1683559D02*
Y1674526D01*
G01D02*
Y1669409D01*
G01X91795Y1690362D02*
Y1694362D01*
G01X96420Y1693803D02*
X94010D01*
X93451Y1694362D01*
X91795D01*
G01X99980Y1687921D02*
X98789D01*
X93939Y1683071D01*
X91820D01*
G01X88670D02*
X86051D01*
X86030Y1683092D01*
G01X88655Y1686622D02*
Y1683086D01*
X88670Y1683071D01*
G01X96580Y169263D02*
X96740Y169103D01*
Y166482D01*
X94585Y164327D01*
G01X122000Y207362D02*
Y174442D01*
X116821Y169263D01*
X99730D01*
G01X99480Y177165D02*
X102361Y180046D01*
Y182723D01*
X106000Y186362D01*
X109000D01*
G01X96880Y216535D02*
X107879D01*
X107940Y216596D01*
G01X96540Y232283D02*
X107695D01*
X107850Y232128D01*
G01X110937Y278875D02*
X109609Y280203D01*
X100880D01*
G01Y285321D02*
X99368D01*
X98345Y284298D01*
Y280798D01*
X98940Y280203D01*
X100880D01*
G01Y297703D02*
Y285321D01*
G01Y302821D02*
X99368D01*
X97845Y301298D01*
Y298798D01*
X98940Y297703D01*
X100880D01*
G01X110937Y306236D02*
X108483D01*
X106045Y303798D01*
G01D02*
X105068Y302821D01*
X100880D01*
G01X116482Y409571D02*
X110982D01*
X109982Y408571D01*
Y405071D01*
G01X98896Y420883D02*
X102062Y424049D01*
X105967D01*
G01X96396Y416383D02*
X97896D01*
X103003Y421490D01*
X105967D01*
G01X96396Y425383D02*
X97621Y426608D01*
X105967D01*
G01X97496Y446519D02*
X101996Y442019D01*
Y440483D01*
X103075Y439404D01*
X105967D01*
G01Y434286D02*
X99193D01*
X97096Y436383D01*
G01X97396Y441383D02*
X101934Y436845D01*
X105967D01*
G01X97496Y446519D02*
Y447024D01*
X94439Y450081D01*
G01X120713Y519817D02*
Y529589D01*
X116580Y533722D01*
X111620D01*
X108550Y536792D01*
G01D02*
Y539203D01*
X110987Y541640D01*
G01X106547Y639477D02*
Y634169D01*
X106110Y633732D01*
G01X108122Y639477D02*
Y631550D01*
X107489Y630917D01*
G01X109696Y639477D02*
Y631557D01*
X110374Y630879D01*
G01X95725Y654540D02*
X97402Y652863D01*
X99460D01*
G01Y654438D02*
X98363D01*
X97450Y655351D01*
Y658032D01*
X95860Y659622D01*
G01X99460Y644989D02*
X97000D01*
X96751Y644740D01*
X94408D01*
G01X101822Y658375D02*
X101650Y658547D01*
Y661103D01*
X99021Y663732D01*
G01X103397Y658375D02*
Y667272D01*
G01X102420Y697262D02*
X97600Y702085D01*
X97601Y705259D01*
X96449Y706411D01*
X94311D01*
G01X95675Y718880D02*
X95849Y718706D01*
Y716358D01*
G01D02*
Y712760D01*
X95405Y712316D01*
X94705D01*
G01X107591Y957546D02*
X111941D01*
G01X107591Y954200D02*
X111941D01*
G01X107591Y994357D02*
X103241D01*
G01X137291Y1057940D02*
X129120D01*
X127446Y1056266D01*
X124567D01*
G01X117863D02*
X112911D01*
X111237Y1057940D01*
X107591D01*
G01X103241Y1255381D02*
X107591D01*
G01X103241Y1252034D02*
X107591D01*
G01X111941Y1248688D02*
X107591D01*
G01X103241Y1258727D02*
X107591D01*
G01X107199Y1528594D02*
Y1524594D01*
G01D02*
Y1520346D01*
X107170Y1520317D01*
G01D02*
X110860D01*
X112270Y1518907D01*
G01X96263Y1585852D02*
Y1581852D01*
G01X106818Y1589352D02*
X104318D01*
G01D02*
X96763D01*
X96263Y1589852D01*
G01X103902Y1584337D02*
X105466D01*
X106818Y1585689D01*
Y1586793D01*
G01X103902Y1584337D02*
X103264D01*
X101749Y1585852D01*
X96263D01*
G01Y1593867D02*
Y1597867D01*
G01X106818Y1598572D02*
X104613Y1596367D01*
X100620D01*
G01D02*
X97763D01*
X96263Y1597867D01*
G01X96338Y1611821D02*
Y1615821D01*
G01D02*
X100020D01*
G01X96338Y1605867D02*
Y1601867D01*
G01Y1605867D02*
X98738D01*
G01X96338Y1601867D02*
X97538Y1600667D01*
X101363D01*
G01D02*
X104245D01*
X104709Y1601131D01*
X106818D01*
G01X104900Y1611975D02*
X108800D01*
G01D02*
X118843D01*
X123750Y1616882D01*
G01X104900Y1611975D02*
Y1613600D01*
X105400Y1614100D01*
X106200D01*
X106818Y1614718D01*
Y1617262D01*
G01X96248Y1630362D02*
Y1634362D01*
G01X104400Y1632385D02*
X105624D01*
X106818Y1633579D01*
Y1635303D01*
G01X104400Y1632385D02*
X102423Y1634362D01*
X96248D01*
G01X96338Y1623821D02*
Y1619821D01*
G01X106818D02*
X101558D01*
G01X104430Y1628012D02*
X100529D01*
X96338Y1623821D01*
G01X101558Y1619821D02*
X96338D01*
G01X96248Y1638362D02*
Y1642362D01*
G01X106818Y1637862D02*
X104318D01*
G01D02*
X96748D01*
X96248Y1638362D01*
G01X117100Y1651800D02*
X99575D01*
G01X104500Y1655800D02*
X99575D01*
G01X369300Y1682900D02*
X368602D01*
X359600Y1673898D01*
Y1657198D01*
X348902Y1646500D01*
X304933D01*
X287033Y1628600D01*
X223000D01*
X216400Y1635200D01*
X210946D01*
X203600Y1642546D01*
Y1680846D01*
X188146Y1696300D01*
X163946D01*
X160146Y1700100D01*
X154500D01*
X150500Y1696100D01*
Y1683900D01*
X145500Y1678900D01*
Y1669500D01*
X131800Y1655800D01*
X104500D01*
G01X109960Y1682803D02*
Y1677362D01*
G01D02*
X118645D01*
X121645Y1674362D01*
G01X102480Y1693803D02*
X96420D01*
G01X109960D02*
X112401Y1691362D01*
X114720D01*
G01X121645Y1688362D02*
X121204Y1687921D01*
X109960D01*
G01X102480D02*
X104661D01*
X105220Y1687362D01*
Y1683362D01*
X104661Y1682803D01*
X102480D01*
G01Y1687921D02*
X99980D01*
G01X114991Y1702633D02*
X111279Y1698921D01*
X109960D01*
G01X102480D02*
X99980D01*
G01X112150Y186362D02*
X115850D01*
G01X111090Y216596D02*
X113490D01*
G01X111000Y232128D02*
X113400D01*
G01X114087Y278875D02*
X118920D01*
G01D02*
X123844D01*
G01X110937Y274800D02*
Y278875D01*
G01X114087Y274800D02*
X118820D01*
G01X123825D02*
Y272175D01*
X124800Y271200D01*
X133200D01*
X134400Y272400D01*
Y305400D01*
X153000Y324000D01*
Y366600D01*
X155400Y369000D01*
X237000D01*
X252000Y384000D01*
Y395400D01*
G01X118820Y274800D02*
X123825D01*
G01X114087Y306236D02*
X119220D01*
G01D02*
X123844D01*
G01X113907Y392071D02*
X115907Y390071D01*
X129482D01*
X130557Y391146D01*
Y392071D01*
G01X117057D02*
X119457D01*
G01X113907Y388071D02*
X115907Y386071D01*
X129482D01*
X130557Y387146D01*
Y388071D01*
G01X117057D02*
X119457D01*
G01X120057Y404571D02*
Y408496D01*
X118982Y409571D01*
X116482D01*
G01X120057Y404571D02*
X127407D01*
G01X153360Y449112D02*
Y468684D01*
X147291Y474753D01*
X125651D01*
X124170Y476234D01*
Y480238D01*
G01X120060D02*
X124170D01*
G01Y483388D02*
X130317D01*
G01X120060D02*
X117824D01*
X116171Y485041D01*
G01X129480Y536662D02*
X125610Y532792D01*
Y523212D01*
X127012Y521810D01*
Y519817D01*
G01X125438D02*
Y521654D01*
X124340Y522752D01*
Y536632D01*
X124435Y536727D01*
G01X123863Y519817D02*
Y521559D01*
X123110Y522312D01*
Y532632D01*
X118880Y536862D01*
G01X122288Y519817D02*
Y521273D01*
X121970Y521591D01*
Y530452D01*
X117480Y534942D01*
X115550D01*
X113700Y536792D01*
G01X124435Y536727D02*
Y538976D01*
X123257Y540154D01*
Y541810D01*
G01X118880Y536862D02*
Y539857D01*
X119087Y540064D01*
Y541720D01*
G01X113700Y536792D02*
Y540287D01*
X115060Y541647D01*
G01X111271Y639477D02*
Y633571D01*
X111920Y632922D01*
G01X112846Y639477D02*
Y634726D01*
X114540Y633032D01*
G01X114421Y639477D02*
Y636561D01*
X115704Y635278D01*
G01D02*
X117750Y633232D01*
G01X115996Y639477D02*
Y637791D01*
X120440Y633347D01*
G01X116567Y766775D02*
X116590Y766798D01*
X121149D01*
G01X150849Y1252034D02*
X146524D01*
X144833Y1250343D01*
X140494D01*
G01X134139D02*
X130119D01*
X128428Y1252034D01*
X121149D01*
G01X114191Y1254604D02*
X114968Y1255381D01*
X121149D01*
G01Y1262074D02*
X116799D01*
G01X114298Y1591911D02*
Y1589352D01*
G01X119483D02*
X116798D01*
G01D02*
X114298D01*
G01X172099Y1588141D02*
X132439D01*
X123230Y1597350D01*
G01X114298Y1603690D02*
X113027D01*
X112458Y1603121D01*
Y1601641D01*
X112968Y1601131D01*
X114298D01*
G01D02*
X119263D01*
G01D02*
X121027D01*
X124263Y1604367D01*
G01X119500Y1622380D02*
X124924D01*
X124983Y1622321D01*
G01X114298Y1622380D02*
X119500D01*
G01X114298D02*
X112180D01*
X111700Y1621900D01*
Y1620200D01*
X112079Y1619821D01*
X114298D01*
G01X366700Y1649000D02*
X364501D01*
X353231Y1637730D01*
X308130D01*
X288900Y1618500D01*
X191100D01*
X189482Y1616882D01*
X123750D01*
G01X114298Y1640421D02*
Y1637862D01*
G01D02*
X119058D01*
G01D02*
X123983D01*
G01X369300Y1680400D02*
X367800D01*
X360800Y1673400D01*
Y1656700D01*
X349400Y1645300D01*
X305303D01*
X287303Y1627300D01*
X220900D01*
X214800Y1633400D01*
X210200D01*
X201800Y1641800D01*
Y1680100D01*
X187400Y1694500D01*
X163200D01*
X159400Y1698300D01*
X155057D01*
X152100Y1695343D01*
Y1683243D01*
X146800Y1677943D01*
Y1668243D01*
X130357Y1651800D01*
X117100D01*
G01X124795Y1678362D02*
Y1681846D01*
G01X121645Y1678362D02*
Y1683362D01*
G01X124795Y1674362D02*
X128195D01*
G01X121645Y1670362D02*
Y1674362D01*
G01Y1696362D02*
Y1700362D01*
G01Y1696362D02*
Y1692362D01*
G01X114720Y1691362D02*
X120645D01*
X121645Y1692362D01*
G01Y1683362D02*
Y1688362D01*
G01X124795Y1700362D02*
X127195D01*
G01X124795Y1704362D02*
X127195D01*
G01X121645D02*
X116720D01*
X114991Y1702633D01*
G01X121645Y1704362D02*
Y1708362D01*
G01X120910Y1726622D02*
X117426D01*
G01X127482Y1731182D02*
X125470D01*
X120910Y1726622D01*
G01X125720Y1719262D02*
Y1721337D01*
X127482Y1723099D01*
Y1723182D01*
G01X145624Y394385D02*
X140168D01*
X137482Y397071D01*
X135220D01*
G01D02*
X131557D01*
X130557Y396071D01*
G01Y384071D02*
X138482D01*
G01D02*
X139482D01*
X142296Y386885D01*
X145624D01*
G01X130557Y392071D02*
X131367Y392881D01*
X138482D01*
G01D02*
X141172D01*
X142168Y391885D01*
X145624D01*
G01X130557Y388071D02*
X131057Y388571D01*
X135482D01*
G01D02*
X140482D01*
X141296Y389385D01*
X145624D01*
G01Y404385D02*
X135482D01*
G01D02*
X130743D01*
X130557Y404571D01*
G01X143821Y427383D02*
X141321Y429883D01*
X134896D01*
G01X128015Y426608D02*
X138896D01*
G01D02*
X140596D01*
X143821Y423383D01*
G01Y419383D02*
X140321Y422883D01*
X134896D01*
G01D02*
X132396D01*
X131230Y424049D01*
X128015D01*
G01X143821Y443383D02*
X134896D01*
G01D02*
Y443382D01*
X130918Y439404D01*
X128015D01*
G01X134896Y429883D02*
X132396D01*
X131680Y429167D01*
X128015D01*
G01X143821Y431383D02*
X141821Y433383D01*
X138896D01*
G01D02*
X132896D01*
X131240Y431727D01*
X128015D01*
G01X143821Y439383D02*
X143321Y439883D01*
X138896D01*
G01D02*
X134397D01*
X131359Y436845D01*
X128015D01*
G01X143821Y435383D02*
X142821Y436383D01*
X134896D01*
G01D02*
X133396D01*
X131299Y434286D01*
X128015D01*
G01X136982Y497090D02*
Y495666D01*
X135006Y493690D01*
G01X130006D02*
X131287D01*
X131737Y494140D01*
Y496295D01*
G01X141103Y480238D02*
X145213D01*
G01X135006Y490540D02*
Y487753D01*
G01D02*
Y485725D01*
X135317Y485414D01*
Y483388D01*
G01X141103D02*
X135317D01*
G01Y480238D02*
X138042D01*
G01X130006Y490540D02*
X131295Y489251D01*
Y487822D01*
G01D02*
X130317Y486844D01*
Y483388D01*
G01Y480238D02*
X132833D01*
G01X143922Y502810D02*
X142321D01*
X141325Y503806D01*
G01D02*
X139433D01*
X136808Y506431D01*
X135674D01*
G01Y504856D02*
X136754D01*
X141220Y500390D01*
Y498810D01*
G01D02*
X143922D01*
G01X133312Y500919D02*
Y498128D01*
X134350Y497090D01*
X136982D01*
G01X131737Y496295D02*
Y500919D01*
G01X143887Y506533D02*
X142960Y505606D01*
X140168D01*
X138408Y507366D01*
G01D02*
X137768Y508006D01*
X135674D01*
G01X139837Y518725D02*
X138841D01*
X137571Y517455D01*
X135674D01*
G01X141329Y510487D02*
X141021Y510795D01*
X137698D01*
X137338Y511155D01*
X135674D01*
G01Y515880D02*
X138580D01*
X139153Y516453D01*
G01D02*
X141565D01*
X143922Y518810D01*
G01X135674Y512730D02*
X138698D01*
X138878Y512550D01*
G01D02*
X142182D01*
X143922Y510810D01*
G01Y514810D02*
X143417Y514305D01*
X139961D01*
G01D02*
X135674D01*
G01X127377Y541880D02*
Y540224D01*
X127427Y540174D01*
Y538715D01*
X129480Y536662D01*
G01X137291Y957546D02*
X141641D01*
G01X137291Y954200D02*
X141641D01*
G01X137291Y994357D02*
X141641D01*
G01X137291Y1057940D02*
X141641D01*
G01X132941Y1255381D02*
X137291D01*
G01X132941Y1252034D02*
X137291D01*
G01X141641Y1248688D02*
X137291D01*
G01X132941Y1258727D02*
X137291D01*
G01X138300Y1625200D02*
X159500D01*
X165700Y1619000D01*
X187700D01*
X197350Y1628650D01*
X213350D01*
X217500Y1624500D01*
X287642D01*
X287932Y1624790D01*
X287933D01*
X306073Y1642930D01*
X350650D01*
X363800Y1656080D01*
Y1666500D01*
X369624Y1672324D01*
X375550D01*
G01X130632Y1723182D02*
Y1727182D01*
G01D02*
X131801D01*
X132726Y1728107D01*
X134557D01*
G01D02*
Y1722778D01*
G01D02*
X137259D01*
X142329Y1727848D01*
X144883D01*
G01Y1730408D02*
X142194D01*
X138358Y1726572D01*
X137852D01*
G01D02*
Y1729538D01*
X136133Y1731257D01*
X134557D01*
G01X130632Y1731182D02*
X130707Y1731257D01*
X134557D01*
G01X149043Y32756D02*
Y29377D01*
X147924Y28258D01*
G01X149043Y44370D02*
X149047Y44374D01*
Y48454D01*
X148784Y48717D01*
Y48720D01*
G01X152877Y411530D02*
Y409723D01*
X153238Y409362D01*
X158325D01*
G01Y413362D02*
X153417D01*
X152877Y412822D01*
Y411530D01*
G01X155226Y425383D02*
Y427383D01*
X153226Y429383D01*
X145896D01*
X143896Y427383D01*
X143821D01*
G01X158376Y421383D02*
X160231Y423238D01*
X164827D01*
X166917Y421148D01*
G01X155226Y421383D02*
X151226Y425383D01*
X145821D01*
X143821Y423383D01*
G01X155226Y417383D02*
X151282Y421327D01*
X145765D01*
X143821Y419383D01*
G01X158376Y417383D02*
Y413413D01*
X158325Y413362D01*
G01X158376Y443319D02*
Y444363D01*
X159396Y445383D01*
X165821D01*
X167359Y443845D01*
G01X155226Y443319D02*
X152662Y445883D01*
X145396D01*
X143821Y444308D01*
Y443383D01*
G01X155226Y430883D02*
X152518D01*
X150018Y433383D01*
X145821D01*
X143821Y431383D01*
G01X155226Y439397D02*
X152826D01*
G01X158376D02*
X156390Y441383D01*
X145821D01*
X143821Y439383D01*
G01X155226Y435383D02*
X153847D01*
X152826Y434362D01*
G01X158376Y435383D02*
X156376Y437383D01*
X145896D01*
X143896Y435383D01*
X143821D01*
G01X145213Y480238D02*
X154664Y470787D01*
X159204D01*
X159714Y470277D01*
Y468287D01*
X159204Y467777D01*
X156816D01*
X156306Y467267D01*
Y465277D01*
X156816Y464767D01*
X159204D01*
X159714Y464257D01*
Y462267D01*
X159204Y461757D01*
X156816D01*
X156306Y461247D01*
Y459257D01*
X156816Y458747D01*
X159204D01*
X159714Y458237D01*
Y456247D01*
X159204Y455737D01*
X156816D01*
X156306Y455227D01*
Y449045D01*
G01X145213Y483388D02*
Y483587D01*
X150113Y488487D01*
G01X149174Y483388D02*
X145213D01*
G01X172632Y454095D02*
X162663D01*
X162163Y454595D01*
Y474880D01*
X156805Y480238D01*
X149174D01*
G01X160000Y510052D02*
X159311Y509363D01*
X150579D01*
X149132Y510810D01*
X147072D01*
G01X152470Y502788D02*
X150525Y504733D01*
X148837D01*
X147037Y506533D01*
G01X208200Y493510D02*
X181440D01*
X178140Y496810D01*
X162530D01*
X156552Y502788D01*
X152470D01*
G01X149504Y519881D02*
X148433Y518810D01*
X147072D01*
G01X152733Y519281D02*
Y517303D01*
X152283Y516853D01*
X147592D01*
X147072Y516333D01*
Y514810D01*
G01X154647Y521783D02*
X153183D01*
X152733Y521333D01*
Y519281D01*
G01X151378Y526924D02*
X151284Y526830D01*
X147072D01*
G01X146367Y766775D02*
X150826D01*
X150849Y766798D01*
G01Y1252034D02*
X156006D01*
X158218Y1249822D01*
X162330D01*
X162851Y1250343D01*
X163839D01*
G01X170194D02*
X172865D01*
X174556Y1252034D01*
X180549D01*
G01X143675Y1255567D02*
Y1255476D01*
X143770Y1255381D01*
X150849D01*
G01Y1262074D02*
X146499D01*
G01X159351Y1403338D02*
Y1405180D01*
X157884Y1406647D01*
Y1411272D01*
X156983Y1412173D01*
G01X147800Y1414500D02*
X149330Y1416030D01*
X155470D01*
X156983Y1414517D01*
Y1412173D01*
G01X368600Y1543200D02*
X356800Y1531400D01*
Y1512600D01*
X349800Y1505600D01*
X153600D01*
G01X151295Y1716362D02*
Y1712362D01*
G01D02*
X151348D01*
X152118Y1711592D01*
X158118D01*
G01X164920Y1712017D02*
X158543D01*
X158118Y1711592D01*
G01X161310Y1708022D02*
X158538D01*
X158118Y1708442D01*
G01D02*
X155914Y1706238D01*
X154473D01*
X152349Y1708362D01*
X151295D01*
G01X148145D02*
X143895D01*
G01X148145Y1701862D02*
Y1708362D01*
G01X155145Y1716362D02*
Y1713517D01*
G01X163060Y1717017D02*
X158693D01*
X158295Y1716619D01*
Y1716362D01*
G01X144520Y1717562D02*
X144820Y1717262D01*
X147298D01*
X148145Y1716415D01*
Y1716362D01*
G01X166274Y230928D02*
Y232446D01*
X168821Y234993D01*
X181266D01*
G01X175982Y383071D02*
X173482D01*
X169668Y386885D01*
X166530D01*
G01X180907Y389071D02*
X179407Y387571D01*
X173482D01*
G01D02*
X171482D01*
X169668Y389385D01*
X166530D01*
G01X175982Y392071D02*
X174843Y390932D01*
X170749D01*
X169796Y391885D01*
X166530D01*
G01X173275Y393497D02*
X172387Y394385D01*
X166530D01*
G01X173482Y396571D02*
X170482D01*
X170168Y396885D01*
X166530D01*
G01X173482Y396571D02*
X178375D01*
G01X175982Y401071D02*
X173482D01*
X171796Y399385D01*
X166530D01*
G01X161526Y425383D02*
X163926D01*
G01X172321Y421383D02*
X172086Y421148D01*
X166917D01*
G01X181821Y421383D02*
X179966Y423238D01*
X174176D01*
X172321Y421383D01*
G01X161526D02*
X162979D01*
X164000Y420362D01*
G01X161526Y417383D02*
X161979D01*
X164000Y415362D01*
G01X172321Y443383D02*
X167821D01*
X167359Y443845D01*
G01X181821Y443383D02*
X179932Y445272D01*
X174110D01*
X172321Y443483D01*
Y443383D01*
G01X161526Y443319D02*
X163926D01*
G01X161526Y430883D02*
X163926D01*
G01X161526Y439397D02*
X163926D01*
G01X161526Y435383D02*
X163926D01*
G01X166991Y957546D02*
X171341D01*
G01X166991Y954200D02*
X171341D01*
G01X166991Y994357D02*
X162641D01*
G01X196691Y1057940D02*
X192878D01*
X192061Y1058757D01*
X190903D01*
X189907Y1057761D01*
X188675D01*
X188007Y1058429D01*
Y1059102D01*
X187496Y1059613D01*
X183875D01*
G01X177234D02*
X174716D01*
X174169Y1059066D01*
Y1058436D01*
X172727Y1056994D01*
X169897D01*
X168951Y1057940D01*
X166991D01*
G01X162641Y1255381D02*
X166991D01*
G01X162641Y1252034D02*
X166991D01*
G01X171341Y1248688D02*
X166991D01*
G01X171947Y1255837D02*
X172403Y1255381D01*
X180549D01*
G01X162641Y1258727D02*
X166991D01*
G01X176793Y1579399D02*
X173331D01*
G01X170829Y1712797D02*
X167818D01*
X167038Y1712017D01*
X164920D01*
G01X170829Y1710237D02*
X166464D01*
X164249Y1708022D01*
X161310D01*
G01X175067Y1730017D02*
X172777Y1727727D01*
Y1725453D01*
X171657Y1724333D01*
X168618D01*
X165103Y1727848D01*
X162461D01*
G01X178226Y1726517D02*
Y1729538D01*
X177747Y1730017D01*
X175067D01*
G01X170829Y1715356D02*
X167779D01*
X166118Y1717017D01*
X163060D01*
G01X174992Y1723592D02*
X173335D01*
X172962Y1723219D01*
Y1721234D01*
G01D02*
Y1721229D01*
X169303D01*
X165243Y1725289D01*
X162461D01*
G01X175067Y1733167D02*
X169777Y1727877D01*
Y1726517D01*
G01D02*
X165886Y1730408D01*
X162461D01*
G01X181992Y1733092D02*
X181917Y1733167D01*
X175067D01*
G01X180907Y385071D02*
X178907Y383071D01*
X175982D01*
G01X190880Y383012D02*
X182966D01*
X180907Y385071D01*
G01X190880Y387162D02*
X182816D01*
X180907Y389071D01*
G01Y393071D02*
X176982D01*
X175982Y392071D01*
G01X190880Y391082D02*
X182896D01*
X180907Y393071D01*
G01X175982Y401071D02*
X181845D01*
G01X187371Y447172D02*
X189368Y445175D01*
X202119D01*
X204699Y447755D01*
G01X178546Y453806D02*
X180868Y451484D01*
X189899D01*
X190801Y450582D01*
X202026D01*
X204699Y453255D01*
G01X176099Y766798D02*
X180549D01*
G01X210248Y1252033D02*
X205627D01*
X203937Y1250343D01*
X199894D01*
G01X193539D02*
X188977D01*
X187286Y1252034D01*
X180549D01*
G01Y1262074D02*
X176199D01*
G01X188407Y1712797D02*
X191234D01*
X192954Y1714517D01*
X195590D01*
G01X188407Y1710237D02*
X191678D01*
X192898Y1709017D01*
X196010D01*
G01X181992Y1729092D02*
Y1723592D01*
G01Y1729092D02*
X179417Y1726517D01*
X178226D01*
G01X188794Y1725092D02*
X187294Y1723592D01*
X185142D01*
G01X178142D02*
Y1720652D01*
G01X185142Y1733092D02*
X185212Y1733022D01*
X199050D01*
G01X195050Y412055D02*
X201999D01*
X204699Y414755D01*
G01X211979Y428735D02*
X207679D01*
X204699Y425755D01*
G01Y423242D02*
Y425755D01*
G01Y431255D02*
Y428742D01*
G01X211979Y420735D02*
X205999Y414755D01*
X204699D01*
G01X195050Y417465D02*
X201909D01*
X204699Y420255D01*
G01X211979Y424735D02*
X207499Y420255D01*
X204699D01*
G01X211979Y444735D02*
X207719D01*
X204699Y447755D01*
G01X194440Y433895D02*
X201839D01*
X204699Y436755D01*
G01X211979Y436735D02*
X211959Y436755D01*
X204699D01*
G01X211979Y440735D02*
X206219D01*
X204699Y442255D01*
G01X194440Y439565D02*
X202009D01*
X204699Y442255D01*
G01X211979Y432735D02*
X210499Y431255D01*
X204699D01*
G01Y458755D02*
X202139Y456195D01*
X198133D01*
X197650Y455712D01*
G01X211979Y452735D02*
X210719D01*
X204699Y458755D01*
G01X211979Y448735D02*
X209219D01*
X204699Y453255D01*
G01X215129Y457222D02*
X212466Y459885D01*
X207569D01*
X204699Y462755D01*
G01X215129Y462235D02*
Y462335D01*
X209209Y468255D01*
X204699D01*
G01X204723Y577764D02*
X203448D01*
X202903Y577538D01*
X201662Y576297D01*
X196789D01*
X195888Y575396D01*
G01X204723Y611764D02*
X203448D01*
X202903Y611538D01*
X201662Y610297D01*
X196789D01*
X195888Y609396D01*
G01X204723Y645764D02*
X203448D01*
X202903Y645538D01*
X201662Y644297D01*
X196789D01*
X195888Y643396D01*
G01X210249Y766798D02*
X205799D01*
G01X196691Y957546D02*
X201041D01*
G01X196691Y954200D02*
X201041D01*
G01X196691Y994357D02*
X201041D01*
G01X226391Y1057940D02*
X217586D01*
X215913Y1059613D01*
X213612D01*
G01X206876D02*
X203704D01*
X202031Y1057940D01*
X196691D01*
G01X192341Y1255381D02*
X196691D01*
G01X192341Y1252034D02*
X196691D01*
G01X201041Y1248688D02*
X196691D01*
G01X201193Y1257900D02*
X201484Y1257609D01*
Y1257527D01*
X203630Y1255381D01*
X210249D01*
G01X192341Y1258727D02*
X196691D01*
G01X205899Y1262074D02*
X210249D01*
G01X195126Y1412173D02*
X196210Y1411089D01*
Y1406482D01*
X197494Y1405198D01*
Y1403338D01*
G01X415795Y1668362D02*
Y1666606D01*
X415792Y1666603D01*
Y1666434D01*
X415220Y1665862D01*
X388880D01*
X384320Y1670422D01*
X371280D01*
X365600Y1664742D01*
Y1655461D01*
X351359Y1641220D01*
X306782D01*
X288352Y1622790D01*
X288351D01*
X288061Y1622500D01*
X215800D01*
X211900Y1626400D01*
X204738D01*
X203120Y1624782D01*
G01X205043Y1718017D02*
Y1714017D01*
G01D02*
X204118Y1713092D01*
X202821D01*
X202476Y1713437D01*
X200720D01*
G01X195590Y1714517D02*
X197884D01*
X198964Y1713437D01*
X200720D01*
G01X205145Y1709862D02*
X203489D01*
X203334Y1710017D01*
X202746D01*
X202476Y1710287D01*
X200720D01*
G01X196010Y1709017D02*
X199619D01*
X200720Y1710118D01*
Y1710287D01*
G01X199050Y1733022D02*
Y1726431D01*
G01X365771Y449480D02*
Y448611D01*
X333936Y416776D01*
X310682D01*
X216480Y322574D01*
Y280416D01*
X230065Y266831D01*
Y180292D01*
X234902Y175455D01*
Y174047D01*
G01X245094Y278685D02*
Y286727D01*
X221152Y310669D01*
Y323044D01*
X298479Y400371D01*
X327060D01*
G01X232494Y278685D02*
Y297757D01*
X220042Y310209D01*
Y323504D01*
X305990Y409452D01*
X327150D01*
G01X228024Y316772D02*
X226115Y318681D01*
X222907D01*
G01X224210Y431501D02*
X223361Y432350D01*
X220315D01*
X218107Y430142D01*
X216536D01*
X215129Y428735D01*
G01X224305Y422977D02*
X222063Y420735D01*
X215129D01*
G01X229825Y426383D02*
X226049D01*
X224305Y424639D01*
Y422977D01*
G01X219995Y426267D02*
X218463Y424735D01*
X215129D01*
G01X229825Y428942D02*
X222670D01*
X219995Y426267D01*
G01X229825Y436619D02*
X224210D01*
G01D02*
X221170D01*
X221054Y436735D01*
X215129D01*
G01Y440735D02*
X218140D01*
G01D02*
X219044D01*
X220600Y439179D01*
X229825D01*
G01X224210Y431501D02*
X229825D01*
G01X215129Y432735D02*
X218010D01*
G01D02*
X219335Y434060D01*
X229825D01*
G01Y441738D02*
X225051D01*
X223664Y443125D01*
G01D02*
X222054Y444735D01*
X215129D01*
G01Y457222D02*
Y457235D01*
X216129Y458235D01*
X223554D01*
G01D02*
X224554Y457235D01*
Y451735D01*
X226874Y449415D01*
X229825D01*
G01X215129Y448735D02*
X220000D01*
G01D02*
X221554D01*
X225992Y444297D01*
X229825D01*
G01Y446856D02*
X226006D01*
X220200Y452662D01*
Y454162D01*
G01D02*
X218773Y452735D01*
X215129D01*
G01Y462235D02*
X220054D01*
G01D02*
X223554D01*
X226054Y459735D01*
Y452735D01*
X226815Y451974D01*
X229825D01*
G01X226391Y957546D02*
X222041D01*
G01X226391Y954200D02*
X222041D01*
G01Y994357D02*
X226391D01*
G01X210249Y1252034D02*
X210248Y1252033D01*
G01X239949Y1252034D02*
X232473D01*
X230782Y1250343D01*
X229594D01*
G01X223239D02*
X218847D01*
X217157Y1252033D01*
X210248D01*
G01X222041Y1255381D02*
X226391D01*
G01X219660Y1260492D02*
X221425Y1258727D01*
X226391D01*
G01X222041Y1252034D02*
X226391D01*
G01X415795Y1672362D02*
X417220D01*
X418620Y1670962D01*
Y1666362D01*
X416410Y1664152D01*
X387480D01*
X383010Y1668622D01*
X372430D01*
X367480Y1663672D01*
Y1654922D01*
X352068Y1639510D01*
X307491D01*
X288771Y1620790D01*
X288770D01*
X288190Y1620210D01*
X212122D01*
X208115Y1624217D01*
G01X375430Y1676462D02*
X373792Y1678100D01*
X368500D01*
X362300Y1671900D01*
Y1656600D01*
X349740Y1644040D01*
X305613D01*
X287763Y1626190D01*
X287762D01*
X287472Y1625900D01*
X219000D01*
X213758Y1631142D01*
X209820D01*
G01X214120Y1713462D02*
X214220Y1713562D01*
Y1715572D01*
X211775Y1718017D01*
X208193D01*
G01X208295Y1709862D02*
X208320Y1709837D01*
X212120D01*
G01X208295Y1703362D02*
Y1709862D01*
G01X233335Y32756D02*
X233336Y32755D01*
Y17665D01*
X233339Y17662D01*
G01X235697Y32756D02*
Y21586D01*
X235701Y21582D01*
G01X240421Y32756D02*
Y21211D01*
X241310Y20322D01*
G01X238059Y32756D02*
Y26236D01*
X238063Y26232D01*
G01X233335Y44370D02*
Y51478D01*
X237220Y55363D01*
Y57362D01*
G01X240421Y44370D02*
Y51564D01*
X242220Y53363D01*
Y57362D01*
G01X238059Y44370D02*
Y52601D01*
X239820Y54362D01*
G01X237220Y65437D02*
Y74862D01*
X239010Y76652D01*
Y78542D01*
G01X237220Y62287D02*
Y57362D01*
G01X239720Y71862D02*
Y69861D01*
X241220Y68361D01*
Y65437D01*
G01X239010Y78542D02*
X241690Y75862D01*
X242145D01*
G01Y71862D02*
X239720D01*
G01X243487Y107835D02*
X237933D01*
G01X238297Y129703D02*
Y127118D01*
G01X230445Y154126D02*
X229789D01*
X227500Y151837D01*
Y144262D01*
X233400Y138362D01*
X257173D01*
X259933Y141122D01*
G01X236920Y146829D02*
X240409D01*
X240459Y146879D01*
X242215D01*
G01X236920Y146829D02*
X234216Y144125D01*
Y142153D01*
X234125Y142062D01*
G01X233595Y154126D02*
Y159071D01*
G01X237400Y163962D02*
X239530Y161832D01*
Y158572D01*
X240499Y157603D01*
X242255D01*
G01X237400Y163962D02*
X236030Y162592D01*
Y159850D01*
X235251Y159071D01*
X233595D01*
G01X267759Y262672D02*
X265069Y265362D01*
X238300D01*
X228754Y274908D01*
Y278685D01*
G01X279400Y296463D02*
X275691Y300172D01*
X248310D01*
X240624Y307858D01*
Y311334D01*
G01X228024D02*
Y316772D01*
G01X231764Y311334D02*
Y317906D01*
X311850Y397992D01*
X345890D01*
X360870Y412972D01*
X415710D01*
G01X360880Y400628D02*
X359310D01*
X344098Y385416D01*
X311037D01*
X238300Y312679D01*
Y305382D01*
X245830Y297852D01*
X254799D01*
X270294Y282357D01*
Y278685D01*
G01X257694D02*
Y283749D01*
X237190Y304253D01*
Y313140D01*
X312293Y388243D01*
X327550D01*
G01X239949Y766798D02*
X235499D01*
G01X226391Y1057940D02*
X232418D01*
X234146Y1059668D01*
X235379D01*
G01X244677Y1059616D02*
X245828D01*
X247504Y1057940D01*
X256091D01*
G01X226391Y1248688D02*
X230741D01*
G01X230864Y1254295D02*
X231950Y1255381D01*
X239949D01*
G01X235599Y1262074D02*
X239949D01*
G01X242783Y32756D02*
Y26620D01*
X242784Y26617D01*
X246510Y22891D01*
Y20362D01*
G01X245146Y32756D02*
Y28066D01*
X246360Y26852D01*
G01X245146Y44370D02*
Y50288D01*
X252220Y57362D01*
G01X242783Y44370D02*
Y50694D01*
X247220Y55131D01*
Y57362D01*
G01X249220Y62287D02*
Y60362D01*
X252220Y57362D01*
G01X247220D02*
Y60287D01*
X245220Y62287D01*
G01X242220Y57362D02*
X241220Y58362D01*
Y62287D01*
G01X249885Y69623D02*
X249220Y68958D01*
Y65437D01*
G01X245220D02*
Y67862D01*
G01X253090Y87362D02*
X253271Y87543D01*
X257722D01*
G01X256978Y107835D02*
X251487D01*
G01X243487D02*
X247487D01*
G01D02*
X251487D01*
G01X253878Y111771D02*
X250400D01*
X250372Y111743D01*
G01X256978Y111771D02*
X253878D01*
G01X254825Y151937D02*
X252326Y149438D01*
X249695D01*
G01X260100Y153887D02*
X260016D01*
X258066Y151937D01*
X254825D01*
G01X242215Y146879D02*
X243553D01*
X244333Y146099D01*
Y144965D01*
X243688Y144320D01*
X242215D01*
G01X249695Y146879D02*
X254940D01*
G01D02*
X254942Y146877D01*
X259933D01*
G01X254756Y159877D02*
X256715D01*
X259500Y162662D01*
G01X249735Y160162D02*
X248220D01*
X247720Y159662D01*
Y158232D01*
X248349Y157603D01*
X249735D01*
G01X259500Y162662D02*
X252235D01*
X249735Y160162D01*
G01X245490Y159702D02*
Y156582D01*
X243952Y155044D01*
X242255D01*
G01X253954Y278685D02*
Y275928D01*
X256630Y273252D01*
X270900D01*
X276620Y267532D01*
Y262572D01*
G01X241354Y278685D02*
Y277028D01*
X247690Y270692D01*
X267530D01*
X271620Y266602D01*
G01X260300Y304762D02*
X255510D01*
X253224Y307048D01*
Y311334D01*
G01X244364D02*
X307947Y374917D01*
X327470D01*
G01X255810Y405582D02*
X263090D01*
X273230Y415722D01*
Y426062D01*
X272557Y426735D01*
X269629D01*
G01X252500Y415862D02*
Y412936D01*
X255247Y410189D01*
X263673D01*
X269611Y416127D01*
Y418579D01*
G01X258066Y426735D02*
X256054D01*
X255702Y426383D01*
X251873D01*
G01Y423824D02*
X255465D01*
X257054Y422235D01*
X263430D01*
G01X262963Y443735D02*
X256054D01*
X255492Y444297D01*
X251873D01*
G01Y446856D02*
X256443D01*
X258339Y448752D01*
X263040D01*
G01X257750Y450842D02*
X256323Y449415D01*
X251873D01*
G01X256091Y957546D02*
X251741D01*
G01X256091Y954200D02*
X251741D01*
G01Y994357D02*
X256091D01*
G01Y1057940D02*
X260441D01*
G01X248047Y1259155D02*
Y1257815D01*
X248557Y1257305D01*
X252357D01*
X254281Y1255381D01*
X256091D01*
G01X250467Y1259175D02*
X251247Y1259955D01*
X252657D01*
X253885Y1258727D01*
X256091D01*
G01X251707Y1252034D02*
X256091D01*
G01Y1248688D02*
X260441D01*
G01X266427Y115315D02*
Y124975D01*
X265910Y125492D01*
G01X264459Y115315D02*
Y120634D01*
X264171Y120922D01*
X263550D01*
G01X268395Y115315D02*
Y120296D01*
X269191Y121092D01*
G01X265910Y125492D02*
Y125893D01*
X267485Y127468D01*
X268297D01*
G01X263550Y120922D02*
Y121543D01*
X261297Y123796D01*
Y123968D01*
G01X269191Y121092D02*
X271797Y123698D01*
Y123968D01*
G01X259933Y143727D02*
Y141122D01*
G01X270128Y151203D02*
Y155203D01*
G01X266978Y147203D02*
X264459D01*
X260600Y151062D01*
G01X270128Y147203D02*
X270125Y147200D01*
Y142892D01*
G01X270128Y147203D02*
X272553D01*
X274053Y148703D01*
X275053D01*
G01X272800Y140162D02*
X271477D01*
X270017Y138702D01*
Y137054D01*
X269925Y136962D01*
G01X266978Y151203D02*
X264578D01*
G01X273075Y136962D02*
X276825D01*
G01X275000Y153862D02*
X271469D01*
X270128Y155203D01*
G01Y159203D02*
X275000D01*
G01X260100Y157037D02*
Y159562D01*
G01X270740Y215582D02*
X271740Y216582D01*
Y220845D01*
G01X265795Y214022D02*
X269180D01*
X270740Y215582D01*
G01X269772Y228719D02*
Y229750D01*
X268240Y231282D01*
X265140D01*
X262140Y234282D01*
G01X271740Y228719D02*
Y230283D01*
X269740Y232283D01*
Y234282D01*
G01X270240Y242357D02*
Y245332D01*
G01X262140Y234282D02*
Y238107D01*
X263240Y239207D01*
G01X269740Y234282D02*
Y238707D01*
X270240Y239207D01*
G01X271620Y266602D02*
Y258007D01*
X271821Y257806D01*
G01X267759D02*
Y262672D01*
G01X266554Y278685D02*
Y276128D01*
X267550Y275132D01*
X272990D01*
X281120Y267002D01*
G01X265824Y311334D02*
Y305962D01*
G01D02*
X268624Y303162D01*
X290910D01*
X293763Y300309D01*
Y296463D01*
G01X269564Y311334D02*
Y319921D01*
X310065Y360422D01*
X321100D01*
G01X289274Y296463D02*
Y299208D01*
X286910Y301572D01*
X263490D01*
X260300Y304762D01*
G01X256964Y311334D02*
X308773Y363143D01*
X327310D01*
G01X266479Y426735D02*
X258066D01*
G01X263430Y422235D02*
X265979D01*
X266479Y422735D01*
G01X269661Y431039D02*
Y426767D01*
X269629Y426735D01*
G01Y422735D02*
Y418597D01*
X269611Y418579D01*
G01X266479Y443735D02*
X266509Y443705D01*
Y439605D01*
G01X266479Y443735D02*
X262963D01*
G01X269629Y447735D02*
X272500D01*
G01D02*
X272627Y447862D01*
X275425D01*
G01X263040Y448752D02*
X264180D01*
X265197Y447735D01*
X266479D01*
G01X275425Y451862D02*
X273500D01*
X272500Y452862D01*
G01D02*
X271373Y451735D01*
X269629D01*
G01X266479D02*
X265479Y452735D01*
X259643D01*
X257750Y450842D01*
G01X271877Y750415D02*
X268877D01*
X265997Y747535D01*
G01X630417Y757135D02*
X621907D01*
X621297Y756525D01*
X601966D01*
X595296Y763195D01*
X372022D01*
X369692Y765525D01*
X271057D01*
G01X633147Y758595D02*
Y755775D01*
X632137Y754765D01*
X601267D01*
X594707Y761325D01*
X371247D01*
X369127Y763445D01*
X272077D01*
X271057Y762425D01*
G01X288433Y32756D02*
Y29150D01*
X288434Y29149D01*
Y29147D01*
X288437Y29144D01*
Y22299D01*
X287000Y20862D01*
G01X276622Y32756D02*
Y30064D01*
X275120Y28562D01*
G01X276622Y44370D02*
Y48150D01*
X275900Y48872D01*
G01X288433Y44370D02*
Y51476D01*
X289400Y52443D01*
Y54222D01*
G01X274301Y118749D02*
Y115216D01*
G01Y118749D02*
X275797Y120245D01*
G01Y127118D02*
Y129592D01*
G01Y120245D02*
Y123968D01*
G01X275053Y148703D02*
Y149704D01*
X279168Y153819D01*
X280741D01*
G01X287000Y139862D02*
X289925D01*
X290625Y139162D01*
G01X286875Y136962D02*
X287000Y137087D01*
Y139862D01*
G01X282000Y143962D02*
X283300Y145262D01*
Y149291D01*
G01X283053Y139728D02*
Y142909D01*
X282000Y143962D01*
G01X283053Y139278D02*
Y139728D01*
G01Y139278D02*
Y137634D01*
X283725Y136962D01*
G01X276825D02*
Y140462D01*
G01X279975Y136962D02*
X278777Y138160D01*
Y142185D01*
X278553Y142409D01*
G01X277000Y143962D02*
X278553Y145515D01*
Y150703D01*
X279700Y151850D01*
X280741D01*
G01X278553Y142409D02*
X277000Y143962D01*
G01X287200D02*
X285269Y145893D01*
Y149291D01*
G01X292500Y144013D02*
X291314D01*
X287237Y148090D01*
Y149291D01*
G01X297700Y144162D02*
X295300Y146562D01*
X291550D01*
X289206Y148906D01*
Y149291D01*
G01X275000Y153862D02*
X276925Y155787D01*
X280741D01*
G01X275000Y159203D02*
X276447Y157756D01*
X280741D01*
G01X287237Y160315D02*
Y164347D01*
X286234Y165350D01*
G01X281234D02*
X282912Y163672D01*
X284392D01*
X285269Y162795D01*
Y160315D01*
G01X276234Y165350D02*
X279225Y162359D01*
X282842D01*
X283300Y161901D01*
Y160315D01*
G01X273708Y220845D02*
Y219814D01*
X276190Y217332D01*
Y215532D01*
G01D02*
X277990D01*
X279740Y213782D01*
Y212737D01*
X277805Y210802D01*
X277705D01*
G01D02*
X276049D01*
X276029Y210822D01*
X273895D01*
G01X277340Y234282D02*
X273708Y230650D01*
Y228719D01*
G01X277240Y239207D02*
X277340Y239107D01*
Y234282D01*
G01X281120Y267002D02*
Y257849D01*
X281077Y257806D01*
G01X276620Y262572D02*
Y257935D01*
X276491Y257806D01*
G01X279154Y278685D02*
Y276968D01*
X286320Y269802D01*
Y262752D01*
G01D02*
Y257967D01*
X286481Y257806D01*
G01X360140Y375392D02*
X357701D01*
X349486Y367177D01*
Y356310D01*
X334228Y341052D01*
X328006D01*
X309440Y322486D01*
Y289272D01*
X307360Y287192D01*
X284914D01*
X282894Y285172D01*
Y278685D01*
G01X284515Y296463D02*
X279400D01*
G01X298184D02*
Y298878D01*
X291300Y305762D01*
X274600D01*
G01D02*
X278424Y309586D01*
Y311334D01*
G01X282164D02*
Y323546D01*
X314950Y356332D01*
X331656D01*
X332808Y357484D01*
G01X302606Y32756D02*
Y26366D01*
X302610Y26362D01*
G01X290795Y32756D02*
X290796Y32755D01*
Y32753D01*
X290799Y32750D01*
Y28362D01*
G01X293157Y32756D02*
Y25569D01*
X292060Y24472D01*
G01X295520Y32756D02*
Y26362D01*
G01X300244Y32756D02*
X300245Y32755D01*
Y28365D01*
X300248Y28362D01*
G01X297882Y32756D02*
Y24480D01*
X299500Y22862D01*
G01X307331Y32756D02*
Y27058D01*
X304927Y24654D01*
G01X304968Y32756D02*
X304969Y32755D01*
Y32753D01*
X304972Y32750D01*
Y28362D01*
G01X304968Y44370D02*
Y41921D01*
X302720Y39673D01*
Y38182D01*
G01X290795Y44370D02*
Y50927D01*
X292590Y52722D01*
Y53982D01*
G01X293157Y44370D02*
X293161Y44374D01*
Y50522D01*
G01X295520Y44370D02*
Y52088D01*
X295524Y52092D01*
G01X300244Y44370D02*
Y49486D01*
X301310Y50552D01*
Y52482D01*
G01X297882Y44370D02*
Y47976D01*
X298550Y48644D01*
Y51602D01*
G01X302606Y44370D02*
Y49748D01*
X303715Y50857D01*
G01X298492Y67513D02*
X299417Y68438D01*
X300656D01*
X300677Y68417D01*
X302517D01*
G01X310459Y75892D02*
Y72206D01*
X306670Y68417D01*
X302517D01*
G01X306521Y82457D02*
X301600D01*
G01D02*
X299028D01*
X299002Y82483D01*
G01X298522Y75673D02*
X302310D01*
G01D02*
X303674D01*
X306521Y78520D01*
G01X299002Y85983D02*
X304964D01*
X306521Y84426D01*
G01X295357Y88903D02*
X297360D01*
X298454Y88450D01*
X299002Y87902D01*
Y85983D01*
G01X298492Y71513D02*
X302463D01*
X302517Y71567D01*
G01D02*
X305247D01*
G01D02*
Y71749D01*
X308490Y74992D01*
Y78520D01*
G01X305232Y91767D02*
Y93523D01*
X305315Y93606D01*
Y95724D01*
G01X307820D02*
X305315D01*
G01X305232Y91767D02*
Y89651D01*
X305956Y88927D01*
X306732D01*
X308490Y87169D01*
Y84426D01*
G01X293775Y139162D02*
X296200D01*
X296800Y139762D01*
G01X304354Y278685D02*
Y263002D01*
G01D02*
Y258103D01*
X304651Y257806D01*
G01X291754Y266962D02*
Y257811D01*
X291759Y257806D01*
G01X291754Y278685D02*
Y266962D01*
G01X295494Y278685D02*
Y282964D01*
X298612Y286082D01*
X307820D01*
X310570Y288832D01*
Y321616D01*
X328896Y339942D01*
X334688D01*
X350596Y355850D01*
Y362448D01*
X357946Y369798D01*
G01X299120Y302112D02*
X302765Y298467D01*
Y296463D01*
G01X303624Y311334D02*
Y304738D01*
X304500Y303862D01*
G01D02*
X306820Y301542D01*
Y296547D01*
X306736Y296463D01*
G01X291024Y311334D02*
Y309658D01*
X292920Y307762D01*
X293470D01*
X299120Y302112D01*
G01X361040Y389478D02*
X359206D01*
X347266Y377538D01*
Y357230D01*
X333308Y343272D01*
X319466D01*
X294764Y318570D01*
Y311334D01*
G01X294760Y553672D02*
X298221D01*
X302684Y558135D01*
Y559792D01*
G01X300520Y552262D02*
X301421D01*
X306956Y557797D01*
Y559792D01*
G01Y562942D02*
X302684D01*
G01X303147Y575158D02*
X307124D01*
X309573Y572709D01*
Y567704D01*
G01X298000Y587890D02*
X300268Y590158D01*
X303147D01*
G01Y585158D02*
X308417D01*
G01X303147Y577658D02*
X307987D01*
G01X303147Y582658D02*
X310800D01*
X312007Y583865D01*
Y588675D01*
G01X303147Y587658D02*
X306367D01*
X308447Y589738D01*
Y592255D01*
G01X306956Y559792D02*
X307048Y559884D01*
X309442D01*
X312616Y563058D01*
Y575816D01*
X308274Y580158D01*
X303147D01*
G01X296170Y1622852D02*
X309618Y1636300D01*
X358050D01*
X367140Y1645390D01*
G01X307331Y44370D02*
Y46466D01*
X308617Y47752D01*
Y48579D01*
X310400Y50362D01*
G01X320430Y78002D02*
X320021Y77593D01*
Y72309D01*
X322467Y69863D01*
G01X318333Y80489D02*
X319046D01*
X322875Y84318D01*
G01X316364Y84426D02*
Y89212D01*
G01X310459Y78520D02*
Y75892D01*
G01X318333Y78520D02*
X318851Y78002D01*
X320430D01*
G01X316982Y95803D02*
X317080Y95705D01*
Y91901D01*
X316982Y91803D01*
G01Y95803D02*
X317028Y95849D01*
Y99837D01*
G01X316364Y89212D02*
Y91185D01*
X316982Y91803D01*
G01X316900Y139962D02*
X320900Y135962D01*
X329875D01*
X332700Y138787D01*
G01X321333Y156078D02*
X319016D01*
X316900Y153962D01*
Y139962D01*
G01X314899Y228258D02*
Y228358D01*
X313995Y229262D01*
Y232174D01*
G01X314899Y228258D02*
Y224002D01*
X314249Y223352D01*
G01D02*
Y223282D01*
X317324Y220207D01*
X325002D01*
G01Y222176D02*
X321292D01*
X319718Y223750D01*
G01X318049Y228258D02*
X317995Y228312D01*
Y232174D01*
G01X319718Y223750D02*
X317880Y225588D01*
Y228089D01*
X318049Y228258D01*
G01X316954Y278685D02*
Y262752D01*
G01D02*
Y257981D01*
X317129Y257806D01*
G01X320694Y278685D02*
Y286346D01*
X324180Y289832D01*
Y318992D01*
X356150Y350962D01*
X357706D01*
X364667Y357923D01*
G01X308094Y278685D02*
X322078Y292669D01*
Y318460D01*
X343880Y340262D01*
Y344642D01*
X359000Y359762D01*
G01X316224Y305762D02*
Y296832D01*
X316463Y296593D01*
Y296463D01*
G01X316224Y311334D02*
Y305762D01*
G01X319964Y311334D02*
Y317916D01*
X342770Y340722D01*
Y346454D01*
X352060Y355744D01*
Y360522D01*
X355671Y364133D01*
G01X360680Y383412D02*
X348376Y371108D01*
Y356770D01*
X333768Y342162D01*
X327546D01*
X307364Y321980D01*
Y311334D01*
G01X321100Y360422D02*
X334175D01*
X335400Y361647D01*
Y377282D01*
X338600Y380482D01*
X340654D01*
G01X316444Y559125D02*
X320141D01*
X320234Y559218D01*
G01X309573Y567704D02*
Y565468D01*
X307047Y562942D01*
X306956D01*
G01X317860Y572322D02*
X320696Y575158D01*
X324347D01*
G01X323380Y563176D02*
X319590Y566966D01*
Y567906D01*
G01D02*
Y570323D01*
X321925Y572658D01*
X324347D01*
G01X319520Y577658D02*
X318716D01*
X315440Y574382D01*
Y567126D01*
X319390Y563176D01*
X320230D01*
G01X312007Y588675D02*
Y592605D01*
X309294Y595318D01*
G01X324347Y582658D02*
X319520D01*
G01X316127Y592785D02*
Y582025D01*
X317994Y580158D01*
X324347D01*
G01Y577658D02*
X319520D01*
G01X324347Y585158D02*
X321034D01*
X318560Y587632D01*
G01D02*
X319120Y588192D01*
Y594678D01*
X317800Y595998D01*
G01X309294Y595318D02*
Y599318D01*
G01X306144D02*
Y602225D01*
G01X308447Y592255D02*
X306655D01*
X306144Y592766D01*
Y595318D01*
G01X314650Y595998D02*
X314640Y596008D01*
Y599926D01*
G01X314650Y595998D02*
Y594262D01*
X316127Y592785D01*
G01X329050Y607402D02*
X320238D01*
X317790Y604954D01*
Y599926D01*
G01X313334Y1361484D02*
Y1362759D01*
X313108Y1363304D01*
X311867Y1364545D01*
Y1369603D01*
X312071Y1369807D01*
G01X325617Y73788D02*
Y69863D01*
G01X322875Y84318D02*
X325617D01*
G01Y73788D02*
X323706D01*
X323040Y73122D01*
G01X332500Y147638D02*
Y150738D01*
G01X328700Y141937D02*
X332700D01*
G01X328760Y147638D02*
Y141997D01*
X328700Y141937D01*
G01X332700D02*
X333556D01*
X334780Y140713D01*
Y137732D01*
X335430Y137082D01*
X337464D01*
G01D02*
Y140229D01*
X336625Y141068D01*
Y141862D01*
G01X328700Y138787D02*
X326216D01*
G01X336240Y157086D02*
Y161622D01*
X335000Y162862D01*
G01D02*
X338925D01*
X339925Y161862D01*
G01X330908Y214302D02*
X331040Y214170D01*
X335575D01*
G01D02*
X337799D01*
X338267Y213702D01*
G01X326971Y212333D02*
Y211440D01*
G01D02*
Y211294D01*
X328588Y209677D01*
G01X325002Y212333D02*
X323314Y210645D01*
G01X328965Y231664D02*
X328939Y231638D01*
Y229139D01*
G01D02*
Y224145D01*
G01X325002D02*
Y224153D01*
X322658Y226497D01*
Y229254D01*
G01D02*
Y231641D01*
X322155Y232144D01*
G01X330908Y224145D02*
X332465Y225702D01*
Y231664D01*
G01X335385Y235309D02*
X335260Y235184D01*
Y232540D01*
X334542Y231822D01*
X332623D01*
X332465Y231664D01*
G01X338249Y223934D02*
X338149D01*
X336391Y222176D01*
X335412D01*
G01D02*
X330908D01*
G01X329648Y257752D02*
Y262677D01*
G01D02*
Y266672D01*
X329554Y266766D01*
Y278685D01*
G01X333294D02*
X336110Y281501D01*
Y315902D01*
X354600Y334392D01*
X365620D01*
X379617Y348389D01*
Y358539D01*
X382190Y361112D01*
Y368298D01*
X386522Y372630D01*
Y386666D01*
X388735Y388879D01*
G01X329002Y296463D02*
X328824Y296641D01*
Y299686D01*
X332000Y302862D01*
G01D02*
X328824Y306038D01*
Y311334D01*
G01X332564D02*
Y316496D01*
X351570Y335502D01*
X365050D01*
X378430Y348882D01*
Y359032D01*
X381080Y361682D01*
Y368830D01*
X385281Y373031D01*
Y393363D01*
X386750Y394832D01*
G01X332808Y357484D02*
X337840Y362516D01*
Y367031D01*
X339070Y368261D01*
X340654D01*
G01X327310Y363143D02*
X333174D01*
G01Y365702D02*
X330674D01*
G01X328167Y379073D02*
X329317Y377923D01*
X333174D01*
G01X327470Y374917D02*
X332727D01*
X333174Y375364D01*
G01X327550Y388243D02*
X333112D01*
X333559Y388690D01*
X333568D01*
G01X336270Y402992D02*
X335681Y403581D01*
X333568D01*
G01X327060Y400371D02*
X333311D01*
X333568Y400628D01*
G01X327150Y409452D02*
X327370Y409672D01*
X339590D01*
X340654Y408608D01*
Y406534D01*
G01X323380Y563176D02*
Y559222D01*
X323384Y559218D01*
G01X324347Y587658D02*
X330093D01*
X331020Y588585D01*
Y594362D01*
G01D02*
X328106Y597276D01*
Y599298D01*
G01X327107Y732665D02*
Y719415D01*
X336527Y709995D01*
X346658D01*
G01X339629Y853490D02*
X338042Y851903D01*
Y849978D01*
G01X331284Y978814D02*
X332398D01*
X332755Y978457D01*
X334079D01*
G01X347677Y130002D02*
X344615D01*
X343450Y131167D01*
G01X339811Y123102D02*
Y121181D01*
X340440Y120552D01*
G01X339195Y131052D02*
X343139Y127108D01*
Y126836D01*
X343713Y126262D01*
X347677D01*
G01X339195Y131052D02*
Y128240D01*
X339811Y127624D01*
Y126252D01*
G01X355189Y144267D02*
X353791Y142869D01*
X350613D01*
G01X347876Y152202D02*
X349310D01*
X351100Y150412D01*
G01D02*
Y146004D01*
X350843Y145747D01*
X348099D01*
X347463Y145111D01*
Y142869D01*
G01X347876Y155942D02*
X342500D01*
G01X343075Y161862D02*
Y156517D01*
X342500Y155942D01*
G01X357660Y318850D02*
X350870Y312060D01*
Y206260D01*
X343075Y198465D01*
Y161862D01*
G01X338267Y213702D02*
X338285Y213684D01*
X342285D01*
G01D02*
X342303Y213702D01*
X346203D01*
G01X338249Y223934D02*
X338349D01*
X340064Y225649D01*
X340714D01*
X342149Y227084D01*
X342249D01*
G01X342000Y258162D02*
Y263087D01*
G01D02*
Y268217D01*
X342154Y268371D01*
Y278685D01*
G01X345894D02*
X349180Y281971D01*
Y316382D01*
X380727Y347929D01*
Y358079D01*
X383300Y360652D01*
Y367752D01*
X387838Y372290D01*
Y382362D01*
X388811Y383335D01*
G01X341295Y295789D02*
Y300452D01*
G01X354145Y296141D02*
Y300892D01*
G01X341295Y300452D02*
Y311205D01*
X341424Y311334D01*
G01X354145Y300892D02*
Y311213D01*
X354024Y311334D01*
G01X345411Y364702D02*
X344411Y365702D01*
X340654D01*
G01X345411Y376923D02*
X344411Y377923D01*
X340654D01*
G01Y391643D02*
X343354D01*
G01X347340Y407462D02*
X344440Y404562D01*
X341635D01*
X340654Y403581D01*
G01X346622Y705779D02*
X346658Y705815D01*
Y709995D01*
G01X434620Y535762D02*
X430820D01*
X425020Y541562D01*
Y663362D01*
X363920Y724462D01*
X353874D01*
X352879Y725457D01*
Y728657D01*
G01X345179Y856694D02*
Y854585D01*
X345178Y854584D01*
G01X347029Y879124D02*
X347030Y879123D01*
Y877015D01*
X347029Y877014D01*
G01X348879Y882329D02*
X348878Y882328D01*
Y880219D01*
G01X343761Y997574D02*
Y999684D01*
G01X343094Y1347521D02*
X343995Y1346620D01*
Y1341747D01*
X345236Y1340506D01*
X345462Y1339961D01*
Y1338686D01*
G01X357323Y122522D02*
X361800D01*
G01X366060Y133912D02*
X384495D01*
X385585Y132822D01*
G01X357324Y148462D02*
X364500D01*
X367341Y151303D01*
G01D02*
X374430Y158392D01*
X394780D01*
G01X373720Y214862D02*
X365649D01*
X362889Y217622D01*
G01X356295Y225862D02*
X357055Y225102D01*
X362889D01*
G01X356295Y221862D02*
Y225862D01*
G01Y219362D02*
Y221862D01*
G01X367354Y278685D02*
Y268270D01*
X367326Y268242D01*
Y263050D01*
G01D02*
Y258381D01*
X367306Y258361D01*
G01X354672Y258243D02*
Y263068D01*
G01D02*
Y268098D01*
X354754Y268180D01*
Y278685D01*
G01X371094D02*
Y280998D01*
X362330Y289762D01*
Y326392D01*
X382947Y347009D01*
Y354999D01*
X387070Y359122D01*
G01X358494Y278685D02*
X360460Y280651D01*
Y326092D01*
X381837Y347469D01*
Y357619D01*
X386540Y362322D01*
Y367222D01*
G01X366498Y295814D02*
Y300723D01*
G01D02*
Y302979D01*
X366493Y302984D01*
Y305012D01*
X366624Y305143D01*
Y311334D01*
G01X370364D02*
Y330026D01*
X385780Y345442D01*
Y352352D01*
G01X364667Y357923D02*
X369818Y363074D01*
Y368200D01*
X371250Y369632D01*
X373512D01*
X373800Y369344D01*
G01X359000Y359762D02*
X362419Y363181D01*
X366457D01*
X366714Y363438D01*
G01Y366391D02*
X364014D01*
G01X366714Y378649D02*
X364014D01*
G01X355671Y364133D02*
X363200Y371662D01*
X374450D01*
X378437Y375649D01*
Y381335D01*
X371110Y388662D01*
Y393712D01*
X371994Y394596D01*
X374159D01*
G01X357946Y369798D02*
X361770Y373622D01*
X369132D01*
X369530Y374020D01*
Y380722D01*
X370658Y381850D01*
X373552D01*
X373800Y381602D01*
G01X366714Y375696D02*
X366410Y375392D01*
X360140D01*
G01X366679Y392037D02*
X364179D01*
G01X388692Y401745D02*
Y403181D01*
X384561Y407312D01*
X380200D01*
X377790Y404902D01*
Y399121D01*
X376401Y397732D01*
X370520D01*
X368720Y395932D01*
Y387372D01*
X367804Y386456D01*
X363724D01*
X360680Y383412D01*
G01X366679Y389478D02*
X361040D01*
G01X370200Y409582D02*
Y405643D01*
X371521Y404322D01*
X373059D01*
X373800Y403581D01*
G01X366714Y400628D02*
X360880D01*
G01X358902Y754945D02*
X594207D01*
X599062Y750090D01*
X700075D01*
X705080Y755095D01*
X817347D01*
X821877Y759625D01*
X823437D01*
X825409Y761597D01*
X831296D01*
X833917Y758976D01*
X837127D01*
G01X363679Y895146D02*
Y893036D01*
G01X367379Y895146D02*
Y893036D01*
G01X378000Y1546400D02*
X379700Y1544700D01*
Y1537200D01*
X379200Y1536700D01*
X368500D01*
X364000Y1532200D01*
Y1513500D01*
X370400Y1507100D01*
X628350D01*
X664097Y1504510D01*
X686953Y1499331D01*
X694856Y1494608D01*
X772300Y1417164D01*
Y1369100D01*
X856200Y1285200D01*
Y1253000D01*
X881800Y1227400D01*
Y944800D01*
X867500Y930500D01*
Y781100D01*
X864700Y778300D01*
G01X368331Y1634522D02*
Y1632979D01*
X368710Y1632600D01*
X369900D01*
X370890Y1633590D01*
Y1634522D01*
G01X374500Y1642847D02*
Y1640899D01*
X373101Y1639500D01*
X369000D01*
G01D02*
X368331Y1638831D01*
Y1634522D01*
G01X372530Y122972D02*
X373870Y124312D01*
X376165D01*
G01X373200Y126052D02*
X375600Y128452D01*
X376145D01*
G01X388735Y124322D02*
Y124222D01*
X386535Y122022D01*
X380930D01*
G01D02*
X379315Y123637D01*
Y124312D01*
G01X379295Y128452D02*
Y131002D01*
G01D02*
X386210D01*
X388650Y128562D01*
Y128491D01*
G01X381795Y217362D02*
X384090Y215067D01*
X388965D01*
G01X381795Y217362D02*
Y212862D01*
G01D02*
X379795Y214862D01*
X373720D01*
G01X394720Y206362D02*
X392670Y204312D01*
X383195D01*
X378645Y208862D01*
G01X393415Y212508D02*
X386720D01*
G01D02*
X385441D01*
X381795Y208862D01*
G01X388720Y218362D02*
X384695D01*
X381795Y221262D01*
Y221362D01*
G01Y225362D02*
X382910D01*
X386690Y229142D01*
G01D02*
X390529Y225303D01*
X393415D01*
G01X386540Y223342D02*
X389697Y220185D01*
X393415D01*
G01X379954Y278685D02*
Y263232D01*
G01D02*
Y258140D01*
X379860Y258046D01*
G01X383694Y278685D02*
Y294506D01*
X386670Y297482D01*
G01X379107Y300712D02*
Y298456D01*
X379112Y298451D01*
Y295936D01*
G01X386670Y297482D02*
X388480Y299292D01*
Y318643D01*
G01X379224Y311334D02*
Y305920D01*
X379107Y305803D01*
Y300712D01*
G01X382964Y311334D02*
Y337106D01*
X394100Y348242D01*
Y357592D01*
G01X385720Y320902D02*
X388180D01*
X388480Y321202D01*
G01X385780Y352352D02*
Y353472D01*
X393695Y361387D01*
Y363081D01*
G01X376500Y366391D02*
X373800D01*
G01X383060Y403542D02*
X381971Y402453D01*
Y374383D01*
X377870Y370282D01*
Y367761D01*
X376500Y366391D01*
G01Y378649D02*
X373800D01*
G01X386540Y367222D02*
Y368472D01*
X390440Y372372D01*
Y374003D01*
X392317Y375880D01*
X393601D01*
G01X377136Y390307D02*
X375406Y392037D01*
X374159D01*
G01X386750Y394832D02*
X388740Y396822D01*
X389860D01*
X392630Y399592D01*
X395810D01*
X397850Y401632D01*
Y405182D01*
X399531Y406863D01*
X401129D01*
G01X375211Y1099017D02*
Y1096908D01*
X375212Y1096907D01*
G01X375222Y1334095D02*
X376123Y1333194D01*
Y1328321D01*
X377364Y1327080D01*
X377590Y1326535D01*
Y1325260D01*
G01X384600Y1595100D02*
Y1600800D01*
X391300Y1607500D01*
X391600D01*
X397100Y1613000D01*
Y1620900D01*
X398500Y1622300D01*
X410000D01*
X414275Y1618025D01*
Y1615200D01*
G01X382220Y1591870D02*
Y1601320D01*
X385700Y1604800D01*
Y1609400D01*
G01D02*
Y1616000D01*
X374658Y1627042D01*
X373449D01*
G01X370890D02*
Y1627872D01*
X371990Y1628972D01*
X382865D01*
X384775Y1627062D01*
G01D02*
Y1622732D01*
X384765Y1622722D01*
G01X394360Y1616380D02*
X393120D01*
X392710Y1615970D01*
X389040D01*
X384765Y1620245D01*
Y1622722D01*
G01X385123Y1634534D02*
X388070Y1637481D01*
Y1645582D01*
X387328Y1646324D01*
X385123D01*
G01X389690Y1650552D02*
X387219D01*
X385123Y1648456D01*
Y1646324D01*
G01X378497Y1634470D02*
X381380Y1637353D01*
Y1644942D01*
X379992Y1646330D01*
X378547D01*
G01X381640Y1651162D02*
X378547Y1648069D01*
Y1646330D01*
G01X380668Y1664844D02*
Y1666100D01*
X380168Y1666600D01*
X378609D01*
X378109Y1666100D01*
Y1664844D01*
G01D02*
Y1661200D01*
X375914Y1659005D01*
G01D02*
X374391Y1657482D01*
Y1654026D01*
G01X386824Y1657204D02*
Y1654955D01*
X383031Y1651162D01*
X381640D01*
G01X378509Y1682584D02*
Y1677584D01*
G01D02*
X378109Y1677184D01*
Y1672324D01*
G01X374509Y1682584D02*
X378509D01*
G01X374509D02*
X372009D01*
G01X400317Y129061D02*
X399321D01*
X394960Y133422D01*
X394210D01*
G01D02*
X389581D01*
X388981Y132822D01*
X388735D01*
G01Y124322D02*
X390391D01*
X390560Y124491D01*
X392930D01*
X393774Y123647D01*
X400317D01*
G01Y126207D02*
X395775D01*
X393491Y128491D01*
X388650D01*
G01X402220Y155833D02*
X409900D01*
G01X393415Y222744D02*
X397940D01*
X398704Y221980D01*
Y216366D01*
X397405Y215067D01*
X393415D01*
G01X388965D02*
X393415D01*
G01Y217626D02*
X389456D01*
X388720Y218362D01*
G01X416415Y222744D02*
X408838D01*
X406279Y225303D01*
X393415D01*
G01X409178Y234167D02*
X402700D01*
G01X392554Y278685D02*
Y263232D01*
G01D02*
Y258098D01*
X392616Y258036D01*
G01X396294Y278685D02*
Y281585D01*
G01X392083Y296504D02*
Y301160D01*
G01D02*
Y306129D01*
X391824Y306388D01*
Y311334D01*
G01X395564D02*
X399242D01*
X402152Y314244D01*
Y317922D01*
X406860Y322630D01*
Y393091D01*
X416498Y402729D01*
G01X395960Y321202D02*
X398720D01*
G01X395960Y323761D02*
X398661D01*
G01X394100Y357592D02*
X397215Y360707D01*
Y365764D01*
X399650Y368199D01*
X401175D01*
G01X387070Y359122D02*
X388940Y360992D01*
Y368606D01*
X390516Y370182D01*
X392920D01*
X397480Y374742D01*
Y379813D01*
X398665Y380998D01*
X401081D01*
G01X390876Y365640D02*
X393695D01*
G01X393601Y378439D02*
X390843D01*
G01X403875Y365640D02*
X401175D01*
G01X401081Y378439D02*
X404120D01*
G01X401070Y391433D02*
X404291D01*
G01X388811Y383335D02*
X391288Y385812D01*
X395520D01*
X397330Y387622D01*
Y392522D01*
X398800Y393992D01*
X401070D01*
G01X388735Y388879D02*
X393585D01*
X393590Y388874D01*
G01X390220Y392062D02*
X390849Y391433D01*
X393590D01*
G01X393649Y404304D02*
X391149D01*
G01X403720Y405552D02*
X403230Y405062D01*
X401887D01*
X401129Y404304D01*
G01X393649Y401745D02*
X388692D01*
G01X402528Y898350D02*
X402529Y898349D01*
Y896240D01*
G01X400679Y901555D02*
Y899446D01*
X400678Y899445D01*
G01X393279Y895146D02*
Y893036D01*
G01X396979Y895146D02*
Y893036D01*
G01X398828Y898350D02*
X398829Y898349D01*
Y896240D01*
G01X400679Y895146D02*
X400678Y895145D01*
Y893036D01*
G01X400679Y907963D02*
X400678Y907962D01*
Y905853D01*
G01X402528Y917576D02*
Y915467D01*
X402529Y915466D01*
G01X402528Y911167D02*
Y909058D01*
X402529Y909057D01*
G01X400679Y914372D02*
X400678Y914371D01*
Y912262D01*
G01X402528Y904759D02*
Y902650D01*
X402529Y902649D01*
G01X402528Y923985D02*
Y921876D01*
X402529Y921875D01*
G01Y960326D02*
X402528Y960327D01*
Y962436D01*
G01X402529Y966735D02*
X402528Y966736D01*
Y968845D01*
G01X401112Y1007187D02*
Y1009296D01*
X401111Y1009297D01*
G01X402961Y1010391D02*
Y1012500D01*
X402962Y1012501D01*
G01X401112Y1013595D02*
X401111Y1013596D01*
Y1015705D01*
G01X402961Y1029617D02*
X402962Y1029618D01*
Y1031727D01*
G01X401112Y1045639D02*
Y1047748D01*
X401111Y1047749D01*
G01X402961Y1036026D02*
X402962Y1036027D01*
Y1038136D01*
G01X402961Y1055251D02*
X402962Y1055252D01*
Y1057361D01*
G01Y1063770D02*
Y1061661D01*
X402961Y1061660D01*
G01X401112Y1058455D02*
Y1060564D01*
X401113Y1060565D01*
G01X399261Y1061660D02*
X399262Y1061661D01*
Y1063770D01*
G01X401111Y1054157D02*
X401112Y1054156D01*
Y1052047D01*
G01X402961Y1048842D02*
Y1050951D01*
X402962Y1050952D01*
G01X402961Y1074477D02*
Y1076586D01*
X402962Y1076587D01*
G01X402961Y1068068D02*
X402962Y1068069D01*
Y1070178D01*
G01X401112Y1066974D02*
Y1064864D01*
G01X400888Y1395508D02*
X402119D01*
X403256Y1396645D01*
Y1397038D01*
G01X403329Y1400684D02*
Y1400318D01*
X402219Y1399208D01*
X401079D01*
G01D02*
X399062D01*
X398507Y1398653D01*
G01X400926Y1404707D02*
X402829D01*
X403329Y1404207D01*
G01X407125Y1419428D02*
X403125D01*
G01D02*
X399156D01*
X399134Y1419406D01*
G01X394367Y1421475D02*
X396436Y1419406D01*
X399134D01*
G01X400924Y1408227D02*
X402824D01*
X403324Y1407727D01*
G01X463140Y1451562D02*
X448780D01*
X448407Y1451935D01*
X397407D01*
X387837Y1442365D01*
Y1431795D01*
X394657Y1424975D01*
X398515D01*
X399134Y1424356D01*
Y1422556D01*
G01X390687Y1431713D02*
X394831Y1427569D01*
X396343D01*
G01X405143D02*
X399493D01*
G01D02*
Y1429389D01*
X398657Y1430225D01*
X395697D01*
X390777Y1435145D01*
Y1435152D01*
G01X549236Y1441207D02*
X545875D01*
X544617Y1442465D01*
Y1458535D01*
X536517Y1466635D01*
X475395D01*
X468867Y1460107D01*
Y1443457D01*
X464785Y1439375D01*
X457667D01*
X452063Y1444979D01*
Y1445701D01*
X453147Y1446785D01*
Y1447507D01*
X452094Y1448560D01*
X451372D01*
X450288Y1447476D01*
X449566D01*
X447347Y1449695D01*
X400027D01*
X390777Y1440445D01*
Y1435152D01*
G01X394067Y1435323D02*
X396343Y1433047D01*
Y1432571D01*
G01X405143D02*
X399493D01*
G01D02*
Y1433991D01*
X404697Y1439195D01*
Y1447335D01*
X405207Y1447845D01*
X446507D01*
X456767Y1437585D01*
X465527D01*
X470657Y1442715D01*
Y1459365D01*
X476137Y1464845D01*
X534977D01*
X542107Y1457715D01*
Y1440385D01*
X545687Y1436805D01*
X564834D01*
X569236Y1441207D01*
G01X396946Y1537632D02*
X399168D01*
X399346Y1537810D01*
G01X402496D02*
Y1541810D01*
G01D02*
Y1545810D01*
G01X407296Y1543686D02*
X405172Y1545810D01*
X402496D01*
G01X409140Y1566892D02*
X406612Y1569420D01*
X403956D01*
X399346Y1564810D01*
G01X402496D02*
Y1560810D01*
G01D02*
Y1556810D01*
G01X407260D02*
X402496D01*
G01X391293Y1634554D02*
Y1636946D01*
X394210Y1639863D01*
Y1644796D01*
X393303Y1645703D01*
X391654D01*
X391563Y1645794D01*
G01X396824Y1650332D02*
X394444D01*
X391563Y1647451D01*
Y1645794D01*
G01X396824Y1657204D02*
Y1650332D01*
G01X391824Y1657204D02*
Y1652686D01*
X389690Y1650552D01*
G01X391824Y1678070D02*
Y1681266D01*
X392720Y1682162D01*
X403700D01*
X405230Y1680632D01*
Y1678092D01*
X407810Y1675512D01*
G01X396824Y1678070D02*
Y1673662D01*
G01D02*
Y1671458D01*
X399920Y1668362D01*
X412645D01*
G01X401824Y1678070D02*
Y1674938D01*
X403000Y1673762D01*
X404459D01*
X404969Y1673252D01*
Y1670872D01*
X405479Y1670362D01*
X406969D01*
X407479Y1670872D01*
Y1672160D01*
X408401Y1673082D01*
X410249D01*
G01X419762Y62665D02*
X415800D01*
G01X419762Y67465D02*
X415800D01*
G01X417443Y123647D02*
X423500D01*
G01X417443Y126207D02*
X420565D01*
X423580Y129222D01*
G01X417622Y149373D02*
Y153477D01*
G01Y157466D02*
Y161466D01*
G01Y153477D02*
Y157466D01*
G01X409900Y155833D02*
X415533Y161466D01*
X417622D01*
G01X410996Y218834D02*
Y213704D01*
X412192Y212508D01*
X416415D01*
G01Y215067D02*
X420865D01*
G01X416415Y209949D02*
X423220D01*
G01X416415Y220185D02*
X412347D01*
X410996Y218834D01*
G01X425780Y220022D02*
X423384Y217626D01*
X416415D01*
G01X417052Y239285D02*
X420475D01*
X420752Y239562D01*
G01X417052Y234167D02*
X414995D01*
X413600Y235562D01*
Y243062D01*
X415200Y244662D01*
X426090D01*
X426490Y244262D01*
G01X405139Y239908D02*
X405762Y239285D01*
X409178D01*
G01X417754Y278685D02*
Y263642D01*
G01D02*
Y258366D01*
X417765Y258355D01*
G01X405154Y278685D02*
Y263472D01*
G01D02*
Y258134D01*
X404985Y257965D01*
G01X408894Y278685D02*
X411220Y281011D01*
Y381502D01*
X415970Y386252D01*
G01X417219Y301637D02*
Y296825D01*
X417218Y296824D01*
G01X404215Y296690D02*
Y301544D01*
G01X417024Y311334D02*
Y307140D01*
X417219Y306945D01*
Y301637D01*
G01X415630Y374921D02*
X413880Y373171D01*
Y318218D01*
X420764Y311334D01*
G01X404215Y301544D02*
Y305642D01*
X404424Y305851D01*
Y311334D01*
G01X408164D02*
Y388486D01*
X415830Y396152D01*
G01X417390Y359132D02*
Y321202D01*
X422893Y315699D01*
Y280084D01*
X421494Y278685D01*
G01X421769Y363644D02*
X419612D01*
X417390Y361422D01*
Y359132D01*
G01X418704Y379201D02*
X421523D01*
G01X416762Y367353D02*
X417912Y366203D01*
X421769D01*
G01X421523Y376642D02*
X417351D01*
X415630Y374921D01*
G01X418540Y392163D02*
X421359D01*
G01X415970Y386252D02*
X419322Y389604D01*
X421359D01*
G01X415830Y396152D02*
X419520Y399842D01*
X423840D01*
X425130Y401132D01*
Y406782D01*
X426195Y407847D01*
X428962D01*
G01X416514Y407028D02*
X418254Y405288D01*
X421482D01*
G01X416498Y402729D02*
X421482D01*
G01X415710Y412972D02*
X430180D01*
X434060Y409092D01*
Y402202D01*
X430020Y398162D01*
X427540D01*
X424990Y395612D01*
Y376842D01*
X429249Y372583D01*
Y368762D01*
G01X404379Y895146D02*
Y893037D01*
X404378Y893036D01*
G01X409928Y898350D02*
X409929Y898349D01*
Y896240D01*
G01X415479Y895146D02*
Y893037D01*
X415478Y893036D01*
G01X417328Y898350D02*
Y896241D01*
X417329Y896240D01*
G01X411779Y901555D02*
Y899446D01*
X411778Y899445D01*
G01X413628Y898350D02*
X413629Y898349D01*
Y896240D01*
G01X419179Y901555D02*
Y899446D01*
X419178Y899445D01*
G01X404379Y901555D02*
Y899446D01*
X404378Y899445D01*
G01X417328Y911167D02*
Y909058D01*
X417329Y909057D01*
G01X406228Y911167D02*
X406229Y911166D01*
Y909057D01*
G01X413628Y911167D02*
Y909058D01*
X413629Y909057D01*
G01X413628Y917576D02*
X413629Y917575D01*
Y915466D01*
G01X406229D02*
X406228Y915467D01*
Y917576D01*
G01X408079Y914372D02*
Y912263D01*
X408078Y912262D01*
G01X406228Y904759D02*
Y902650D01*
X406229Y902649D01*
G01X415479Y907963D02*
Y905854D01*
X415478Y905853D01*
G01X411779Y914372D02*
X411778Y914371D01*
Y912262D01*
G01X415479Y914372D02*
X415478Y914371D01*
Y912262D01*
G01X417328Y917576D02*
X417329Y917575D01*
Y915466D01*
G01X406228Y923985D02*
X406229Y923984D01*
Y921875D01*
G01X408079Y920780D02*
Y918671D01*
X408078Y918670D01*
G01X417328Y923985D02*
Y921876D01*
X417329Y921875D01*
G01X413628Y923985D02*
X412897Y924716D01*
X411872Y925264D01*
G01X415479Y918670D02*
Y920780D01*
G01X411779Y918670D02*
Y920780D01*
G01X415911Y1047749D02*
X415912Y1047748D01*
Y1045639D01*
G01X406661Y1042434D02*
X406662Y1042435D01*
Y1044544D01*
G01X410361Y1042434D02*
X410362Y1042435D01*
Y1044544D01*
G01X408511Y1047749D02*
Y1045639D01*
X408512D01*
G01X414061Y1042434D02*
Y1044543D01*
X414062Y1044544D01*
G01X406661Y1055251D02*
X406662Y1055252D01*
Y1057361D01*
G01X406661Y1048842D02*
Y1050951D01*
X406662Y1050952D01*
G01X414060D02*
Y1048842D01*
X414061D01*
G01X417762Y1057361D02*
X417761Y1057360D01*
Y1055251D01*
G01X406661Y1061660D02*
X406662Y1061661D01*
Y1063770D01*
G01X408512Y1058455D02*
Y1060564D01*
X408511Y1060565D01*
G01X410361Y1061660D02*
X410362Y1061661D01*
Y1063770D01*
G01X412212Y1052047D02*
Y1054156D01*
X412211Y1054157D01*
G01X404812Y1052047D02*
X404811Y1052048D01*
Y1054157D01*
G01X414061Y1055251D02*
X414062Y1055252D01*
Y1057361D01*
G01X410361Y1055251D02*
X410362Y1055252D01*
Y1057361D01*
G01X417761Y1061660D02*
Y1063769D01*
X417762Y1063770D01*
G01X414061Y1061660D02*
X414062Y1061661D01*
Y1063770D01*
G01X408512Y1071273D02*
X408511Y1071274D01*
Y1073383D01*
G01X406661Y1068068D02*
Y1070177D01*
X406662Y1070178D01*
G01X404812Y1071273D02*
X404811Y1071274D01*
Y1073383D01*
G01X417762Y1076587D02*
Y1074478D01*
X417761Y1074477D01*
G01X408512Y1064864D02*
X408511Y1064865D01*
Y1066974D01*
G01X412212Y1071273D02*
X412211Y1071274D01*
Y1073383D01*
G01X415912Y1071273D02*
X415911Y1071274D01*
Y1073383D01*
G01X414061Y1068068D02*
Y1070177D01*
X414062Y1070178D01*
G01X417761Y1068068D02*
Y1070177D01*
X417762Y1070178D01*
G01X412212Y1064864D02*
X412211Y1064865D01*
Y1066974D01*
G01X414061Y1095813D02*
Y1093703D01*
G01X408968Y1334095D02*
X408251Y1333378D01*
Y1328321D01*
X409492Y1327080D01*
X409718Y1326535D01*
Y1325260D01*
G01X409980Y1397028D02*
X409970Y1397038D01*
X406406D01*
G01X409980Y1397028D02*
X413539D01*
X414909Y1395658D01*
G01D02*
Y1397234D01*
X416155Y1398480D01*
Y1404128D01*
G01X406479Y1400684D02*
X406993D01*
X408915Y1402606D01*
G01D02*
X412058D01*
X413679Y1404227D01*
Y1404917D01*
X414464Y1405702D01*
X416155D01*
G01X406479Y1404207D02*
X407429Y1405157D01*
X411121D01*
G01D02*
X413241Y1407277D01*
X416155D01*
G01Y1410427D02*
X408968D01*
G01D02*
X408164Y1411231D01*
X406474D01*
G01X416155Y1416726D02*
X414897D01*
X413350Y1418273D01*
Y1418792D01*
X412080Y1420062D01*
X407759D01*
X407125Y1419428D01*
G01X416155Y1419876D02*
X414901D01*
X413630Y1421147D01*
Y1421437D01*
X410074Y1424993D01*
G01X406474Y1407727D02*
X406910Y1408163D01*
X411150D01*
G01D02*
X412346D01*
X413035Y1408852D01*
X416155D01*
G01X411162Y1414126D02*
X412826D01*
X413376Y1413576D01*
X416155D01*
G01X416926Y1426471D02*
X418002D01*
X418813Y1425660D01*
Y1424108D01*
G01X410074Y1424993D02*
Y1425788D01*
X408293Y1427569D01*
G01Y1432571D02*
X411063Y1429801D01*
X412211D01*
X413697Y1428315D01*
G01D02*
X413729Y1428283D01*
Y1425004D01*
X416155Y1422578D01*
Y1421450D01*
G01X412386Y1547487D02*
X411097D01*
X407296Y1543686D01*
G01X412386Y1552605D02*
X411465D01*
X407260Y1556810D01*
G01X418960Y1609000D02*
X416575D01*
X414275Y1611300D01*
G01D02*
Y1615200D01*
G01X426440Y1611559D02*
X426300Y1611699D01*
Y1613300D01*
X425700Y1613900D01*
X419600D01*
X418625Y1614875D01*
Y1616600D01*
G01X418960Y1606441D02*
X415234D01*
X414275Y1607400D01*
G01D02*
Y1603500D01*
G01X412600Y1601000D02*
X414275Y1602675D01*
Y1603500D01*
G01X416020Y1620862D02*
X416480Y1620402D01*
X418575D01*
G01X419135Y1643159D02*
X412456Y1649838D01*
G01X417960Y1650072D02*
X419155Y1648877D01*
Y1647216D01*
G01X407810Y1675512D02*
X411795D01*
X412645Y1676362D01*
G01X421320Y1671699D02*
X419877Y1673142D01*
X419015D01*
X415795Y1676362D01*
G01X413007Y1680267D02*
Y1679150D01*
X415795Y1676362D01*
G01X410249Y1673082D02*
X411925D01*
X412645Y1672362D01*
G01X427120Y59862D02*
X428494Y61236D01*
X432662D01*
X433882Y60016D01*
X435262D01*
G01Y65016D02*
X428500D01*
G01D02*
X425263D01*
X422912Y62665D01*
G01X435262Y70016D02*
X428500D01*
G01D02*
X425463D01*
X422912Y67465D01*
G01X428889Y121515D02*
Y124015D01*
G01X423500Y123647D02*
X428521D01*
X428889Y124015D01*
G01X428882Y128522D02*
X428889Y128515D01*
G01X428883Y131015D02*
X428882Y131014D01*
Y128522D01*
G01X423580Y129222D02*
X424280Y128522D01*
X428882D01*
G01X420772Y149373D02*
X429780D01*
G01X420772Y157466D02*
X429780D01*
G01X420772Y161466D02*
X429780D01*
G01X420772Y153477D02*
X429780D01*
G01X420865Y215067D02*
X427940D01*
X428145Y214862D01*
G01X431295Y209862D02*
X433695D01*
G01X423220Y209949D02*
X426402D01*
X426489Y209862D01*
X428145D01*
G01X420752Y239562D02*
X421752Y240562D01*
X423845D01*
G01X426490Y244262D02*
X444600D01*
X452700Y252362D01*
X477500D01*
X482180Y257042D01*
Y273042D01*
X485000Y275862D01*
Y282862D01*
X491930Y289792D01*
Y296702D01*
X482820Y305812D01*
Y310192D01*
X480800Y312212D01*
X476850D01*
X473689Y309051D01*
X470654D01*
G01X431914Y278715D02*
Y263404D01*
X432054Y263264D01*
G01D02*
Y258536D01*
X431873Y258355D01*
G01X433996Y394722D02*
X438750Y389968D01*
Y321132D01*
X442880Y317002D01*
X454794D01*
X456934Y314862D01*
Y311275D01*
X455910Y310251D01*
Y292182D01*
X455200Y291472D01*
X449550D01*
X436793Y278715D01*
X435654D01*
G01X429702Y296313D02*
Y301086D01*
X429708Y301092D01*
G01D02*
Y311250D01*
X429624Y311334D01*
G01X433364D02*
X435980Y313950D01*
Y379746D01*
X433956Y381770D01*
G01X429003Y379201D02*
X431781D01*
G01X434006Y365203D02*
X433006Y366203D01*
X429249D01*
G01X433596Y391163D02*
X432596Y392163D01*
X428839D01*
G01X433956Y381770D02*
X429013D01*
X429003Y381760D01*
G01X428839Y394722D02*
X429386Y395269D01*
X433449D01*
X433996Y394722D01*
G01X428962Y405288D02*
X431920D01*
G01X431220Y507143D02*
X437303D01*
X439893Y509733D01*
G01X431220Y496362D02*
X437522D01*
X439893Y498733D01*
G01X431220Y501643D02*
X437303D01*
X439893Y504233D01*
G01X431220Y512623D02*
X437283D01*
X439893Y515233D01*
G01X431220Y518133D02*
X437293D01*
X439893Y520733D01*
G01X431220Y523362D02*
X437022D01*
X439893Y526233D01*
G01X434320Y540153D02*
X437313D01*
X439893Y542733D01*
G01X422879Y895146D02*
Y893037D01*
X422878Y893036D01*
G01X424728Y898350D02*
Y896241D01*
X424729Y896240D01*
G01X430279Y895146D02*
X430278Y895145D01*
Y893036D01*
G01X432128Y898350D02*
Y896241D01*
X432129Y896240D01*
G01X421028Y898350D02*
X421029Y898349D01*
Y896240D01*
G01X426579Y901555D02*
X426578Y901554D01*
Y899445D01*
G01X428428Y898350D02*
X428429Y898349D01*
Y896240D01*
G01X433979Y901555D02*
X433978Y901554D01*
Y899445D01*
G01X422879Y914372D02*
X422878Y914371D01*
Y912262D01*
G01X424728Y917576D02*
X424729Y917575D01*
Y915466D01*
G01X426579Y914372D02*
X426578Y914371D01*
Y912262D01*
G01X430279Y914372D02*
Y912263D01*
X430278Y912262D01*
G01X432128Y917576D02*
Y915467D01*
X432129Y915466D01*
G01X421028Y911167D02*
X421029Y911166D01*
Y909057D01*
G01X432128D02*
Y911167D01*
G01X433978Y905853D02*
Y907962D01*
X433979Y907963D01*
G01X424728Y909057D02*
Y911167D01*
G01X422879Y907963D02*
Y905854D01*
X422878Y905853D01*
G01X430279Y907963D02*
X430278Y907962D01*
Y905853D01*
G01X426578D02*
X426579Y905854D01*
Y907963D01*
G01X421028Y917576D02*
X421029Y917575D01*
Y915466D01*
G01X433979Y914372D02*
Y912262D01*
G01X430279Y920780D02*
Y918671D01*
X430278Y918670D01*
G01X432128Y923985D02*
Y921876D01*
X432129Y921875D01*
G01X433979Y920780D02*
Y918670D01*
G01X435829Y923985D02*
X435830Y923984D01*
Y921876D01*
X435829Y921875D01*
G01X424728Y923985D02*
X424729Y923984D01*
Y921875D01*
G01X422879Y920780D02*
Y918671D01*
X422878Y918670D01*
G01X421028Y923985D02*
X421029Y923984D01*
Y921875D01*
G01X426579Y920780D02*
Y918671D01*
X426578Y918670D01*
G01X430279Y927189D02*
Y925079D01*
G01X432128Y930393D02*
Y928285D01*
X432130Y928283D01*
G01X430279Y933598D02*
Y931487D01*
G01X435829Y930393D02*
Y928284D01*
X435830Y928283D01*
G01X435829Y936801D02*
Y934693D01*
X435830Y934692D01*
G01X432128Y936801D02*
Y934694D01*
X432130Y934692D01*
G01X427012Y1045639D02*
Y1047748D01*
X427011Y1047749D01*
G01X427012Y1041340D02*
X427013Y1041339D01*
Y1039231D01*
X427012Y1039230D01*
G01X419612Y1045639D02*
Y1047748D01*
X419611Y1047749D01*
G01X421461Y1042434D02*
X421462Y1042435D01*
Y1044544D01*
G01X427012Y1052047D02*
X427011Y1052048D01*
Y1054157D01*
G01X430711Y1052047D02*
Y1054157D01*
G01X428861Y1055251D02*
Y1057361D01*
G01X432561Y1055251D02*
Y1057361D01*
G01X421461Y1055251D02*
X421462Y1055252D01*
Y1057361D01*
G01X425161Y1048842D02*
X425162Y1048843D01*
Y1050952D01*
G01X423312Y1052047D02*
X423311Y1052048D01*
Y1054157D01*
G01X428862Y1050952D02*
Y1048843D01*
X428861Y1048842D01*
G01X421462Y1050952D02*
Y1048843D01*
X421461Y1048842D01*
G01X419612Y1052047D02*
X419611Y1052048D01*
Y1054157D01*
G01X425161Y1061660D02*
X425162Y1061661D01*
Y1063770D01*
G01X419612Y1058455D02*
X419611Y1058456D01*
Y1060565D01*
G01X423312Y1058455D02*
Y1060564D01*
X423311Y1060565D01*
G01X427012Y1058455D02*
X427011Y1058456D01*
Y1060565D01*
G01X428861Y1061660D02*
Y1063770D01*
G01X430711Y1058455D02*
Y1060565D01*
G01X423312Y1071273D02*
X423311Y1071274D01*
Y1073383D01*
G01X432561Y1068068D02*
X432560Y1068069D01*
Y1070178D01*
G01X419612Y1077681D02*
Y1079790D01*
X419611Y1079791D01*
G01X421461Y1074477D02*
X421462Y1074478D01*
Y1076587D01*
G01X421461Y1068068D02*
X421462Y1068069D01*
Y1070178D01*
G01X419612Y1064864D02*
X419611Y1064865D01*
Y1066974D01*
G01X425161Y1068068D02*
Y1070177D01*
X425162Y1070178D01*
G01X428861Y1068068D02*
Y1070177D01*
X428862Y1070178D01*
G01X430711Y1064864D02*
Y1066974D01*
G01X419612Y1099017D02*
Y1096907D01*
G01X429846Y1543810D02*
Y1547810D01*
G01D02*
X428422D01*
X426922Y1546310D01*
X424921D01*
G01X431620Y1541362D02*
X429846Y1543136D01*
Y1543810D01*
G01X424921Y1546310D02*
X422421D01*
X421244Y1547487D01*
X419866D01*
G01X434430Y1567562D02*
X434970D01*
X437670Y1564862D01*
X438020D01*
G01X429846Y1555810D02*
Y1551810D01*
G01X419866Y1552605D02*
X424820D01*
G01D02*
X427627D01*
X428422Y1551810D01*
X429846D01*
G01X430120Y1583466D02*
Y1579466D01*
G01X437460Y1579509D02*
X433350D01*
G01X430120Y1579466D02*
X433307D01*
X433350Y1579509D01*
G01X432200Y1607060D02*
Y1605132D01*
X429383Y1602315D01*
Y1600229D01*
G01Y1597079D02*
X433383D01*
G01D02*
X437383D01*
G01X426440Y1611559D02*
X430841D01*
X431500Y1610900D01*
Y1610300D01*
G01D02*
Y1609600D01*
X430838Y1608938D01*
X426502D01*
X426440Y1609000D01*
G01X426968Y1646026D02*
Y1640064D01*
X430360Y1636672D01*
Y1633932D01*
X431779Y1632513D01*
X432640D01*
G01Y1620702D02*
X431570D01*
X430240Y1619372D01*
X427530D01*
X426510Y1620392D01*
G01D02*
X421735D01*
X421725Y1620402D01*
G01X422305Y1647216D02*
X424706Y1649617D01*
X430870D01*
X433021Y1647466D01*
G01D02*
X435155Y1645332D01*
Y1641057D01*
X437069Y1639143D01*
Y1636942D01*
G01X422285Y1643159D02*
X425152Y1646026D01*
X426968D01*
G01X432640Y1634482D02*
Y1636746D01*
X431035Y1638351D01*
Y1641851D01*
G01X442650Y101912D02*
X442900Y102162D01*
Y107747D01*
G01X446640D02*
Y104552D01*
G01X450380Y117195D02*
Y123012D01*
G01D02*
X454500D01*
X456564Y120948D01*
G01X446746Y149864D02*
Y152662D01*
G01X458896Y149864D02*
X456474Y147442D01*
X452318D01*
X449931Y149829D01*
G01D02*
Y145710D01*
G01Y149829D02*
X449896Y149864D01*
G01X458264Y264032D02*
X452103D01*
X452071Y264064D01*
G01D02*
Y276472D01*
X450000Y278543D01*
G01X442224Y301142D02*
Y296530D01*
X442265Y296489D01*
G01X442224Y311334D02*
Y301142D01*
G01X450500Y358862D02*
X451062Y359424D01*
Y364503D01*
G01X443770Y371042D02*
X445100D01*
X448503Y367639D01*
Y364503D01*
G01X451062Y397262D02*
X449960Y396160D01*
Y392263D01*
X451062Y391161D01*
Y387503D01*
G01X445720Y399187D02*
X446416Y398491D01*
Y394306D01*
G01D02*
Y392116D01*
X448503Y390029D01*
Y387503D01*
G01X447490Y409052D02*
X445720Y407282D01*
Y402337D01*
G01X455720Y408187D02*
X451720D01*
G01X455720Y399187D02*
X451720Y403187D01*
Y408187D01*
G01X443300Y410962D02*
Y415967D01*
X444020Y416687D01*
G01X446303Y434003D02*
Y429351D01*
X442802Y425850D01*
Y424850D01*
G01D02*
Y421555D01*
X444020Y420337D01*
Y419837D01*
G01X447750Y414112D02*
X448520Y414882D01*
Y416687D01*
G01X448862Y434003D02*
Y428410D01*
X447552Y427100D01*
G01D02*
Y422461D01*
X448520Y421493D01*
Y419837D01*
G01X437520Y464837D02*
X441095Y461262D01*
X444450D01*
X446303Y459409D01*
Y457003D01*
G01X442520Y464837D02*
X445444D01*
X448862Y461419D01*
Y457003D01*
G01X451520Y464837D02*
X451421Y464738D01*
Y457003D01*
G01X437520Y473412D02*
Y476337D01*
G01D02*
Y479262D01*
G01Y470262D02*
Y464837D01*
G01X442520Y473412D02*
Y476337D01*
G01D02*
Y479262D01*
G01Y470262D02*
Y464837D01*
G01X451520Y470262D02*
Y464837D01*
G01X447520Y479262D02*
Y474262D01*
X451520Y470262D01*
G01Y479262D02*
X447520D01*
G01X445253Y513483D02*
X443643D01*
X439893Y509733D01*
G01X448403Y505483D02*
X453423D01*
G01X448403Y509483D02*
X453923D01*
X455423Y510983D01*
G01X445253Y505483D02*
X439893Y500123D01*
Y498733D01*
G01X445253Y509483D02*
X445143D01*
X439893Y504233D01*
G01X453680Y515072D02*
X449992D01*
X448403Y513483D01*
G01Y517483D02*
X453436Y522516D01*
X457456D01*
G01X445253Y517483D02*
X442143D01*
X439893Y515233D01*
G01X445253Y521483D02*
X440643D01*
X439893Y520733D01*
G01X448403Y521483D02*
Y522463D01*
X452107Y526167D01*
X453423D01*
G01X445253Y525483D02*
X444503Y526233D01*
X439893D01*
G01X448403Y525483D02*
Y526463D01*
X451923Y529983D01*
X457423D01*
G01X454885Y539483D02*
X450403D01*
X448403Y537483D01*
G01X445253D02*
X445143D01*
X439893Y542733D01*
G01Y547769D02*
X442649Y545013D01*
X445909D01*
X448403Y542519D01*
G01D02*
X449783Y543899D01*
X457423D01*
G01X448403Y547519D02*
X453423D01*
G01X448403D02*
X443153Y552769D01*
X439893D01*
G01X437679Y895146D02*
Y893037D01*
X437678Y893036D01*
G01X435829Y898350D02*
Y896240D01*
G01X441379Y901555D02*
X441378Y901554D01*
Y899445D01*
G01X445079Y895146D02*
X445078Y895145D01*
Y893036D01*
G01X446928Y898350D02*
X446929Y898349D01*
Y896240D01*
G01X445079Y901555D02*
X445078Y901554D01*
Y899445D01*
G01X443228Y898350D02*
X443229Y898349D01*
Y896240D01*
G01X448779Y901555D02*
X448778Y901554D01*
Y899445D01*
G01X450629Y898350D02*
X450630Y898349D01*
Y896240D01*
G01X435829Y909057D02*
Y911167D01*
G01X443228D02*
Y909058D01*
X443229Y909057D01*
G01X435829Y917576D02*
Y915466D01*
G01X439528Y917576D02*
Y915467D01*
X439529Y915466D01*
G01X445079Y905853D02*
X445078Y905854D01*
Y907962D01*
X445079Y907963D01*
G01X441379D02*
X441378Y907962D01*
Y905854D01*
X441379Y905853D01*
G01X450629Y911167D02*
Y909058D01*
X450630Y909057D01*
G01X448779Y907963D02*
X448778Y907962D01*
Y905854D01*
X448779Y905853D01*
G01X448780Y912262D02*
X448779Y912263D01*
Y914372D01*
G01X441380Y912262D02*
X441379Y912263D01*
Y914372D01*
G01X439528Y911167D02*
Y909058D01*
X439529Y909057D01*
G01X445079Y914372D02*
Y912263D01*
X445080Y912262D01*
G01X443228Y917576D02*
Y915467D01*
X443229Y915466D01*
G01X450629Y917576D02*
X450630Y917575D01*
Y915467D01*
X450629Y915466D01*
G01X439528Y923985D02*
X439529Y923984D01*
Y921875D01*
G01X441379Y920780D02*
X441378Y920779D01*
Y918670D01*
G01X450629Y923985D02*
Y921875D01*
G01X445079Y920780D02*
X445078Y920779D01*
Y918670D01*
G01X443228Y923985D02*
X443229Y923984D01*
Y921875D01*
G01X448779Y920780D02*
Y918670D01*
G01X443228Y930393D02*
Y928285D01*
X443230Y928283D01*
G01X448779Y933598D02*
Y931488D01*
X448780Y931487D01*
G01X437679Y933598D02*
Y931487D01*
G01X450629Y930393D02*
Y928284D01*
X450630Y928283D01*
G01X448779Y927189D02*
X448780Y927188D01*
Y925079D01*
G01X445079Y933598D02*
Y931487D01*
G01Y925079D02*
Y927189D01*
G01X439528Y930393D02*
Y928285D01*
X439530Y928283D01*
G01X437679Y927189D02*
Y925079D01*
G01X446928Y936801D02*
Y934694D01*
X446930Y934692D01*
G01X443228Y936801D02*
Y934694D01*
X443230Y934692D01*
G01X439528Y936801D02*
Y934694D01*
X439530Y934692D01*
G01X449212Y1052047D02*
X449211Y1054157D01*
G01X449213Y1060565D02*
X449212Y1060564D01*
Y1058455D01*
G01X451061Y1048842D02*
X451062Y1048843D01*
Y1050952D01*
G01X451061Y1055251D02*
X451062Y1055252D01*
Y1057361D01*
G01X451061Y1074477D02*
Y1076587D01*
G01Y1068068D02*
X451062Y1070178D01*
G01X451061Y1080885D02*
Y1082994D01*
X451060Y1082995D01*
G01X439478Y1334095D02*
X440379Y1333194D01*
Y1328321D01*
X441620Y1327080D01*
X441846Y1326535D01*
Y1325260D01*
G01X450026Y1409125D02*
X447432Y1411719D01*
X445230D01*
G01X450445Y1547437D02*
X445520D01*
G01D02*
Y1552197D01*
G01X448079D02*
X445520D01*
G01X438020Y1564862D02*
X442020D01*
G01D02*
X442961Y1563921D01*
Y1559677D01*
G01X446020Y1564862D02*
X450020D01*
G01D02*
X452520D01*
G01X445520Y1559677D02*
Y1564362D01*
X446020Y1564862D01*
G01X452020Y1574862D02*
X448740D01*
G01X456020D02*
X452020D01*
G01X437460Y1586989D02*
Y1588077D01*
X436383Y1589154D01*
Y1591964D01*
G01D02*
Y1594654D01*
X437383Y1595654D01*
Y1597079D01*
G01X447740Y1591180D02*
X444640D01*
X442578Y1589118D01*
Y1586989D01*
G01X437069Y1618242D02*
X437110Y1618201D01*
Y1613352D01*
X438749Y1611713D01*
G01D02*
X441690Y1608772D01*
X446854D01*
X450005Y1611923D01*
G01X445225Y1613427D02*
X443144D01*
X443096Y1613475D01*
X441263Y1614235D01*
X441006Y1614492D01*
Y1618242D01*
G01X443800Y1610712D02*
X443110D01*
X439037Y1614785D01*
Y1618242D01*
G01X459900Y1614582D02*
X457590Y1616892D01*
X450240D01*
X448890Y1618242D01*
X448880D01*
G01X451340Y1628576D02*
X453584D01*
X457450Y1632442D01*
X465500D01*
G01X451340Y1620702D02*
X452730D01*
X453830Y1619602D01*
X460710D01*
G01X463344Y1637622D02*
X460860D01*
X454953Y1635175D01*
X452291Y1632513D01*
X451340D01*
G01X458978Y1634481D02*
X457830D01*
X456360Y1633872D01*
X453033Y1630545D01*
X451340D01*
G01X449940Y1647412D02*
X451511Y1645841D01*
X454580D01*
G01X447090Y1647472D02*
X450000Y1644562D01*
Y1642420D01*
X451697Y1640723D01*
X454580D01*
G01X464586Y1674991D02*
Y1667091D01*
X456472Y1658977D01*
Y1639725D01*
X455407Y1638660D01*
X449626D01*
X448880Y1637914D01*
Y1636942D01*
G01X467430Y1666242D02*
X457802Y1656614D01*
Y1638890D01*
X456526Y1637614D01*
X454095Y1636607D01*
X451970Y1634482D01*
X451340D01*
G01X446920Y1644280D02*
X447320Y1643880D01*
Y1641220D01*
X444943Y1638843D01*
Y1636942D01*
G01X472178Y66575D02*
X468762Y69991D01*
X465455D01*
G01D02*
X464541D01*
X459566Y65016D01*
X456128D01*
G01X472152Y61129D02*
X468290Y64991D01*
X465455D01*
G01D02*
X464247D01*
X459272Y60016D01*
X456128D01*
G01X472108Y55935D02*
X468052Y59991D01*
X465455D01*
G01D02*
X460480Y55016D01*
X456128D01*
G01X456564Y120948D02*
Y115948D01*
G01X459714D02*
X462320D01*
G01X458896Y149864D02*
X464321D01*
G01D02*
X469856D01*
X470092Y149628D01*
X471316D01*
G01X455746Y154864D02*
X453028D01*
G01X458896D02*
X463821D01*
G01D02*
X466321D01*
X468998Y152187D01*
X471316D01*
G01X454925Y213362D02*
X452500D01*
G01X471000Y215244D02*
X461900D01*
G01D02*
X460018Y213362D01*
X458075D01*
G01X471000Y228039D02*
X468323D01*
X467500Y228862D01*
Y229862D01*
X468500Y230862D01*
X476999D01*
X480924Y234787D01*
X483500D01*
G01X454925Y222362D02*
X452500D01*
G01X471000Y222921D02*
X461900D01*
G01D02*
X461341Y222362D01*
X458075D01*
G01X471000Y225480D02*
X466300D01*
G01X471000Y217803D02*
X466300D01*
G01X475252Y264085D02*
X468384D01*
X468323Y264146D01*
G01X470000Y278543D02*
X468520Y277063D01*
Y264343D01*
X468323Y264146D01*
G01X452071Y260914D02*
Y254862D01*
G01X464818Y307082D02*
X462720D01*
X461736Y306098D01*
G01D02*
X462720Y305114D01*
X464818D01*
G01X463198Y311587D02*
Y309536D01*
X463683Y309051D01*
X464818D01*
G01X461736Y301098D02*
X463783Y303145D01*
X464818D01*
G01X456660Y359172D02*
X456180Y359652D01*
Y364503D01*
G01X460800Y358962D02*
X458739Y361023D01*
Y364503D01*
G01X459220Y393762D02*
X456180Y390722D01*
Y387503D01*
G01X459220Y393762D02*
Y390382D01*
X458739Y389901D01*
Y387503D01*
G01X455720Y399187D02*
Y395579D01*
X454513Y394372D01*
G01D02*
X453621Y393480D01*
Y387503D01*
G01X467500Y399187D02*
Y394943D01*
X461298Y388741D01*
Y387503D01*
G01X462720Y399187D02*
X467500D01*
G01X453020Y416687D02*
Y414262D01*
G01X453980Y434003D02*
Y426528D01*
X452552Y425100D01*
G01D02*
Y422461D01*
X453020Y421993D01*
Y419837D01*
G01X458600Y414262D02*
X457520Y415342D01*
Y416687D01*
G01Y419837D02*
Y421993D01*
X458052Y422525D01*
Y427100D01*
G01D02*
X456539Y428613D01*
Y434003D01*
G01X456520Y464837D02*
Y464461D01*
X453980Y461921D01*
Y457003D01*
G01X461520Y464837D02*
X456539Y459856D01*
Y457003D01*
G01X466520Y464837D02*
X462110Y460427D01*
X460004D01*
X459098Y459521D01*
Y457003D01*
G01X456520Y479262D02*
Y476337D01*
G01D02*
Y473412D01*
G01Y470262D02*
Y464837D01*
G01X461520Y479262D02*
Y476337D01*
G01D02*
Y473412D01*
G01Y470262D02*
Y464837D01*
G01X466520D02*
Y470262D01*
G01X453423Y505483D02*
X457923Y509983D01*
Y513483D01*
X460371Y515931D01*
X464994D01*
G01Y521049D02*
X459657D01*
X453680Y515072D01*
G01X457456Y522516D02*
X458548Y523608D01*
X464994D01*
G01X453423Y526167D02*
X464994D01*
G01X455423Y510983D02*
Y513563D01*
X460350Y518490D01*
X464994D01*
G01Y536404D02*
X461502D01*
X458423Y539483D01*
X454885D01*
G01X457423Y529983D02*
X459423D01*
X460679Y528727D01*
X464994D01*
G01X453423Y547519D02*
X458387D01*
X460923Y544983D01*
Y542983D01*
X462384Y541522D01*
X464994D01*
G01X457423Y543899D02*
X462359Y538963D01*
X464994D01*
G01X452479Y895146D02*
Y893036D01*
G01X454328Y898350D02*
X454329Y898349D01*
Y896240D01*
G01X459879Y895146D02*
X459878Y895145D01*
Y893036D01*
G01X461728Y898350D02*
X461729Y898349D01*
Y896240D01*
G01X467279Y895146D02*
X467278Y895145D01*
Y893036D01*
G01X456179Y901555D02*
X456178Y901554D01*
Y899445D01*
G01X458028Y898350D02*
X458029Y898349D01*
Y896240D01*
G01X463579Y901555D02*
X463578Y901554D01*
Y899445D01*
G01X465428Y898350D02*
X465429Y898349D01*
Y896240D01*
G01X463579Y907963D02*
Y905854D01*
X463578Y905853D01*
G01X454328Y911167D02*
Y909058D01*
X454329Y909057D01*
G01X452479Y905853D02*
X452478Y905854D01*
Y907962D01*
X452479Y907963D01*
G01X467279Y914372D02*
X467278Y914371D01*
Y912262D01*
G01X458028Y911167D02*
Y909058D01*
X458029Y909057D01*
G01X459879Y907963D02*
Y905854D01*
X459878Y905853D01*
G01X461728Y917576D02*
Y915467D01*
X461729Y915466D01*
G01X467279Y907963D02*
Y905854D01*
X467278Y905853D01*
G01X461728Y911167D02*
Y909058D01*
X461729Y909057D01*
G01X452479Y914372D02*
X452478Y914371D01*
Y912262D01*
G01X458028Y917576D02*
X458029Y917575D01*
Y915466D01*
G01X454328Y917576D02*
X454329Y917575D01*
Y915466D01*
G01X463579Y914372D02*
X463578Y914371D01*
Y912262D01*
G01X459879Y914372D02*
X459878Y914371D01*
Y912262D01*
G01X467279Y920780D02*
X467278Y920779D01*
Y918670D01*
G01X454328Y923985D02*
X454329Y923984D01*
Y921875D01*
G01X463579Y920780D02*
X463578Y920779D01*
Y918670D01*
G01X465428Y923985D02*
X465429Y923984D01*
Y921875D01*
G01X458028Y923985D02*
X458029Y923984D01*
Y921875D01*
G01X452479Y920780D02*
X452478Y920779D01*
Y918670D01*
G01X459879Y920780D02*
X459878Y920779D01*
Y918670D01*
G01X467712Y1045639D02*
X467711Y1045640D01*
Y1047750D01*
G01X460312Y1045639D02*
X460311Y1045640D01*
Y1047750D01*
G01X467712Y1039230D02*
X467711Y1039231D01*
Y1041340D01*
G01X452912Y1045639D02*
Y1047748D01*
X452911Y1047749D01*
G01X454761Y1042434D02*
X454762Y1042435D01*
Y1044544D01*
G01X456612Y1039230D02*
X456611Y1039231D01*
Y1041340D01*
G01X464012Y1039230D02*
X464011Y1039231D01*
Y1041340D01*
G01X462161Y1042434D02*
X462162Y1042435D01*
Y1044544D01*
G01X458461Y1042434D02*
X458462Y1042435D01*
Y1044544D01*
G01X464012Y1052047D02*
X464011Y1052048D01*
Y1054157D01*
G01X465861Y1048842D02*
X465860Y1048843D01*
Y1050952D01*
G01X456612Y1058455D02*
Y1060564D01*
X456611Y1060565D01*
G01X462161Y1055251D02*
Y1057361D01*
G01Y1061660D02*
Y1063770D01*
G01X460312Y1052047D02*
Y1054157D01*
G01X458461Y1055251D02*
Y1057360D01*
X458462Y1057361D01*
G01X452912Y1052047D02*
X452911Y1054157D01*
G01X464012Y1058455D02*
Y1060565D01*
G01X454761Y1048842D02*
X454762Y1048843D01*
Y1050952D01*
G01X458461Y1048842D02*
X458460Y1048843D01*
Y1050952D01*
G01X460312Y1058455D02*
X460311Y1058456D01*
Y1060565D01*
G01X454761Y1055251D02*
X454762Y1055252D01*
Y1057361D01*
G01X452912Y1071273D02*
X452911Y1071274D01*
Y1073383D01*
G01X460312Y1071273D02*
Y1073382D01*
X460311Y1073383D01*
G01X458460Y1070178D02*
X458461Y1070177D01*
Y1068068D01*
G01X460312Y1064864D02*
X460311Y1064865D01*
Y1066974D01*
G01X464011D02*
Y1064865D01*
X464012Y1064864D01*
G01X465861Y1068068D02*
X465860Y1068069D01*
Y1070178D01*
G01X464012Y1079791D02*
Y1077681D01*
G01X460312Y1079791D02*
Y1077681D01*
G01X462161Y1074477D02*
X462162Y1074478D01*
Y1076587D01*
G01X465861Y1074477D02*
Y1076586D01*
X465862Y1076587D01*
G01X464012Y1071273D02*
X464011Y1073383D01*
G01X458461Y1074477D02*
Y1076586D01*
X458462Y1076587D01*
G01X462161Y1095812D02*
Y1093703D01*
G01X458461Y1095812D02*
Y1093703D01*
G01X465861Y1089403D02*
Y1087294D01*
G01X456612Y1092607D02*
Y1090498D01*
G01X454761Y1089403D02*
Y1087294D01*
G01X460312Y1084090D02*
Y1086199D01*
X460311Y1086200D01*
G01X454761Y1080885D02*
Y1082994D01*
X454760Y1082995D01*
G01X465861Y1095812D02*
Y1093703D01*
G01X464012Y1092607D02*
Y1090498D01*
G01X454761Y1095812D02*
Y1093703D01*
G01X458461Y1089403D02*
Y1087294D01*
G01X462161Y1089403D02*
Y1087294D01*
G01X460312Y1099016D02*
Y1096907D01*
G01X465947Y1398355D02*
Y1397116D01*
X466457Y1396606D01*
X468241D01*
G01X467150Y1422842D02*
X463432D01*
X461239Y1420649D01*
G01X468620Y1407537D02*
X461239Y1414918D01*
Y1420649D01*
G01X462079Y1562197D02*
X459520D01*
G01D02*
Y1557437D01*
G01D02*
Y1552512D01*
G01X456961Y1569677D02*
Y1573921D01*
X456020Y1574862D01*
G01X460020D02*
X464020D01*
G01X459520Y1569677D02*
Y1574362D01*
X460020Y1574862D01*
G01X464020D02*
X466520D01*
G01X459779Y1599255D02*
X457220D01*
G01D02*
Y1594495D01*
G01D02*
Y1589570D01*
G01X466338Y1603682D02*
Y1599322D01*
X466320Y1599304D01*
G01X466338Y1614682D02*
Y1610682D01*
G01X454661Y1606735D02*
Y1609235D01*
G01D02*
X457578Y1612152D01*
X462520D01*
X463990Y1610682D01*
X466338D01*
G01X457220Y1606735D02*
Y1603562D01*
G01D02*
X466218D01*
X466338Y1603682D01*
G01X466295Y1618626D02*
X462251Y1614582D01*
X459900D01*
G01X466295Y1618626D02*
Y1622735D01*
G01X465500Y1632442D02*
X469846D01*
X471285Y1631003D01*
G01X460710Y1619602D02*
X464210Y1623102D01*
Y1624557D01*
X466385Y1626732D01*
G01X467430Y1661242D02*
Y1658432D01*
X470260Y1655602D01*
Y1649772D01*
X466329Y1645841D01*
X462060D01*
G01X472355Y1643242D02*
X466910D01*
G01D02*
X466880D01*
X464361Y1640723D01*
X462060D01*
G01X463344Y1637622D02*
X477600D01*
X478290Y1636932D01*
X623680D01*
X637340Y1623272D01*
X663442D01*
X671520Y1615194D01*
Y1562040D01*
X778848Y1454712D01*
X856270D01*
X886184Y1424798D01*
Y1303766D01*
X990660Y1199290D01*
Y767310D01*
X1001767Y756203D01*
X1003973D01*
X1007873Y752303D01*
Y748826D01*
G01X471225Y1634947D02*
X470790Y1635382D01*
X464646D01*
X463745Y1634481D01*
X458978D01*
G01X467430Y1661242D02*
X470355D01*
X472355Y1659242D01*
G01X466460Y1672332D02*
X471590Y1677462D01*
X472285D01*
G01X466180Y1678392D02*
X469020Y1681232D01*
X472055D01*
X472285Y1681462D01*
G01X485598Y66565D02*
X482671Y69492D01*
X473520D01*
X472178Y68150D01*
Y66575D01*
G01X485708Y61205D02*
X482971Y63942D01*
X473710D01*
X472152Y62384D01*
Y61129D01*
G01X485868Y55895D02*
X483031Y58732D01*
X473610D01*
X472108Y57230D01*
Y55935D01*
G01X478316Y147069D02*
X481880D01*
G01X471000Y220362D02*
X474500D01*
X476000Y221862D01*
Y226861D01*
X474822Y228039D01*
X471000D01*
G01X483500Y237937D02*
Y246362D01*
G01Y237937D02*
X502350D01*
X502425Y237862D01*
G01X483500Y234787D02*
X506575D01*
X508500Y232862D01*
G01X473500Y246362D02*
Y237937D01*
G01X478500Y258862D02*
X477325D01*
X475252Y260935D01*
G01X470000Y278543D02*
X469992Y278551D01*
Y292144D01*
X475150Y297302D01*
Y301684D01*
X474736Y302098D01*
G01X474310Y293022D02*
Y284233D01*
X480000Y278543D01*
G01X485500Y296937D02*
X481500D01*
G01D02*
X482500Y297937D01*
Y300836D01*
X479736Y303598D01*
G01D02*
X478220Y305114D01*
X470654D01*
G01X479736Y308598D02*
X478220Y307082D01*
X470654D01*
G01X474736Y302098D02*
X473689Y303145D01*
X470654D01*
G01X478720Y363287D02*
X474720D01*
G01X472720Y391362D02*
X470220Y388862D01*
Y382932D01*
X473900Y379252D01*
Y372502D01*
X471860Y370462D01*
Y366147D01*
X474720Y363287D01*
G01X482720Y366437D02*
X486720D01*
G01X478720D02*
Y368862D01*
X480174Y370316D01*
G01D02*
X482720Y372862D01*
Y375319D01*
G01X480145Y391362D02*
X476402D01*
X473060Y388020D01*
Y383805D01*
X474460Y382405D01*
G01D02*
X479767D01*
G01X482720D02*
Y387370D01*
G01D02*
Y390787D01*
X483295Y391362D01*
G01X480520Y416687D02*
X471920D01*
G01X482952Y433862D02*
Y429210D01*
X479451Y425709D01*
Y424709D01*
G01D02*
Y421556D01*
X479485Y421522D01*
Y421272D01*
X480520Y420237D01*
Y419837D01*
G01X485511Y433862D02*
Y428269D01*
X484201Y426959D01*
G01D02*
Y422312D01*
X485020Y421493D01*
Y419837D01*
G01X474169Y464696D02*
X477744Y461121D01*
X481099D01*
X482952Y459268D01*
Y456862D01*
G01X474169Y473271D02*
Y476196D01*
G01D02*
Y479121D01*
G01Y470121D02*
Y464696D01*
G01X479169Y473271D02*
Y476196D01*
G01D02*
Y479121D01*
G01Y470121D02*
Y464696D01*
G01D02*
X482093D01*
X485511Y461278D01*
Y456862D01*
G01X484169Y479121D02*
Y474121D01*
X488169Y470121D01*
G01Y479121D02*
X484169D01*
G01X474679Y895146D02*
X474678Y895145D01*
Y893036D01*
G01X472828Y898350D02*
X472829Y898349D01*
Y896240D01*
G01X478379Y901555D02*
X478378Y901554D01*
Y899445D01*
G01X476528Y898350D02*
X476529Y898349D01*
Y896240D01*
G01X470979Y901555D02*
X470978Y901554D01*
Y899445D01*
G01X470979Y914372D02*
Y912263D01*
X470980Y912262D01*
G01X476528Y917576D02*
Y915467D01*
X476529Y915466D01*
G01X478379Y914372D02*
Y912263D01*
X478380Y912262D01*
G01X480228Y904759D02*
X480229Y904758D01*
Y902649D01*
G01X469128Y904759D02*
X469129Y904758D01*
Y902649D01*
G01X469128Y917576D02*
Y915467D01*
X469129Y915466D01*
G01X472828D02*
Y917576D01*
G01Y904759D02*
X472829Y904758D01*
Y902649D01*
G01X480228Y909057D02*
Y911167D01*
G01X476528Y904759D02*
X476529Y904758D01*
Y902649D01*
G01X470979Y907963D02*
Y905854D01*
X470978Y905853D01*
G01X478379Y907963D02*
X478378Y907962D01*
Y905853D01*
G01X472828Y911167D02*
Y909058D01*
X472829Y909057D01*
G01X469128Y911167D02*
Y909058D01*
X469129Y909057D01*
G01X476528Y911167D02*
Y909058D01*
X476529Y909057D01*
G01X478379Y918670D02*
Y920780D01*
G01X472828Y923985D02*
X472829Y923984D01*
Y921875D01*
G01X470978Y918670D02*
Y920779D01*
X470979Y920780D01*
G01X469128Y923985D02*
X469129Y923984D01*
Y921875D01*
G01X478379Y965640D02*
Y963531D01*
X478378Y963530D01*
G01X482079Y965640D02*
X482077Y963530D01*
X482078Y963529D01*
G01X478379Y972049D02*
Y969939D01*
G01X480228Y981662D02*
Y979553D01*
X480229Y979552D01*
G01X480228Y975253D02*
Y973144D01*
X480229Y973143D01*
G01X478379Y978457D02*
Y976348D01*
X478378Y976347D01*
G01X480228Y968845D02*
X480229Y968844D01*
Y966735D01*
G01X478379Y984866D02*
X478378Y984865D01*
Y982756D01*
G01X482512Y1013595D02*
X482511Y1015705D01*
G01X480661Y1029617D02*
X480662Y1029618D01*
Y1031727D01*
G01X480661Y1023208D02*
X480662Y1023209D01*
Y1025318D01*
G01X471411Y1041340D02*
Y1039231D01*
X471412Y1039230D01*
G01X475111Y1047749D02*
Y1045639D01*
X475112D01*
G01X469561Y1042434D02*
X469562Y1042435D01*
Y1044544D01*
G01X478811Y1034931D02*
Y1032822D01*
X478812Y1032821D01*
G01X480661Y1036026D02*
Y1038135D01*
X480662Y1038136D01*
G01X478812Y1039230D02*
X478811Y1039231D01*
Y1041340D01*
G01X480661Y1042434D02*
X480662Y1042435D01*
Y1044544D01*
G01X473261Y1042434D02*
X473262Y1042435D01*
Y1044544D01*
G01X478812Y1064864D02*
Y1066973D01*
X478811Y1066974D01*
G01X469560Y1070178D02*
X469561Y1070177D01*
Y1068068D01*
G01X471412Y1064864D02*
Y1066973D01*
X471411Y1066974D01*
G01X476961Y1074477D02*
Y1076586D01*
X476962Y1076587D01*
G01X480661Y1074477D02*
X480662D01*
Y1076587D01*
G01X480661Y1068068D02*
X480662Y1070178D01*
G01X476961Y1068068D02*
X476962Y1070178D01*
G01X473261Y1074477D02*
X473262Y1074478D01*
Y1076587D01*
G01X469561Y1074477D02*
X469562Y1074478D01*
Y1076587D01*
G01X471412Y1071273D02*
X471411Y1073383D01*
G01X471412Y1077681D02*
Y1079790D01*
X471411Y1079791D01*
G01X475112Y1071273D02*
X475111Y1073383D01*
G01X482512Y1071273D02*
X482511Y1073383D01*
G01X478812Y1092607D02*
Y1090498D01*
G01X475112Y1092607D02*
Y1090498D01*
G01X473261Y1089403D02*
Y1087294D01*
G01X471412Y1086199D02*
Y1084090D01*
G01X476961Y1082994D02*
Y1080885D01*
G01X482512Y1092607D02*
Y1090498D01*
G01X476961Y1095812D02*
Y1093703D01*
G01X471412Y1092607D02*
Y1090498D01*
G01X475112Y1086199D02*
Y1084090D01*
G01X478812Y1086199D02*
Y1084090D01*
G01X471606Y1334095D02*
X472507Y1333194D01*
Y1328321D01*
X473748Y1327080D01*
X473974Y1326535D01*
Y1325260D01*
G01X489429Y1406538D02*
X488036D01*
X487064Y1405566D01*
Y1403321D01*
X485455Y1401712D01*
X483560D01*
G01X471422Y1400435D02*
Y1396637D01*
G01D02*
X471391Y1396606D01*
G01X471422Y1396637D02*
X473022D01*
X473747Y1397362D01*
X480620D01*
X481041Y1397783D01*
Y1400385D01*
G01D02*
X482408Y1399018D01*
X486566D01*
X487110Y1399562D01*
G01X489429Y1409687D02*
X486225D01*
X485834Y1409296D01*
G01X470890Y1431504D02*
Y1435838D01*
G01X469535Y1626732D02*
X472220D01*
G01X471285Y1631003D02*
Y1631437D01*
X472720Y1632872D01*
X483241D01*
X485075Y1631038D01*
G01X472355Y1651242D02*
Y1647242D01*
G01D02*
Y1643242D01*
G01X474375Y1634947D02*
X474590Y1635162D01*
X623030D01*
X636631Y1621561D01*
X662649D01*
X669360Y1614850D01*
Y1550220D01*
X677020Y1542560D01*
X687510D01*
X777128Y1452942D01*
X854901D01*
X884406Y1423437D01*
Y1303029D01*
X988882Y1198553D01*
Y1188501D01*
X988372Y1187991D01*
X987510D01*
X987000Y1187481D01*
Y1185991D01*
X987510Y1185481D01*
X988372D01*
X988882Y1184971D01*
Y1183481D01*
X988372Y1182971D01*
X987510D01*
X987000Y1182461D01*
Y1180971D01*
X987510Y1180461D01*
X988372D01*
X988882Y1179951D01*
Y766573D01*
X1001030Y754425D01*
X1003236D01*
X1005373Y752288D01*
Y748826D01*
G01X679270Y1604040D02*
X679910Y1604680D01*
Y1610210D01*
X663560Y1626560D01*
X645332D01*
X631180Y1640712D01*
X491010D01*
X489660Y1639362D01*
X485310D01*
X484010Y1640662D01*
X469970D01*
X469580Y1640272D01*
G01X472355Y1663242D02*
Y1667242D01*
G01Y1663242D02*
Y1659242D01*
G01X475505D02*
X477905D01*
G01X475150Y1654302D02*
X475505Y1653947D01*
Y1651242D01*
G01X472285Y1673462D02*
Y1677462D01*
G01Y1685462D02*
Y1681462D01*
G01X494000Y212685D02*
X498700D01*
G01D02*
X501523Y209862D01*
X506925D01*
G01X494000Y215244D02*
X503100D01*
G01X494000Y217803D02*
X490560D01*
X488700Y219663D01*
Y224262D01*
X489918Y225480D01*
X494000D01*
G01X508500Y232862D02*
Y227962D01*
X506018Y225480D01*
X494000D01*
G01Y220362D02*
X498700D01*
G01X503100Y222921D02*
X494000D01*
G01X492936Y264832D02*
X499053D01*
X499096Y264789D01*
G01X499992Y278551D02*
Y278543D01*
X499096Y277647D01*
Y264789D01*
G01X496028Y258590D02*
X494372D01*
X492936Y260026D01*
Y261682D01*
G01X486370Y262952D02*
X487786Y264368D01*
Y276329D01*
X490000Y278543D01*
G01X499992Y278551D02*
X500000Y278543D01*
G01X504054Y302445D02*
X505096D01*
X505606Y301935D01*
Y301071D01*
X504129Y299594D01*
Y292651D01*
X499992Y288514D01*
Y278551D01*
G01X485500Y293787D02*
X489091D01*
G01X495136Y305398D02*
X492411D01*
G01D02*
Y309398D01*
G01X498218Y306382D02*
X496120D01*
X495136Y305398D01*
G01D02*
X496120Y304414D01*
X498218D01*
G01X495136Y300398D02*
X497183Y302445D01*
X498218D01*
G01X492385Y313582D02*
X495036Y310931D01*
Y310398D01*
G01D02*
X497083Y308351D01*
X498218D01*
G01X489235Y313582D02*
X486710D01*
G01X486720Y363287D02*
Y360862D01*
G01X498720Y363287D02*
Y360862D01*
G01X494720Y363287D02*
X490720D01*
G01D02*
Y360862D01*
G01X485673Y375319D02*
Y370314D01*
G01D02*
X486720Y369267D01*
Y366437D01*
G01X502720D02*
X498720D01*
G01X500670Y370180D02*
X498720Y368230D01*
Y366437D01*
G01X499073Y375426D02*
Y373009D01*
X500670Y371412D01*
Y370180D01*
G01X494720Y366437D02*
Y370337D01*
G01D02*
X496120Y371737D01*
Y375426D01*
G01X490810Y387640D02*
Y386160D01*
X493167Y383803D01*
Y382512D01*
G01X493145Y391362D02*
X492032D01*
X490810Y390140D01*
Y387640D01*
G01X500220Y391362D02*
X496295D01*
G01X500220D02*
Y388680D01*
X496120Y384580D01*
Y382512D01*
G01X489520Y416687D02*
Y411862D01*
G01X485020Y416687D02*
Y414162D01*
G01X490629Y433862D02*
Y426387D01*
X489201Y424959D01*
G01D02*
Y421812D01*
X489520Y421493D01*
Y419837D01*
G01X494020Y416687D02*
Y414262D01*
G01Y419837D02*
Y421493D01*
X494701Y422174D01*
Y426959D01*
G01D02*
X493188Y428472D01*
Y433862D01*
G01X493169Y464696D02*
Y464312D01*
X490629Y461772D01*
Y456862D01*
G01X498169Y464696D02*
X493188Y459715D01*
Y456862D01*
G01X488169Y464696D02*
X488070Y464597D01*
Y456862D01*
G01X503169Y464696D02*
X498125Y459652D01*
X496391D01*
X495747Y459008D01*
Y456862D01*
G01X493169Y473271D02*
Y476196D01*
G01D02*
Y479121D01*
G01Y470121D02*
Y464696D01*
G01X498169Y473271D02*
Y476196D01*
G01D02*
Y479121D01*
G01Y470121D02*
Y464696D01*
G01X488169Y470121D02*
Y464696D01*
G01X503943Y507819D02*
X501853D01*
X498423Y511249D01*
G01X503943Y519819D02*
X502713Y521049D01*
X496794D01*
X493950Y523893D01*
G01D02*
X491106Y521049D01*
X487042D01*
G01X503943Y515819D02*
X501779Y517983D01*
X498923D01*
G01D02*
X495434D01*
X494927Y518490D01*
X487042D01*
G01X503943Y511819D02*
X503087D01*
X499923Y514983D01*
X494423D01*
G01D02*
X491314D01*
X490366Y515931D01*
X487042D01*
G01X498423Y511249D02*
X492297D01*
X490174Y513372D01*
X487042D01*
G01Y526167D02*
X490057D01*
X493987Y530097D01*
G01X503943Y523819D02*
X502584D01*
X499215Y527188D01*
G01D02*
X493803D01*
X490223Y523608D01*
X487042D01*
G01X524920Y539819D02*
X520920Y543819D01*
X498759D01*
X491344Y536404D01*
X487042D01*
G01X524820Y545319D02*
X522692D01*
X516649Y551362D01*
X503302D01*
X490903Y538963D01*
X487042D01*
G01X493987Y530097D02*
X500467D01*
X502745Y527819D01*
X503943D01*
G01X487042Y533845D02*
X491785D01*
X496223Y538283D01*
X499123D01*
G01D02*
X500659Y539819D01*
X503943D01*
G01X498563Y607067D02*
Y615590D01*
X498585Y615612D01*
G01X489429Y1404569D02*
Y1401881D01*
X487110Y1399562D01*
G01X515539Y65158D02*
Y71390D01*
X522228Y78079D01*
G01X513177Y65158D02*
Y75903D01*
X513260Y75986D01*
Y78242D01*
G01X516236Y92948D02*
Y92646D01*
X517020Y91862D01*
Y86437D01*
G01X522228Y78079D02*
Y81995D01*
X520936Y83287D01*
X517020D01*
G01X512220D02*
Y82063D01*
X513260Y81023D01*
Y78242D01*
G01X507025Y86422D02*
X507040Y86437D01*
X512220D01*
G01X513586Y92799D02*
Y87803D01*
X512220Y86437D01*
G01X544390Y236512D02*
Y211837D01*
X511355Y178802D01*
Y131994D01*
X518771Y124578D01*
X543089D01*
X556805Y110862D01*
X569000D01*
X587000Y92862D01*
Y65523D01*
X591599Y60924D01*
X598023D01*
X598650Y61551D01*
Y65158D01*
G01X542050Y231722D02*
Y211774D01*
X509745Y179469D01*
Y131327D01*
X518104Y122968D01*
X542422D01*
X556408Y108982D01*
X568221D01*
X585120Y92083D01*
Y64742D01*
X591300Y58562D01*
X598620D01*
X601011Y60953D01*
Y61550D01*
X601012Y61551D01*
Y65158D01*
G01X595415Y246515D02*
X593570Y244670D01*
X571010D01*
X554850Y228510D01*
X547900D01*
X547110Y227720D01*
Y212280D01*
X512995Y178165D01*
Y133165D01*
X519610Y126550D01*
X543630D01*
X545310Y124870D01*
X554010D01*
X557280Y121600D01*
X567610D01*
X577220Y111990D01*
X586620D01*
X596620Y101990D01*
Y96420D01*
X594470Y94270D01*
Y92920D01*
X593240Y91690D01*
Y91095D01*
G01X510075Y209862D02*
X512500D01*
G01X510075Y223362D02*
X512500D01*
G01X506925D02*
X503541D01*
X503100Y222921D01*
G01X502425Y237862D02*
Y241862D01*
G01X515804Y265038D02*
X515728Y265114D01*
X509496D01*
G01D02*
Y278047D01*
X509992Y278543D01*
Y278551D01*
G01X536420Y309422D02*
X514456D01*
X512279Y307245D01*
Y283917D01*
X514970Y281226D01*
Y270392D01*
X518590Y266772D01*
Y262872D01*
X517606Y261888D01*
X515804D01*
G01X504054Y306382D02*
X508829D01*
X510825Y304386D01*
Y279384D01*
X509992Y278551D01*
G01D02*
X510000Y278543D01*
G01X508575Y288862D02*
Y292183D01*
X507750Y293008D01*
G01D02*
Y293112D01*
X506000Y294862D01*
Y299370D01*
X508500Y301870D01*
Y303362D01*
G01X508502Y298813D02*
X507750Y298061D01*
Y296158D01*
G01X508500Y303362D02*
X507448Y304414D01*
X504054D01*
G01Y308351D02*
X507089D01*
X508136Y309398D01*
G01D02*
X508332Y309594D01*
Y315404D01*
G01X507160Y332452D02*
X518720Y344012D01*
Y363287D01*
G01X510720Y360862D02*
Y363287D01*
G01D02*
X506720D01*
G01X504040Y378327D02*
Y374320D01*
G01D02*
X505878D01*
X507210Y375652D01*
Y378477D01*
X509267Y380534D01*
Y382405D01*
G01X518720Y366437D02*
X514720D01*
G01X518250Y370250D02*
X518440Y370440D01*
Y372052D01*
X515173Y375319D01*
G01X518250Y370250D02*
X517050D01*
X514720Y367920D01*
Y366437D01*
G01X510720D02*
Y370361D01*
G01D02*
X512220Y371861D01*
Y375319D01*
G01X505720Y392787D02*
X509720D01*
G01D02*
Y390362D01*
G01X504040Y381477D02*
Y385560D01*
G01D02*
X510801D01*
X512220Y384141D01*
Y382405D01*
G01X509720Y395937D02*
Y398820D01*
X508690Y399850D01*
G01X517720Y395937D02*
X513720D01*
G01X507267Y411905D02*
X502040D01*
G01D02*
Y419410D01*
X503492Y420862D01*
X508145D01*
G01X508690Y399850D02*
Y401610D01*
X510220Y403140D01*
Y404819D01*
G01Y411905D02*
Y416970D01*
G01X513173Y404819D02*
X516691D01*
X517460Y404050D01*
Y399960D01*
G01X510220Y416970D02*
X511295Y418045D01*
Y420862D01*
G01X517184Y470181D02*
Y457916D01*
X513979Y454711D01*
Y444062D01*
G01X513444Y460733D02*
Y457522D01*
G01X503169Y470121D02*
Y464696D01*
G01X517184Y475952D02*
Y480713D01*
X517020Y480877D01*
G01X524220Y505862D02*
Y504362D01*
X523021Y503163D01*
X518817D01*
X516011Y505969D01*
G01X507093Y511819D02*
X510161D01*
X516011Y505969D01*
G01X524220Y500362D02*
Y498862D01*
X523421Y498063D01*
X518417D01*
X516011Y500469D01*
G01X507093Y507819D02*
X508661D01*
X516011Y500469D01*
G01X524220Y516862D02*
Y516362D01*
X522331Y514473D01*
X518507D01*
X516011Y516969D01*
G01X507093Y519819D02*
X513161D01*
X516011Y516969D01*
G01X524220Y511362D02*
Y509862D01*
X523101Y508743D01*
X518737D01*
X516011Y511469D01*
G01X507093Y515819D02*
X511661D01*
X516011Y511469D01*
G01X524720Y519743D02*
X518737D01*
X516011Y522469D01*
G01X507093Y523819D02*
X514661D01*
X516011Y522469D01*
G01X507093Y527819D02*
X507243Y527969D01*
X516011D01*
G01X524720Y525293D02*
X518687D01*
X516011Y527969D01*
G01Y539819D02*
X515877D01*
X513120Y537062D01*
X506700D01*
X503943Y539819D01*
G01X502861Y1108629D02*
Y1106520D01*
G01X501012Y1105426D02*
Y1103316D01*
G01X512112Y1105426D02*
Y1103316D01*
G01X508412Y1111833D02*
Y1109724D01*
G01X506561Y1102220D02*
Y1100111D01*
G01X504712Y1111833D02*
Y1109724D01*
G01X501012Y1111833D02*
Y1109724D01*
G01X504712Y1105426D02*
Y1103316D01*
G01X510261Y1108630D02*
Y1106520D01*
G01X512112Y1111833D02*
Y1109724D01*
G01X508412Y1105426D02*
Y1103316D01*
G01X506561Y1115038D02*
Y1112929D01*
G01X503734Y1347521D02*
X504635Y1346620D01*
Y1341747D01*
X505876Y1340506D01*
X506102Y1339961D01*
Y1338686D01*
G01X523978Y59074D02*
X525778D01*
X527350Y57502D01*
Y53544D01*
G01X529078Y59282D02*
X529713Y58647D01*
Y53544D01*
G01X527350Y65158D02*
Y69462D01*
X527520Y69632D01*
Y69633D01*
G01X529713Y65158D02*
Y71799D01*
X528590Y72922D01*
G01X518450Y101602D02*
X522948Y106100D01*
X533497D01*
X536245Y103352D01*
G01X517290Y104252D02*
X521100Y108062D01*
X536315D01*
G01X531523Y134361D02*
X534088D01*
X534565Y134838D01*
Y139862D01*
G01X531523Y129243D02*
X527160D01*
G01X534565Y139862D02*
Y151838D01*
X534042Y152361D01*
X531523D01*
G01X519010Y147912D02*
X519679Y147243D01*
X531523D01*
G01X520400Y168443D02*
X521558Y167285D01*
X530978D01*
G01X523220Y170362D02*
X522319D01*
X520400Y168443D01*
G01X526920Y161362D02*
X527719D01*
X528524Y162167D01*
X530978D01*
G01X538852Y167285D02*
X537067D01*
X535510Y168842D01*
Y180632D01*
X534780Y181362D01*
X531980D01*
G01Y178803D02*
X526730D01*
G01X526980Y322582D02*
X538525Y334127D01*
Y391337D01*
X537075Y392787D01*
X533720D01*
G01X521820Y336762D02*
Y349262D01*
X520820Y350262D01*
Y373092D01*
X517720Y376192D01*
Y392787D01*
G01X531720Y363287D02*
Y360862D01*
G01X527720D02*
Y363287D01*
G01D02*
X523720D01*
G01X520830Y380807D02*
Y376860D01*
G01D02*
X523221D01*
X526267Y379906D01*
Y382905D01*
G01X535720Y366437D02*
X531720D01*
G01X535910Y370450D02*
X532173Y374187D01*
Y375819D01*
G01X527720Y366437D02*
Y370430D01*
G01D02*
X529220Y371930D01*
Y375819D01*
G01X521720Y392787D02*
X525720D01*
G01D02*
Y390362D01*
G01X517720Y395937D02*
Y399700D01*
X517460Y399960D01*
G01X529220Y382905D02*
Y386341D01*
X527661Y387900D01*
X520890D01*
G01D02*
X520830Y387840D01*
Y383957D01*
G01X525720Y395937D02*
X525670Y395987D01*
Y399850D01*
G01X533720Y395937D02*
X529720D01*
G01X520760Y417110D02*
X523267Y414603D01*
Y411905D01*
G01X525670Y399850D02*
Y401312D01*
X526220Y401862D01*
Y404819D01*
G01Y411905D02*
Y413880D01*
X529960Y417620D01*
G01X529173Y404819D02*
X530820D01*
X533720Y401919D01*
Y400160D01*
G01X523145Y420862D02*
X520760Y418477D01*
Y417110D01*
G01X529960Y417620D02*
Y419040D01*
X528138Y420862D01*
X526295D01*
G01X522641Y440322D02*
X526840D01*
X529520Y443002D01*
Y453522D01*
X525920Y457122D01*
Y473562D01*
X525820Y473662D01*
G01X535375Y442376D02*
X532650D01*
G01X535375Y450330D02*
X532650D01*
G01X535375Y454270D02*
X532650D01*
G01X525955Y478492D02*
X525780Y478317D01*
Y476690D01*
X525050Y475960D01*
X522080D01*
X520924Y474804D01*
Y470181D01*
G01X542554Y465696D02*
X531400D01*
G01X542554Y470814D02*
X531380D01*
G01X517184Y470181D02*
Y475952D01*
G01X542554Y473373D02*
X530009D01*
X529120Y474262D01*
X526420D01*
X525820Y473662D01*
G01X542554Y478492D02*
X530630D01*
G01X525955D02*
X530630D01*
G01X530490Y483610D02*
X542554D01*
G01X519975Y495112D02*
X522555Y492532D01*
X527395D01*
X529975Y495112D01*
G01X535080Y491292D02*
X531260Y495112D01*
X529975D01*
G01Y489112D02*
X527675Y486812D01*
X522275D01*
X519975Y489112D01*
G01X534890Y486169D02*
X531947Y489112D01*
X529975D01*
G01X531258Y505473D02*
Y504665D01*
X526815Y500222D01*
G01X535444Y498578D02*
X533800Y500222D01*
X529965D01*
G01X518563Y607067D02*
Y615730D01*
X518575Y615742D01*
G01X530178Y893036D02*
X530179Y893037D01*
Y895146D01*
G01X532461Y1121446D02*
Y1119337D01*
G01Y1127855D02*
Y1125746D01*
G01X539720Y30792D02*
X541770Y28742D01*
X745600D01*
X756220Y39362D01*
X758820D01*
X763120Y43662D01*
Y48362D01*
X774059Y59301D01*
Y68912D01*
G01X541524Y53544D02*
Y53542D01*
X542053Y53013D01*
Y47455D01*
X542050Y47452D01*
G01X543886Y53544D02*
Y53542D01*
X543924Y53504D01*
Y45826D01*
X540960Y42862D01*
X539720D01*
G01X546248Y53544D02*
Y44420D01*
X544720Y42892D01*
G01X548610Y53544D02*
Y48083D01*
X548609Y48082D01*
G01X548610Y67277D02*
X549264Y67931D01*
G01X541524Y65158D02*
Y67278D01*
X542192Y67946D01*
G01X543886Y65158D02*
Y67222D01*
X543212Y67896D01*
G01X536265Y99172D02*
Y103332D01*
X536245Y103352D01*
G01X536325Y112512D02*
Y108072D01*
X536315Y108062D01*
G01X552395Y127788D02*
X546900D01*
G01D02*
X545445Y129243D01*
X539397D01*
G01Y134361D02*
X545088D01*
X546461Y135734D01*
G01D02*
X548565Y137838D01*
X552331D01*
X552395Y137774D01*
G01X543083Y146338D02*
X542178Y147243D01*
X539397D01*
G01Y152361D02*
X544933D01*
X547600Y155028D01*
G01X567673Y127983D02*
X567662Y127972D01*
X566330D01*
X560720Y133582D01*
Y154952D01*
X556700Y158972D01*
X555420D01*
X554320Y157872D01*
X537190D01*
X534765Y160297D01*
Y161067D01*
G01X544720Y171362D02*
X540643Y167285D01*
X538852D01*
G01X547600Y155028D02*
X548750Y153878D01*
X552395D01*
G01X549645Y161362D02*
X544820D01*
G01X559145D02*
X555869D01*
X553969Y159462D01*
X551545D01*
X549645Y161362D01*
G01X544820D02*
X542720D01*
X541915Y162167D01*
X538852D01*
G01X549645Y171862D02*
X545220D01*
X544720Y171362D01*
G01X539460Y183921D02*
X544720D01*
G01D02*
X548704D01*
X549645Y184862D01*
G01X539460Y181362D02*
X547878D01*
X549306Y179934D01*
G01X554306D02*
X551798Y177426D01*
X547347D01*
X545970Y178803D01*
X539460D01*
G01X549645Y184862D02*
X552145Y187362D01*
X557145D01*
X559645Y184862D01*
G01X536127Y258442D02*
Y260798D01*
X536489Y261160D01*
Y264692D01*
G01D02*
Y269472D01*
G01X557639Y253202D02*
X555384Y250947D01*
X547756D01*
X544001Y254702D01*
G01X539830Y274912D02*
X536489Y271571D01*
Y269472D01*
G01X544920Y306862D02*
Y302362D01*
X605920Y241362D01*
Y226862D01*
X610495Y222287D01*
X616014D01*
G01X547420Y306862D02*
Y302861D01*
X608479Y241802D01*
Y227922D01*
X611555Y224846D01*
X616014D01*
G01X549220Y339687D02*
Y361277D01*
X547330Y363167D01*
G01X552583Y366842D02*
X552058Y366317D01*
X547330D01*
G01X591230Y363354D02*
Y349312D01*
X585000Y343082D01*
X566960D01*
X552090Y357952D01*
Y363042D01*
X550000Y365132D01*
X547800D01*
X547330Y365602D01*
Y366317D01*
G01X535720Y366437D02*
X535910Y366627D01*
Y370450D01*
G01X552583Y396573D02*
X552480Y396470D01*
Y393102D01*
X551970Y392592D01*
X548350D01*
X546830Y394112D01*
Y403292D01*
G01X533720Y400160D02*
Y395937D01*
G01X546830Y403292D02*
Y403582D01*
X548300Y405052D01*
Y408332D01*
G01X547810Y414472D02*
X548300Y413982D01*
Y411482D01*
G01X549670Y419892D02*
X554300Y415262D01*
Y411482D01*
G01X548670Y446396D02*
X544500D01*
X543240Y445136D01*
G01X538525Y446396D02*
Y442376D01*
G01X543240Y445136D02*
X539785D01*
X538525Y446396D01*
G01X542870Y438320D02*
X541300D01*
X538525Y441095D01*
Y442376D01*
G01X548670Y450136D02*
X543240D01*
G01D02*
X538719D01*
X538525Y450330D01*
G01D02*
Y454270D01*
G01X542554Y468255D02*
X535810D01*
G01X542554Y475932D02*
X533410D01*
G01X534990Y481051D02*
X542554D01*
G01Y491680D02*
X540681D01*
X536891Y495470D01*
Y497131D01*
X535444Y498578D01*
G01X542554Y488728D02*
X537644D01*
X535080Y491292D01*
G01X542554Y486169D02*
X534890D01*
G01X538012Y1116133D02*
Y1118240D01*
X538010Y1118242D01*
G01X543561Y1121446D02*
Y1119337D01*
G01X539861Y1127855D02*
Y1125746D01*
G01X534311Y1124650D02*
Y1122541D01*
G01X536161Y1127855D02*
Y1125746D01*
G01Y1121446D02*
Y1119337D01*
G01X539861Y1121446D02*
Y1119337D01*
G01X541711Y1124650D02*
Y1122541D01*
G01X543561Y1127855D02*
Y1125746D01*
G01X538012Y1131059D02*
Y1128950D01*
G01X535862Y1370319D02*
X536763Y1369418D01*
Y1364545D01*
X538004Y1363304D01*
X538230Y1362759D01*
Y1361484D01*
G01X552000Y1452937D02*
X550076D01*
X549364Y1452225D01*
Y1445141D01*
X549236Y1445013D01*
Y1441207D01*
G01X565146Y53544D02*
Y48020D01*
X565184Y47982D01*
G01X563482Y40826D02*
X563242Y40586D01*
X562586D01*
X560421Y42751D01*
Y53544D01*
G01X558058Y46352D02*
X558059Y46353D01*
Y53544D01*
G01X562784D02*
Y49833D01*
X562190Y49239D01*
Y43803D01*
X563081Y42912D01*
X565669D01*
X568959Y39622D01*
X576590D01*
X586260Y49292D01*
Y52222D01*
G01X550972Y53544D02*
Y42903D01*
X550971Y42902D01*
G01X555697Y53544D02*
Y47882D01*
X554983Y47168D01*
Y45312D01*
G01X553335Y53544D02*
Y49157D01*
X553650Y48842D01*
G01X565146Y65158D02*
Y81936D01*
X562820Y84262D01*
G01X562784Y65158D02*
Y78298D01*
X562783Y78299D01*
G01X550972Y65158D02*
Y67223D01*
X550284Y67911D01*
Y67931D01*
G01X564425Y102862D02*
X559000D01*
G01X564425Y98862D02*
X561000D01*
G01X551231Y122671D02*
X560040Y113862D01*
X569795D01*
X589330Y94327D01*
Y91095D01*
G01X571373Y133101D02*
X566661D01*
X564200Y135562D01*
G01D02*
X562100Y137662D01*
Y145852D01*
X563539Y147291D01*
X569273D01*
G01X555545Y127788D02*
X558515D01*
G01X566500Y125097D02*
X565425D01*
X562734Y127788D01*
X558515D01*
G01X569273Y142173D02*
X564890D01*
G01X555545Y153878D02*
X557525D01*
X559065Y152338D01*
Y139338D01*
X557501Y137774D01*
X555545D01*
G01X654325Y174437D02*
X638673D01*
X632910Y180200D01*
Y192572D01*
X631780Y193702D01*
X610280D01*
X603680Y187102D01*
Y172392D01*
X598880Y167592D01*
X590710D01*
X585780Y162662D01*
X579540D01*
X578120Y164082D01*
X565015D01*
X562295Y161362D01*
G01X573795Y167112D02*
X571605Y169302D01*
X564485D01*
X562295Y167112D01*
G01X569470Y171702D02*
X563735D01*
X559145Y167112D01*
G01X555545Y153878D02*
Y156462D01*
G01X562795Y184862D02*
X567500D01*
G01X557639Y253202D02*
X558263Y253826D01*
X562440D01*
G01D02*
X563346Y254732D01*
X567644D01*
G01X554489Y257202D02*
X552089D01*
G01X557639D02*
X559639Y259202D01*
X562564D01*
G01D02*
X565733D01*
X567644Y257291D01*
G01X593120Y342782D02*
Y339962D01*
X590220Y337062D01*
X586424D01*
X566804Y317442D01*
X551500D01*
X550760Y316702D01*
Y311616D01*
G01X566514Y310847D02*
X565745Y311616D01*
X558240D01*
G01X555520Y309827D02*
X555985D01*
X557774Y311616D01*
X558240D01*
G01X552760Y300922D02*
X550760Y302922D01*
Y306498D01*
G01X558240D02*
Y300872D01*
G01X575050Y383602D02*
X577144Y385696D01*
X582558D01*
X588370Y379884D01*
Y350262D01*
X584200Y346092D01*
X569310D01*
X564698Y350704D01*
Y363127D01*
G01X557490Y361932D02*
Y366011D01*
X555142Y368359D01*
Y373573D01*
G01X557490Y361932D02*
X560353D01*
X564698Y366277D01*
G01X552583Y366842D02*
Y373573D01*
G01X569340Y366277D02*
X564698D01*
G01X580629Y370896D02*
X576888D01*
X573990Y367998D01*
X561051D01*
X560260Y368789D01*
Y373573D01*
G01X576907Y374655D02*
X576233Y373981D01*
Y372167D01*
X573461Y369395D01*
X563434D01*
X562819Y370010D01*
Y373573D01*
G01X565378Y396573D02*
Y394434D01*
X566400Y393412D01*
X569670D01*
X570700Y394442D01*
Y397162D01*
G01X555142Y396573D02*
Y399800D01*
X553210Y401732D01*
Y403652D01*
G01D02*
Y407242D01*
X554300Y408332D01*
G01X564300D02*
Y403607D01*
X564170Y403477D01*
G01D02*
X560260Y399567D01*
Y396573D01*
G01X562200Y419412D02*
X564300Y417312D01*
Y411482D01*
G01X559300Y417182D02*
X556800Y414682D01*
Y410832D01*
X559300Y408332D01*
G01D02*
Y404307D01*
X558590Y403597D01*
G01D02*
Y403697D01*
X557701Y402808D01*
Y396573D01*
G01X562819D02*
Y398811D01*
X564720Y400712D01*
X566750D01*
X569600Y403562D01*
G01X568400Y424392D02*
Y427002D01*
X567760Y427642D01*
X559330D01*
X556400Y424712D01*
Y420082D01*
X559300Y417182D01*
G01X558118Y442656D02*
X564965D01*
G01D02*
Y446683D01*
X564942Y446706D01*
G01X569490Y437600D02*
X572320D01*
X573341Y438621D01*
Y448789D01*
X572980Y449150D01*
X565560D01*
X564942Y448532D01*
Y446706D01*
G01X565586Y462744D02*
X568918D01*
G01X565586Y465696D02*
X568526D01*
X571670Y462552D01*
X576950D01*
G01X565586Y468255D02*
X568687D01*
X570750Y466192D01*
X572400D01*
G01X565586Y470814D02*
X569098D01*
X570080Y469832D01*
X576920D01*
G01X565586Y473373D02*
X572379D01*
G01X565586Y475932D02*
X576970D01*
G01X565586Y478492D02*
X572540D01*
G01X565586Y481051D02*
X577000D01*
G01X565586Y483610D02*
X572442D01*
X572520Y483532D01*
G01X565586Y486169D02*
X569887D01*
X572400Y488682D01*
G01X565586Y488728D02*
X568596D01*
X572380Y492512D01*
Y493802D01*
G01X960920Y659762D02*
X965320D01*
X968120Y662562D01*
Y667062D01*
X961320Y673862D01*
X805774D01*
X799074Y667162D01*
X717374D01*
X699320Y649108D01*
Y615708D01*
X682874Y599262D01*
X576274D01*
X559620Y582608D01*
Y568208D01*
X554320Y562908D01*
Y512316D01*
X561774Y504862D01*
X565964D01*
X566664Y504162D01*
X568520D01*
G01X963720Y662262D02*
X965020D01*
X966020Y663262D01*
Y666262D01*
X960220Y672062D01*
X806520D01*
X799820Y665362D01*
X718120D01*
X701120Y648362D01*
Y631254D01*
X701630Y630744D01*
X704232D01*
X704742Y630234D01*
Y628744D01*
X704232Y628234D01*
X701630D01*
X701120Y627724D01*
Y626234D01*
X701630Y625724D01*
X704232D01*
X704742Y625214D01*
Y623724D01*
X704232Y623214D01*
X701630D01*
X701120Y622704D01*
Y621214D01*
X701630Y620704D01*
X704232D01*
X704742Y620194D01*
Y618704D01*
X704232Y618194D01*
X701630D01*
X701120Y617684D01*
Y614962D01*
X683620Y597462D01*
X577020D01*
X561420Y581862D01*
Y567462D01*
X556120Y562162D01*
Y513062D01*
X562520Y506662D01*
X568520D01*
G01X797200Y599883D02*
Y602312D01*
X788630Y610882D01*
Y617352D01*
X777420Y628562D01*
X752620D01*
X741320Y617262D01*
Y613562D01*
X738120Y610362D01*
X732320D01*
X727970Y606012D01*
X706370D01*
X694000Y593642D01*
X579100D01*
X565420Y579962D01*
Y558302D01*
X560700Y553582D01*
Y549230D01*
X559927Y548457D01*
G01X552000Y1456787D02*
Y1452937D01*
G01X569236Y1441207D02*
Y1444347D01*
X560646Y1452937D01*
X557720D01*
G01X654540Y1424205D02*
X653653Y1425092D01*
X643080D01*
X609310Y1458862D01*
X570423D01*
X569913Y1458352D01*
Y1457056D01*
X569403Y1456546D01*
X567913D01*
X567403Y1457056D01*
Y1458352D01*
X566893Y1458862D01*
X558220D01*
X555830Y1456472D01*
Y1454827D01*
X557720Y1452937D01*
G01X654540Y1427605D02*
X653737Y1426802D01*
X643790D01*
X610020Y1460572D01*
X552635D01*
X552000Y1459937D01*
G01X572232Y53544D02*
Y43870D01*
X573190Y42912D01*
G01X567507Y45869D02*
X567508Y45870D01*
Y53544D01*
G01X574595D02*
Y48407D01*
X575330Y47672D01*
G01X569870Y53544D02*
Y48320D01*
X570208Y47982D01*
G01X567865Y92656D02*
X582000Y78521D01*
Y60082D01*
X584788Y57294D01*
X586120Y56742D01*
X587152Y55710D01*
X588500Y52456D01*
Y49002D01*
X589329Y44835D01*
X589897Y43464D01*
X591230Y42131D01*
X600329Y38362D01*
X607501D01*
X610461Y41322D01*
Y53544D01*
G01X574595Y65158D02*
Y82887D01*
X573920Y83562D01*
X572220D01*
G01X572232Y65158D02*
Y77861D01*
X572231Y77862D01*
G01X569870Y65158D02*
Y85012D01*
X567520Y87362D01*
G01X567508Y65158D02*
Y81048D01*
X567507Y81049D01*
G01X570150Y102862D02*
X576407Y96605D01*
X583410Y79698D01*
Y60803D01*
X585262Y58951D01*
X586491Y58442D01*
X588614Y56319D01*
X589910Y53190D01*
Y49171D01*
X590631Y45545D01*
X591207Y44155D01*
X591732Y43630D01*
X600829Y39862D01*
X606000D01*
X608780Y42642D01*
Y50662D01*
X608098Y51344D01*
Y53544D01*
G01X567575Y102862D02*
X570150D01*
G01X567575Y98862D02*
X567865Y98572D01*
Y92656D01*
G01X571373Y127983D02*
X567673D01*
G01X579247Y133101D02*
X584638D01*
X586068Y134531D01*
G01X585986Y124754D02*
X582757Y127983D01*
X579247D01*
G01X578765Y152912D02*
Y147757D01*
X578299Y147291D01*
X577147D01*
G01X581120Y155062D02*
Y144222D01*
X586460Y138882D01*
X592827D01*
X595395Y136314D01*
G01X573360Y140532D02*
X575001Y142173D01*
X577147D01*
G01X573795Y167112D02*
X578720D01*
G01D02*
X583711D01*
X583875Y167276D01*
G01X579275Y157684D02*
X578765Y157174D01*
Y152912D01*
G01X582425Y157684D02*
Y156367D01*
X581120Y155062D01*
G01X567500Y184862D02*
Y182962D01*
X580627Y169835D01*
X583875D01*
G01X581881Y194378D02*
X579481D01*
G01X570645Y225362D02*
X567730D01*
G01X573795D02*
X578390D01*
G01D02*
X580240Y227212D01*
X582945D01*
X584795Y225362D01*
G01X570645Y221362D02*
X567730D01*
G01X584795D02*
X581995Y218562D01*
X578450D01*
G01D02*
X576595D01*
X573795Y221362D01*
G01X575124Y252173D02*
X580320D01*
G01D02*
X586460D01*
X586489Y252202D01*
G01X574800Y322462D02*
X579500D01*
X610900Y353862D01*
Y376062D01*
X608208Y378754D01*
Y396661D01*
X585450Y419419D01*
Y454312D01*
X595600Y464462D01*
Y481962D01*
X598300Y484662D01*
X605248D01*
X607750Y482160D01*
X622170D01*
X625090Y485080D01*
X630050D01*
X631625Y483505D01*
Y482662D01*
G01X577720Y381862D02*
Y377792D01*
X586442Y369070D01*
Y369040D01*
X580484Y363082D01*
X578582D01*
G01X571830Y348772D02*
X569340Y351262D01*
Y363127D01*
G01X586070Y352302D02*
X579140D01*
X573460Y357982D01*
Y363127D01*
G01Y366277D02*
X573505Y366232D01*
X578582D01*
G01X580629Y370896D02*
Y366604D01*
X580257Y366232D01*
X578582D01*
G01X571720Y381862D02*
Y385572D01*
X573608Y387460D01*
X583410D01*
X594380Y376490D01*
Y363354D01*
G01X570700Y397162D02*
X572200Y398662D01*
Y404562D01*
X569300Y407462D01*
Y408332D01*
G01X569600Y403562D02*
X566830Y406332D01*
Y418402D01*
X568030Y419602D01*
X569112D01*
X569152Y419562D01*
G01X568115Y442656D02*
X571110D01*
G01X568918Y462744D02*
X572430Y459232D01*
G01X568092Y446706D02*
X571110D01*
G01X580645Y493212D02*
X583220D01*
G01X587995Y488212D02*
X585565Y490642D01*
X579925D01*
X577495Y488212D01*
G01X572520Y483532D02*
X573590D01*
X577495Y487437D01*
Y488212D01*
G01X572400Y488682D02*
X576930Y493212D01*
X577495D01*
G01X572380Y493802D02*
X575790Y497212D01*
X577495D01*
G01X569050Y578292D02*
Y537200D01*
X566700Y534850D01*
Y514000D01*
X568979Y511721D01*
X575321D01*
X595640Y491402D01*
Y486662D01*
X583140Y474162D01*
Y418462D01*
X605898Y395704D01*
Y372984D01*
G01X584173Y498422D02*
X582963Y497212D01*
X580645D01*
G01X582075Y514362D02*
Y510337D01*
X583150Y509262D01*
G01X598650Y53544D02*
Y48742D01*
X597955Y48047D01*
G01X593369Y45682D02*
X596146Y48459D01*
Y49796D01*
X596287Y49937D01*
Y53544D01*
G01X593925Y65158D02*
Y76097D01*
X592265Y77757D01*
G01X590680Y83591D02*
X589330Y84941D01*
Y87945D01*
G01X592265Y77757D02*
Y81075D01*
X593240Y82050D01*
Y87945D01*
G01X598410Y124102D02*
X600695Y121817D01*
X602278D01*
G01X586068Y134531D02*
X587851Y136314D01*
X592245D01*
G01X598390Y126802D02*
X596902Y125314D01*
X595395D01*
G01X592245D02*
X586546D01*
X585986Y124754D01*
G01X598724Y150296D02*
X598240Y149812D01*
X590590D01*
X588181Y152221D01*
Y152575D01*
G01X593299Y145883D02*
X594270Y144912D01*
X597480D01*
X598795Y146227D01*
G01X591355Y164717D02*
X596720D01*
G01X589690Y161732D02*
X591355Y163397D01*
Y164717D01*
G01X596720D02*
X601540D01*
X601645Y164612D01*
G01X599720Y179287D02*
X596795D01*
G01X593220D02*
X591692D01*
X590281Y180698D01*
G01X593220Y187287D02*
Y184887D01*
G01Y182437D02*
Y184887D01*
G01X585031Y198378D02*
Y202378D01*
G01Y194378D02*
X585025Y194372D01*
Y190092D01*
G01X595644Y204994D02*
X594071D01*
X589956Y200879D01*
Y200878D01*
G01D02*
Y199303D01*
X585031Y194378D01*
G01X599720Y190437D02*
Y192093D01*
X596576Y195237D01*
G01D02*
X598203Y196864D01*
Y200466D01*
G01X593220Y190437D02*
Y193242D01*
X590900Y195562D01*
G01D02*
X593456Y198118D01*
Y201878D01*
X594603Y203025D01*
X595644D01*
G01Y206962D02*
X589956D01*
G01D02*
X589615D01*
X585031Y202378D01*
G01Y210378D02*
Y215378D01*
G01Y210378D02*
Y206378D01*
G01Y215378D02*
X591478Y208931D01*
X595644D01*
G01X595900Y216612D02*
X596820D01*
X600172Y213260D01*
Y211490D01*
G01X591420Y213922D02*
X596651D01*
X598203Y212370D01*
Y211490D01*
G01X598416Y224846D02*
X585311D01*
X584795Y225362D01*
G01Y221362D02*
X585720Y222287D01*
X598416D01*
G01X592220Y249362D02*
X588120D01*
X586489Y250993D01*
Y252202D01*
G01X640720Y290267D02*
Y274973D01*
X628759Y263012D01*
X598890D01*
X596239Y260361D01*
Y257532D01*
G01X593763Y293999D02*
Y295699D01*
X594236Y296172D01*
X595419D01*
X597812Y293779D01*
X599552D01*
G01X588850Y291622D02*
X589252Y291220D01*
X599552D01*
G01Y296338D02*
X597863D01*
X596119Y298082D01*
X592936D01*
G01D02*
X589545D01*
X588120Y296657D01*
G01X610720Y462862D02*
X607455Y459597D01*
Y428627D01*
X612718Y423364D01*
Y352856D01*
X595520Y335658D01*
Y314862D01*
G01X599552Y311693D02*
X593265D01*
G01D02*
X588242D01*
X588120Y311571D01*
G01X599552Y304016D02*
X593311D01*
G01D02*
X588156D01*
X588120Y304052D01*
G01X595380Y416660D02*
X593580D01*
X587530Y422710D01*
Y441190D01*
X599824Y453484D01*
Y454600D01*
G01X583150Y509262D02*
X584339D01*
X586760Y511683D01*
Y514303D01*
G01X594240Y516862D02*
X591500D01*
G01X680220Y524787D02*
X683585Y528152D01*
Y531448D01*
X681671Y533362D01*
X614000D01*
X597500Y516862D01*
X594240D01*
G01Y519421D02*
Y524527D01*
X594575Y524862D01*
G01D02*
X599900D01*
G01X586760Y514303D02*
X588441D01*
X589000Y514862D01*
Y516362D01*
X588500Y516862D01*
X586760D01*
G01X612823Y53544D02*
X612300Y53021D01*
Y43754D01*
X612822Y43232D01*
G01X606880Y44682D02*
X605736Y45826D01*
Y53544D01*
G01X617547D02*
Y48159D01*
X615400Y46012D01*
X614400D01*
G01X603374Y53544D02*
Y48334D01*
X603063Y48023D01*
G01X601012Y53544D02*
Y49937D01*
X600873Y49798D01*
Y44225D01*
X599800Y43152D01*
G01X610461Y65158D02*
Y80721D01*
X608620Y82562D01*
Y94162D01*
G01X608098Y65158D02*
Y78784D01*
X606020Y80862D01*
Y84562D01*
G01X612823Y65158D02*
Y91240D01*
X613020Y91437D01*
Y94162D01*
G01X605736Y65158D02*
Y76446D01*
X603220Y78962D01*
Y87662D01*
X603880Y88322D01*
Y93902D01*
G01X603410Y132682D02*
X606260Y135532D01*
X612170D01*
X614707Y138069D01*
Y139283D01*
G01X610104Y124967D02*
X606079D01*
G01X610104D02*
X614384D01*
G01X606079D02*
X602278D01*
G01X616676Y139283D02*
Y136538D01*
X614000Y133862D01*
G01D02*
Y125351D01*
X614384Y124967D01*
G01X600071Y138202D02*
X602019D01*
X604214Y140397D01*
Y144689D01*
X606338Y146813D01*
X609146D01*
G01X605090Y137542D02*
X611681D01*
X612738Y138599D01*
Y139283D01*
G01X598724Y150296D02*
X599480Y151052D01*
X602580D01*
G01D02*
X603830D01*
X604133Y150749D01*
X609146D01*
G01X598795Y146227D02*
X599120Y145902D01*
X602522D01*
X603019Y146399D01*
G01D02*
X605401Y148781D01*
X609146D01*
G01X607940Y173930D02*
Y166763D01*
X614707Y159996D01*
Y158279D01*
G01X612738D02*
Y159694D01*
X605530Y166902D01*
Y176520D01*
X607940Y178930D01*
G01X609146Y154687D02*
X607575D01*
X603981Y158281D01*
G01D02*
X602782Y159480D01*
X599330D01*
G01X599720Y187287D02*
Y184887D01*
G01Y182437D02*
Y184887D01*
G01X602000Y195162D02*
X600172Y196990D01*
Y200466D01*
G01X607200Y194062D02*
X602140Y199122D01*
Y200466D01*
G01X611200Y197262D02*
X606200D01*
X604109Y199353D01*
Y200466D01*
G01X601230Y216482D02*
X602140Y215572D01*
Y211490D01*
G01X616014Y227406D02*
X613030D01*
X612331Y228105D01*
Y229265D01*
X613031Y229965D01*
X616014D01*
G01X609419Y257525D02*
X611251D01*
X612034Y256742D01*
Y253202D01*
X611239Y252407D01*
X609419D01*
G01X599389Y257532D02*
X604230D01*
G01D02*
X609412D01*
X609419Y257525D01*
G01X618115Y278205D02*
X614095D01*
G01X616790Y283292D02*
X614095Y280597D01*
Y278205D01*
G01X604725D02*
X608895D01*
G01X608920Y283292D02*
Y278230D01*
X608895Y278205D01*
G01X621992Y291220D02*
X615078D01*
X608920Y285062D01*
Y283292D01*
G01X605350Y293092D02*
X603220Y295222D01*
Y298272D01*
X602595Y298897D01*
X599552D01*
G01X627236Y320876D02*
X625745Y319385D01*
Y315167D01*
X624600Y314022D01*
X620070D01*
X618010Y311962D01*
Y305752D01*
X605350Y293092D01*
G01X619496Y320895D02*
X619690Y320701D01*
Y317622D01*
X615560Y313492D01*
Y307862D01*
X605870Y298172D01*
G01D02*
X602585Y301457D01*
X599552D01*
G01X646645Y462862D02*
Y464218D01*
X645501Y465362D01*
X642620D01*
X637520Y460262D01*
X610420D01*
X608865Y458707D01*
Y429517D01*
X614318Y424064D01*
Y352460D01*
X600320Y338462D01*
Y315462D01*
X599620Y314762D01*
G01X599552Y306575D02*
X602357D01*
X605560Y303372D01*
G01D02*
X611380Y309192D01*
Y320616D01*
X611609Y320845D01*
G01X599552Y309134D02*
X601992D01*
X607590Y314732D01*
G01D02*
X603790Y318532D01*
Y320763D01*
X603822Y320795D01*
G01X614130Y328762D02*
Y326516D01*
X611609Y323995D01*
G01X615635Y324030D02*
X615600Y323995D01*
X611609D01*
G01X603822Y323945D02*
X603851Y323974D01*
X607675D01*
G01X605305Y331162D02*
X603822Y329679D01*
Y323945D01*
G01X600800Y430900D02*
X602220Y429480D01*
Y426622D01*
G01X602795Y416362D02*
X605220D01*
G01X599661Y426622D02*
Y421362D01*
G01D02*
Y416378D01*
X599645Y416362D01*
G01X604795Y449362D02*
Y444362D01*
G01D02*
X604779Y444346D01*
Y442321D01*
X601820Y439362D01*
G01D02*
X604779Y436403D01*
Y434102D01*
G01X616645Y442862D02*
X614220D01*
G01X602910Y461862D02*
Y458783D01*
X603005Y458688D01*
G01X601645Y449362D02*
X600345Y448062D01*
X599080D01*
G01X616645Y457862D02*
X614220D01*
G01X604360Y452120D02*
Y453214D01*
X602974Y454600D01*
G01X616645Y467862D02*
X614220D01*
G01X616645Y472862D02*
X614220D01*
G01X602910Y464768D02*
Y461862D01*
G01X602795Y482362D02*
Y477362D01*
G01X600351Y472248D02*
Y470731D01*
X600720Y470362D01*
X602520D01*
X602910Y470752D01*
Y472248D01*
G01X602795Y477362D02*
Y472363D01*
X602910Y472248D01*
G01X605469Y464768D02*
Y467562D01*
G01X616645Y477862D02*
X614220D01*
G01X601220Y489622D02*
Y486922D01*
G01X598661Y489622D02*
Y486922D01*
G01X600645Y506862D02*
Y510862D01*
G01Y506862D02*
Y504362D01*
G01X603779Y497102D02*
Y502082D01*
G01D02*
Y506846D01*
X603795Y506862D01*
G01X600645Y510862D02*
Y514862D01*
G01X603795Y510862D02*
X606200D01*
G01X599900Y524862D02*
X602500D01*
X613000Y535362D01*
X682500D01*
X685500Y532362D01*
Y523861D01*
X680220Y518581D01*
Y514437D01*
G01X637220Y31462D02*
Y33762D01*
X632220Y38762D01*
X630220D01*
X626920Y42062D01*
Y44952D01*
X631520Y49552D01*
Y76092D01*
X629684Y77928D01*
G01X624634Y53544D02*
Y49194D01*
X624633Y49193D01*
G01X622272Y53544D02*
Y57951D01*
X622271Y57952D01*
G01X629820Y42562D02*
X631192Y41190D01*
X640092D01*
X641820Y39462D01*
X650338D01*
X652231Y41355D01*
Y49936D01*
X652232Y49937D01*
Y53544D01*
G01X619910D02*
Y49541D01*
X619562Y49193D01*
G01X622272Y65158D02*
Y74093D01*
X623290Y75111D01*
Y78482D01*
G01X619910Y65158D02*
Y94932D01*
X617585Y97257D01*
G01X624634Y65158D02*
Y71976D01*
X626000Y73342D01*
Y96652D01*
X622540Y100112D01*
X620540D01*
G01X617547Y65158D02*
Y94024D01*
X617409Y94162D01*
G01X629684Y77928D02*
Y82218D01*
X627620Y84282D01*
Y106482D01*
X654050Y132912D01*
Y149692D01*
X650820Y152922D01*
Y157187D01*
X646145Y161862D01*
G01X623290Y78482D02*
Y86997D01*
X622000Y88287D01*
G01X623300Y95762D02*
Y92737D01*
X622000Y91437D01*
G01X632300Y104472D02*
X629360Y101532D01*
Y90021D01*
X631342Y88039D01*
G01X624550Y139283D02*
Y136812D01*
X627000Y134362D01*
X629500D01*
G01D02*
X630850Y133012D01*
Y125068D01*
X630951Y124967D01*
G01X626699D02*
Y129862D01*
G01D02*
Y131663D01*
X622581Y135781D01*
Y139283D01*
G01X620612D02*
Y133862D01*
G01D02*
X622592Y131882D01*
Y124967D01*
G01X618644Y139283D02*
Y136007D01*
X617500Y134863D01*
Y129862D01*
G01D02*
X618460Y128902D01*
Y124967D01*
G01X637055Y159515D02*
X634959Y157419D01*
Y154715D01*
X630993Y150749D01*
X628142D01*
G01X640000Y154345D02*
X636533D01*
X630969Y148781D01*
X628142D01*
G01Y146813D02*
X632451D01*
X633500Y147862D01*
G01X628142Y144844D02*
X639982D01*
G01X633500Y141362D02*
X631987Y142875D01*
X628142D01*
G01X615970Y161522D02*
Y160452D01*
X616676Y159746D01*
Y158279D01*
G01X637145Y230362D02*
X634475Y227692D01*
X629890D01*
X627645Y229937D01*
Y230362D01*
G01D02*
X622730D01*
G01D02*
X619721D01*
X619324Y229965D01*
X616014D01*
G01X630139Y249202D02*
X634880D01*
G01X622064Y250202D02*
X623064Y249202D01*
X626989D01*
G01X630139Y260202D02*
X634820D01*
G01X616899Y257525D02*
X620388D01*
X621893Y259030D01*
G01D02*
X623065Y260202D01*
X626989D01*
G01X616899Y252407D02*
X619859D01*
X622064Y250202D01*
G01X621992Y288661D02*
X619539D01*
X616790Y285912D01*
Y283292D01*
G01X621992Y296338D02*
X629870D01*
G01D02*
X630594D01*
X632610Y294322D01*
X637565D01*
X637570Y294327D01*
G01X621992Y293779D02*
X627073D01*
X630670Y290182D01*
X631861D01*
G01X621992Y304016D02*
X628603D01*
G01D02*
X634076D01*
X636607Y306547D01*
X637570D01*
G01X621992Y301457D02*
X633150D01*
G01X621992Y298897D02*
X627950D01*
G01D02*
X636970D01*
X637570Y298297D01*
G01X621992Y309134D02*
X627600D01*
G01D02*
X631117D01*
X637570Y315587D01*
G01X621992Y306575D02*
X632143D01*
G01X619474Y331162D02*
X626610Y324026D01*
X627236D01*
G01X631146Y324065D02*
X631107Y324026D01*
X627236D01*
G01X619496Y324045D02*
X623360D01*
X623365Y324050D01*
G01X615180Y336812D02*
Y330417D01*
X619496Y326101D01*
Y324045D01*
G01X674731Y359924D02*
X667479D01*
X663070Y364333D01*
Y373831D01*
X656286Y380615D01*
X633728D01*
X623214Y370101D01*
X618803D01*
X615920Y372984D01*
Y421779D01*
X617645Y423504D01*
Y426362D01*
G01X676203Y413289D02*
X680220Y409272D01*
Y404333D01*
X678190Y399432D01*
X676520Y397762D01*
Y388846D01*
X674036Y386362D01*
X630824D01*
X619100Y374638D01*
G01X679353Y413289D02*
X682720Y409922D01*
Y404004D01*
X680279Y398111D01*
X678930Y396762D01*
Y387672D01*
X675210Y383952D01*
X632310D01*
X621720Y373362D01*
G01X628500Y402362D02*
Y405362D01*
X630000Y406862D01*
X631425D01*
G01X624220Y411362D02*
X624720D01*
X627220Y408862D01*
X644145D01*
X646645Y411362D01*
G01X631645D02*
X629220D01*
G01X620795Y426362D02*
X623220D01*
G01X625500Y421362D02*
X630500Y416362D01*
X631645D01*
G01Y421362D02*
X629220D01*
G01X631645Y426362D02*
X629220D01*
G01X625900Y431050D02*
Y431542D01*
X628720Y434362D01*
X630721D01*
X631645Y433438D01*
Y431362D01*
G01X629220Y442862D02*
X630645D01*
X631645Y441862D01*
G01X619795Y442862D02*
X622220D01*
G01X619795Y457862D02*
X622220D01*
G01X631645Y452862D02*
X629220D01*
G01X631645Y447862D02*
X629220D01*
G01X634795Y467862D02*
Y466438D01*
X633619Y465262D01*
X624460D01*
G01D02*
X620819D01*
X619795Y466286D01*
Y467862D01*
G01X634795Y472862D02*
Y471438D01*
X633719Y470362D01*
X624460D01*
G01D02*
X620819D01*
X619795Y471386D01*
Y472862D01*
G01X634795Y477862D02*
Y476637D01*
X633620Y475462D01*
X624470D01*
G01D02*
X620719D01*
X619795Y476386D01*
Y477862D01*
G01Y462862D02*
X622220D01*
G01X629480Y512425D02*
Y508862D01*
G01X629920Y516652D02*
X629820Y516752D01*
X626910D01*
X622583Y512425D01*
X619220D01*
G01X633220Y520299D02*
X629372D01*
X626680Y522991D01*
Y525972D01*
G01D02*
X625000D01*
X622960Y523932D01*
Y520299D01*
G01X866820Y736562D02*
Y735962D01*
X860930Y730072D01*
X856130D01*
X795120Y669062D01*
X716435D01*
X711279Y663906D01*
X654269D01*
X641286Y658528D01*
X629220Y646462D01*
Y643462D01*
G01X863925Y737697D02*
X858390Y732162D01*
X854684D01*
X793784Y671262D01*
X714932D01*
X709880Y666210D01*
X654546D01*
X639713Y660067D01*
X630064Y650418D01*
X630063D01*
X627020Y647374D01*
Y645318D01*
X626720D01*
Y643462D01*
G01X762617Y758885D02*
X727287D01*
X723847Y762325D01*
X626083D01*
X623936Y764472D01*
X618860D01*
X617940Y763552D01*
G01X625249Y766798D02*
X625569Y766478D01*
X629658D01*
G01X625249Y1252034D02*
X633819D01*
X635495Y1250358D01*
X638157D01*
G01X644617D02*
X645069D01*
X646745Y1252034D01*
X654949D01*
G01X625249Y1255381D02*
X629699D01*
G01X625249Y1262074D02*
X632080D01*
G01X628970Y1670880D02*
Y1678810D01*
X630050Y1679890D01*
X637550D01*
X639250Y1678190D01*
X653820D01*
X658380Y1682750D01*
X686670D01*
X688670Y1684750D01*
X696690D01*
X699750Y1681690D01*
Y1675249D01*
X699363Y1674862D01*
X695195D01*
G01X649870Y53544D02*
Y49937D01*
X649869Y49936D01*
Y42334D01*
X649117Y41582D01*
X644440D01*
X643880Y42142D01*
G01X642784Y53544D02*
Y59299D01*
X640531Y61552D01*
X638731D01*
X637000Y63283D01*
Y68142D01*
G01X640421Y53544D02*
X640700Y53823D01*
Y58263D01*
X639301Y59662D01*
X637101D01*
X634500Y62263D01*
Y73422D01*
G01X645146Y53544D02*
Y50708D01*
X641200Y46762D01*
G01X642784Y65158D02*
Y77926D01*
X644360Y79502D01*
X648258D01*
G01X640421Y65158D02*
Y80218D01*
X643387Y83184D01*
G01X637000Y68142D02*
Y71363D01*
X638500Y72863D01*
Y79787D01*
G01X643387Y83184D02*
X643490Y83287D01*
X647420D01*
X648320Y84187D01*
G01X649870Y65158D02*
Y68763D01*
X649573Y69060D01*
Y73021D01*
X645462Y77132D01*
X645330D01*
G01X647508Y65158D02*
Y70794D01*
X645330Y72972D01*
G01X638500Y82937D02*
X640220Y84657D01*
Y85542D01*
G01D02*
Y86293D01*
X638478Y88035D01*
G01X634500Y82937D02*
X634690Y83127D01*
Y85542D01*
G01D02*
X634492Y85740D01*
Y88039D01*
G01X634500Y73422D02*
Y79787D01*
G01X638438Y92085D02*
Y88075D01*
X638478Y88035D01*
G01X634492Y92119D02*
Y88039D01*
G01X640000Y108542D02*
X637000Y105542D01*
Y102254D01*
X637842Y101412D01*
X640549D01*
X641588Y100373D01*
Y92085D01*
G01X639970Y113892D02*
X637530D01*
X634820Y111182D01*
Y102817D01*
X631342Y99339D01*
Y92119D01*
G01X639901Y103462D02*
X641389D01*
X644040Y100811D01*
Y90447D01*
X641628Y88035D01*
G01X652035Y120412D02*
X647700D01*
X645230Y117942D01*
Y116302D01*
G01D02*
X647380Y114152D01*
X652279D01*
G01X645069Y140699D02*
X645086Y140682D01*
Y134506D01*
G01X633500Y147862D02*
X635509Y149871D01*
X645069D01*
G01X639982Y144844D02*
X640120Y144982D01*
X645069D01*
G01Y140699D02*
X634163D01*
X633500Y141362D01*
G01X646145Y166362D02*
X640130D01*
G01X645069Y154345D02*
X640000D01*
G01X635820Y180570D02*
X638520Y183270D01*
Y187030D01*
X640430Y188940D01*
X652040D01*
X653140Y190040D01*
X661609D01*
X662476Y189173D01*
X667551D01*
G01X641766Y180757D02*
X640590Y181933D01*
Y186670D01*
X641370Y187450D01*
X652310D01*
X653440Y188580D01*
X661130D01*
X662506Y187204D01*
X667551D01*
G01X635820Y190570D02*
X637230Y191980D01*
X650900D01*
X652030Y193110D01*
X667551D01*
G01Y191142D02*
X663247D01*
X662939Y191450D01*
X652490D01*
X651420Y190380D01*
X639620D01*
X635820Y186580D01*
Y185570D01*
G01X640295Y230362D02*
Y234237D01*
G01X828145Y176362D02*
X822035Y170252D01*
X790910D01*
X769310Y191852D01*
Y223942D01*
X759835Y233417D01*
X668565D01*
X648130Y253852D01*
X642109D01*
X639559Y251302D01*
Y249202D01*
G01X634880D02*
X639559D01*
G01X634820Y260202D02*
X639559D01*
G01D02*
Y258023D01*
X642020Y255562D01*
X648840D01*
X669275Y235127D01*
X760545D01*
X771020Y224652D01*
Y192562D01*
X791620Y171962D01*
X819320D01*
X826720Y179362D01*
X869919D01*
X871519Y180962D01*
X883820D01*
X884290Y181432D01*
Y183106D01*
G01X631861Y290182D02*
X637485D01*
X637570Y290267D01*
G01X652670Y290371D02*
X652566Y290267D01*
X640720D01*
G01Y298297D02*
X643800D01*
G01X640720Y302247D02*
X643800D01*
G01X633150Y301457D02*
X636780D01*
X637570Y302247D01*
G01X645990Y314482D02*
X644885Y315587D01*
X640720D01*
G01Y310962D02*
X643800D01*
G01X632143Y306575D02*
X633183D01*
X637570Y310962D01*
G01X651520Y378662D02*
X645020Y372162D01*
Y352762D01*
X652670Y345112D01*
Y290371D01*
G01X636075Y392862D02*
Y389862D01*
G01X632620D02*
X632925Y390167D01*
Y392862D01*
G01X645925D02*
Y389937D01*
G01X638700Y400962D02*
Y405162D01*
X637000Y406862D01*
X634575D01*
G01X647700Y399162D02*
X646425Y400437D01*
Y402362D01*
G01X643500Y400962D02*
Y406842D01*
X643520Y406862D01*
X646425D01*
G01X643940Y411482D02*
Y413657D01*
X646645Y416362D01*
G01X634795Y411362D02*
X637220D01*
G01X646645Y426362D02*
X644220D01*
G01X646645Y421362D02*
X644220D01*
G01X673054Y425888D02*
X671479Y424313D01*
X659371D01*
X658220Y423162D01*
X654820D01*
X653920Y424062D01*
X641720D01*
X640720Y423062D01*
G01D02*
X639920Y423862D01*
X635719D01*
X634795Y422938D01*
Y421362D01*
G01Y416362D02*
X637220D01*
G01X634795Y426362D02*
X637220D01*
G01D02*
X639620Y428762D01*
X653220D01*
X653720Y428262D01*
X659450D01*
X660250Y427462D01*
X671479D01*
X673054Y429037D01*
G01X634798Y436650D02*
X644932D01*
X647420Y434162D01*
G01D02*
X646645Y433387D01*
Y431362D01*
G01X639545Y445195D02*
X639000Y445740D01*
Y449100D01*
X640400Y450500D01*
X659800D01*
X663940Y446360D01*
X671479D01*
X673054Y444785D01*
G01X634795Y447862D02*
Y446000D01*
X635600Y445195D01*
X639545D01*
G01X634795Y441862D02*
X639819D01*
X642519Y444562D01*
X650920D01*
X651620Y443862D01*
X654620D01*
X655820Y442662D01*
G01X638250Y439250D02*
X640149D01*
X642761Y441862D01*
X646645D01*
G01X634795Y431362D02*
X637220D01*
G01X640720Y452862D02*
X638390Y450532D01*
X635420D01*
X634795Y451157D01*
Y452862D01*
G01X646645Y447862D02*
X644220D01*
G01X673054Y447935D02*
X671527Y449462D01*
X667620D01*
X657510Y459572D01*
X652916D01*
X652126Y460362D01*
X640619D01*
X638119Y457862D01*
X637195D01*
G01X634795D02*
X637195D01*
G01X637220Y467862D02*
X634795D01*
G01X637220Y472862D02*
X634795D01*
G01Y462862D02*
X637220D01*
G01X640820Y467862D02*
Y469762D01*
X641320Y470262D01*
X645921D01*
X646645Y469538D01*
Y467862D01*
G01X637220Y477862D02*
X634795D01*
G01X639428Y480474D02*
X637240Y482662D01*
X634775D01*
G01X676203Y466832D02*
X674700Y468335D01*
Y476800D01*
X673620Y477880D01*
X666914D01*
X665457Y479337D01*
X652425D01*
X651600Y480162D01*
X639740D01*
X639428Y480474D01*
G01X654318Y504277D02*
Y506061D01*
X652207Y508172D01*
X642580D01*
G01D02*
Y510552D01*
X644337Y512309D01*
X646815D01*
G01X633220Y520299D02*
Y526287D01*
X633145Y526362D01*
G01X636941Y957546D02*
X641391D01*
G01X636941Y954200D02*
X641391D01*
G01Y994357D02*
X643145D01*
X644257Y995469D01*
Y1000325D01*
G01X641391Y1057940D02*
X648341D01*
X650014Y1059613D01*
X650797D01*
G01X658867D02*
X660433D01*
X661685Y1060865D01*
X663584D01*
X664034Y1060415D01*
Y1058900D01*
X664994Y1057940D01*
X671091D01*
G01X641391Y1255381D02*
X637891D01*
X636946Y1256326D01*
Y1258414D01*
G01X641391Y1258727D02*
X645605D01*
X647690Y1260812D01*
G01X637041Y1252034D02*
X641391D01*
G01Y1248688D02*
X641488Y1248785D01*
X645897D01*
G01X643725Y1646119D02*
Y1643467D01*
G01X635410Y1664220D02*
Y1643650D01*
X641130Y1637930D01*
X655440D01*
X666410Y1626960D01*
X682940D01*
X685680Y1629700D01*
X691062D01*
X691572Y1630210D01*
Y1632667D01*
G01X636702Y1677610D02*
X635640Y1676548D01*
Y1667390D01*
X639166Y1663864D01*
Y1643867D01*
X641935Y1641098D01*
X650914D01*
X651725Y1641909D01*
Y1643397D01*
G01X648225Y1658482D02*
Y1660754D01*
X646505Y1662474D01*
Y1665405D01*
G01X646800Y1653194D02*
X648225Y1654619D01*
Y1658482D01*
G01X647725Y1649269D02*
X646800Y1650194D01*
Y1653194D01*
G01X642725Y1658562D02*
Y1661294D01*
X643945Y1662514D01*
Y1665405D01*
G01X643650Y1653194D02*
Y1653268D01*
X642725Y1654193D01*
Y1658562D01*
G01X643725Y1649269D02*
X643650Y1649344D01*
Y1653194D01*
G01X637540Y1669480D02*
X653620D01*
X660850Y1662250D01*
X665990D01*
X668668Y1659572D01*
Y1659557D01*
G01X645725Y1691182D02*
Y1695269D01*
X645300Y1695694D01*
G01X646505Y1682983D02*
Y1686294D01*
X645725Y1687074D01*
Y1691182D01*
G01X646225Y1702619D02*
X645300Y1701694D01*
Y1695694D01*
G01X640725Y1691452D02*
Y1694269D01*
X642150Y1695694D01*
G01X643945Y1682983D02*
Y1687348D01*
X640725Y1690568D01*
Y1691452D01*
G01X642225Y1702619D02*
X642150Y1702544D01*
Y1695694D01*
G01X646225Y1702619D02*
X650225D01*
G01X642225Y1705769D02*
Y1708457D01*
G01X636160Y1710662D02*
X636360Y1710862D01*
X648383D01*
X648893Y1711372D01*
Y1713177D01*
X649403Y1713687D01*
X650893D01*
X651403Y1713177D01*
Y1711372D01*
X651913Y1710862D01*
X653403D01*
X653913Y1711372D01*
Y1713177D01*
X654423Y1713687D01*
X655913D01*
X656423Y1713177D01*
Y1711372D01*
X656933Y1710862D01*
X661154D01*
X661600Y1710416D01*
Y1706761D01*
X660608Y1705769D01*
X650225D01*
G01X645295Y1714362D02*
Y1718362D01*
G01X648220Y1716912D02*
X646770Y1718362D01*
X645295D01*
G01Y1726362D02*
Y1722362D01*
G01X648220Y1722921D02*
X645854D01*
X645295Y1722362D01*
G01X647508Y53544D02*
Y46383D01*
X647447Y46322D01*
G01X652232Y65158D02*
Y69118D01*
X651680Y69670D01*
Y73812D01*
G01X656957Y65158D02*
Y69205D01*
X656500Y69662D01*
G01X654595Y65158D02*
Y69667D01*
X654000Y70262D01*
Y75966D01*
X657165Y79131D01*
G01X659319Y65158D02*
Y68763D01*
X659318Y68764D01*
Y72386D01*
X656426Y75278D01*
Y75431D01*
G01X661681Y65158D02*
X661432Y65407D01*
Y69507D01*
X661587Y69662D01*
G01X664043Y65158D02*
Y68763D01*
X664042Y68764D01*
Y70840D01*
X662424Y74738D01*
X661600Y75562D01*
G01X648258Y79502D02*
X648440D01*
X650680Y81742D01*
Y90552D01*
X651915Y91787D01*
X655000D01*
G01X651680Y73812D02*
Y78843D01*
X653820Y80983D01*
Y84187D01*
G01X655000Y94937D02*
X659000D01*
G01X673987Y87662D02*
X674159Y87834D01*
Y92273D01*
X671495Y94937D01*
X659000D01*
G01X667610Y110337D02*
X667535Y110412D01*
X660941D01*
G01X652320Y123362D02*
X653420D01*
X655185Y121597D01*
Y120412D01*
G01X658490Y139140D02*
Y153384D01*
X660814Y155708D01*
X667551D01*
G01X649295Y166362D02*
Y171362D01*
G01X654370Y158572D02*
X663317Y167519D01*
X667551D01*
G01X654390Y152972D02*
X657530Y156112D01*
Y158768D01*
X664313Y165551D01*
X667551D01*
G01Y169488D02*
X659986D01*
X654470Y163972D01*
G01D02*
X652360Y161862D01*
X649295D01*
G01X667551Y171456D02*
X656415D01*
X654156Y169197D01*
G01D02*
X651991Y171362D01*
X649295D01*
G01X654310Y186192D02*
X650625D01*
X649295Y184862D01*
G01X667551Y173425D02*
X655337D01*
X654325Y174437D01*
G01X649870Y181942D02*
X651196Y183268D01*
X667551D01*
G01X651730Y177212D02*
X655817Y181299D01*
X667551D01*
G01Y185236D02*
X655266D01*
X654310Y186192D01*
G01X662560Y214152D02*
X663917Y212795D01*
X667551D01*
G01X742720Y380262D02*
X747100Y375882D01*
Y361300D01*
X744800Y359000D01*
X711800D01*
X710000Y357200D01*
X707300D01*
X704674Y354574D01*
Y339225D01*
X661440Y295991D01*
Y292762D01*
X659049Y290371D01*
X655820D01*
G01X649075Y392862D02*
Y389937D01*
G01X649575Y402362D02*
X652000D01*
G01X653100Y407862D02*
X652100Y406862D01*
X649575D01*
G01X669904Y416439D02*
X661397D01*
X655620Y410662D01*
G01D02*
X654920Y411362D01*
X649795D01*
G01Y426362D02*
X654920D01*
X655620Y425662D01*
G01D02*
X655846Y425888D01*
X669904D01*
G01X649795Y421362D02*
X654920D01*
X655620Y420662D01*
G01D02*
X656694Y419588D01*
X669904D01*
G01X673054D02*
X671428Y417962D01*
X657920D01*
X655620Y415662D01*
G01D02*
X654920Y416362D01*
X649795D01*
G01X669904Y432187D02*
X668379Y430662D01*
X655620D01*
G01D02*
X654920Y431362D01*
X649795D01*
G01X673054Y438486D02*
X671478Y440062D01*
X658420D01*
X655820Y442662D01*
G01X669904Y438486D02*
X656644D01*
X655820Y437662D01*
G01D02*
X651620Y441862D01*
X649795D01*
G01X669904Y444785D02*
X662396D01*
X659519Y447662D01*
X655820D01*
G01Y452662D02*
X649995D01*
X649795Y452862D01*
G01X655800Y461432D02*
X653630D01*
X652200Y462862D01*
X649795D01*
G01X655820Y447662D02*
X649995D01*
X649795Y447862D01*
G01X652195Y457862D02*
X656220D01*
X666147Y447935D01*
X669904D01*
G01X649795Y457862D02*
X652195D01*
G01X655820Y472662D02*
X650620Y477862D01*
X649795D01*
G01X655820Y472662D02*
X656548Y473390D01*
X667140D01*
X668968Y471562D01*
X671474D01*
X673054Y469982D01*
G01X655820Y467662D02*
Y468262D01*
X651220Y472862D01*
X649795D01*
G01X655820Y467662D02*
X656620Y468462D01*
X664770D01*
X664990Y468242D01*
X669544D01*
X669764Y468462D01*
X671424D01*
X673054Y466832D01*
G01X649795Y467862D02*
X650620D01*
X653818Y464664D01*
X655700D01*
G01X669904Y466832D02*
X669882Y466810D01*
X659968D01*
X657822Y464664D01*
X655700D01*
G01X669904Y476281D02*
X656340D01*
X655557Y477064D01*
G01X649795Y482862D02*
X650620D01*
X651620Y481862D01*
X655500D01*
G01X663000Y489500D02*
X655000D01*
X649795Y484295D01*
Y482862D01*
G01X655500Y481862D02*
X659062D01*
X661790Y484590D01*
X670558D01*
X674590Y480558D01*
Y478860D01*
X676203Y477247D01*
Y476281D01*
G01X650437Y491260D02*
X655100D01*
X659900Y496060D01*
Y503240D01*
X658863Y504277D01*
X656877D01*
G01X661865Y508479D02*
Y505334D01*
G01X656877Y504277D02*
Y502737D01*
X656290Y502150D01*
X654750D01*
X654318Y502582D01*
Y504277D01*
G01X663720Y523806D02*
X657532D01*
X654895Y521169D01*
G01X654318Y511757D02*
Y517442D01*
X654895Y518019D01*
G01D02*
X659036D01*
X659039Y518016D01*
G01D02*
X665105D01*
X665990Y517131D01*
G01D02*
Y515754D01*
X661865Y511629D01*
G01X654927Y525105D02*
X650845D01*
G01X650794Y521182D02*
X650845Y521233D01*
Y525105D01*
G01X661220Y526862D02*
X659942D01*
X659136Y526056D01*
X655878D01*
X654927Y525105D01*
G01X651759Y511757D02*
Y514074D01*
X650794Y515039D01*
G01D02*
Y518032D01*
G01X650599Y766798D02*
X654949D01*
G01Y1252034D02*
X662926D01*
X664620Y1253728D01*
X667834D01*
X667857Y1253705D01*
G01X674137D02*
X675027D01*
X676698Y1252034D01*
X684649D01*
G01X654949Y1255381D02*
X649182D01*
X647877Y1254076D01*
G01X654949Y1262074D02*
X659952D01*
X661400Y1263522D01*
G01X662000Y1416500D02*
X667000D01*
X670602Y1412898D01*
Y1412198D01*
G01X651725Y1646119D02*
Y1643397D01*
G01Y1649269D02*
X647725D01*
G01X650725Y1690682D02*
Y1695119D01*
X650225Y1695619D01*
G01X649064Y1682983D02*
Y1685926D01*
X650725Y1687587D01*
Y1690682D01*
G01X653420Y1698662D02*
X653313Y1698769D01*
X650225D01*
G01X651480Y1717803D02*
X650589Y1716912D01*
X648220D01*
G01X658960Y1717803D02*
X661401Y1715362D01*
X663720D01*
G01X651480Y1722921D02*
X648220D01*
G01X663720Y1726362D02*
X662401D01*
X658960Y1722921D01*
G01X680579Y53544D02*
Y52509D01*
X679410Y49692D01*
Y42422D01*
X677560Y40572D01*
G01X678217Y53544D02*
Y51300D01*
X677650Y50733D01*
Y45272D01*
X673190Y40812D01*
X672250D01*
G01X678217Y65158D02*
Y68763D01*
X677980Y69000D01*
Y73802D01*
X676890Y74892D01*
Y78302D01*
X674540Y80652D01*
G01X668768Y65158D02*
Y68763D01*
X668767Y68764D01*
Y70159D01*
X666054Y72872D01*
X664728Y76073D01*
Y87900D01*
X668020Y91192D01*
X671320D01*
G01X673492Y65158D02*
Y68763D01*
X673491Y68764D01*
Y71151D01*
X670840Y73802D01*
Y85892D01*
X670800Y85932D01*
G01X675854Y65158D02*
Y68763D01*
X675853Y68764D01*
Y72704D01*
X674035Y74522D01*
G01X671130Y65158D02*
Y68763D01*
X671129Y68764D01*
Y70655D01*
X667940Y73844D01*
Y80142D01*
G01X673720Y110362D02*
X667635D01*
X667610Y110337D01*
G01X676643Y111960D02*
X680623D01*
G01X680378Y123420D02*
X676280D01*
X675560Y122700D01*
Y117120D01*
G01X672520Y121560D02*
Y123640D01*
X674212Y125332D01*
X681616D01*
X683528Y123420D01*
G01X683500Y381200D02*
X682320D01*
X678050Y376930D01*
Y370290D01*
X678503Y369837D01*
X680600D01*
G01X672820Y396522D02*
X670055Y393757D01*
Y391602D01*
G01X673220Y388362D02*
Y391587D01*
X673205Y391602D01*
G01X673054Y413289D02*
X672820Y413055D01*
Y396522D01*
G01X676203Y425888D02*
X674628Y424313D01*
G01X673054Y422738D02*
X671479Y421163D01*
G01X676203Y429037D02*
X674628Y427462D01*
G01X679353Y416439D02*
X677778Y414864D01*
G01X679353Y425888D02*
X677778Y424313D01*
G01X673054Y416439D02*
X671479Y414864D01*
G01X676203Y422738D02*
X674628Y421163D01*
G01X676203Y419588D02*
X674628Y418013D01*
G01X679353Y419588D02*
X677778Y418013D01*
G01X679353Y422738D02*
X677778Y421163D01*
G01X669904Y422738D02*
X668329Y421163D01*
G01X679353Y429037D02*
X677778Y427462D01*
G01X667660Y429037D02*
X669904D01*
G01X679353Y432187D02*
X677778Y430612D01*
G01X676203Y438486D02*
X674628Y436911D01*
G01X673054Y435336D02*
X671479Y436911D01*
G01X679353Y435336D02*
X677778Y433761D01*
G01X669904Y435336D02*
X668329Y436911D01*
G01X679353Y441636D02*
X677778Y440061D01*
G01X676203Y441636D02*
X674628Y440061D01*
G01X679353Y438486D02*
X677778Y436911D01*
G01X679353Y444785D02*
X677778Y443210D01*
G01X665870Y433942D02*
X666080Y433732D01*
X674620D01*
X676203Y435315D01*
Y435336D01*
G01X669904Y441636D02*
X667677D01*
G01X673054D02*
X671479Y443211D01*
G01X679353Y447935D02*
X677778Y449510D01*
G01X669904Y451084D02*
X668329Y452659D01*
G01X676203Y451084D02*
X674628Y452659D01*
G01X673054Y451084D02*
X671479Y452659D01*
G01X679353Y451084D02*
X677778Y452659D01*
G01X669904Y454234D02*
X668329Y455809D01*
G01X673054Y457384D02*
X671479Y458959D01*
G01X676203Y457384D02*
X674628Y458959D01*
G01X669904Y457384D02*
X668329Y458959D01*
G01X679353Y457384D02*
X677778Y458959D01*
G01X679353Y454234D02*
X677778Y455809D01*
G01X676203Y454234D02*
X674628Y455809D01*
G01X668067Y462090D02*
X669624Y460533D01*
X669904D01*
G01X679353D02*
X677778Y462108D01*
G01X673054Y454234D02*
X671479Y455809D01*
G01X679353Y476281D02*
X677778Y477856D01*
G01X679353Y469982D02*
X677778Y471557D01*
G01X679353Y473132D02*
X677778Y474707D01*
G01X673054Y463683D02*
X671479Y465258D01*
G01X676203Y463683D02*
X674628Y465258D01*
G01X669904Y463683D02*
X668329Y465258D01*
G01X679353Y463683D02*
X677778Y465258D01*
G01X679353Y466832D02*
X677778Y468407D01*
G01X667350Y470680D02*
X668048Y469982D01*
X669904D01*
G01X673054Y473132D02*
X671479Y474707D01*
G01X676203Y479431D02*
Y480967D01*
X674628Y482542D01*
Y484006D01*
G01X676720Y493562D02*
X675220Y495062D01*
Y498287D01*
G01X679353Y479431D02*
Y480797D01*
X676720Y483430D01*
Y493562D01*
G01X682503Y479431D02*
Y480447D01*
X679120Y483830D01*
Y494362D01*
X677678Y495804D01*
Y520404D01*
X676220Y521862D01*
X675220D01*
G01X673054Y479431D02*
X671479Y481006D01*
G01X675220Y511287D02*
Y508862D01*
G01X670220Y501437D02*
Y503837D01*
G01Y498287D02*
X675220D01*
G01X670720Y521862D02*
Y524244D01*
X671263Y524787D01*
X675220D01*
G01X680220Y527937D02*
X675220D01*
G01X666641Y957546D02*
X671091D01*
G01X666641Y954200D02*
X671091D01*
G01Y994357D02*
Y997660D01*
X672063Y998632D01*
G01X671091Y1057940D02*
X677365D01*
X679038Y1059613D01*
X680747D01*
G01X688627D02*
X690833D01*
X693331Y1057115D01*
X696586D01*
X697411Y1057940D01*
X700791D01*
G01X666741Y1255381D02*
X671091D01*
G01Y1258727D02*
X665345D01*
X664630Y1259442D01*
G01X671091Y1252034D02*
X666741D01*
G01X671091Y1248688D02*
X675340D01*
X675537Y1248885D01*
G01X684649Y1262074D02*
X677980D01*
G01X670602Y1412198D02*
X671503Y1411297D01*
Y1406692D01*
X672970Y1405225D01*
Y1403363D01*
G01X678877Y1566798D02*
X674290Y1571385D01*
Y1596590D01*
X675000Y1597300D01*
X681470D01*
X681970Y1597800D01*
Y1623490D01*
X686070Y1627590D01*
X702350D01*
X705340Y1630580D01*
Y1638572D01*
X704830Y1639082D01*
X703040D01*
X702530Y1639592D01*
Y1641982D01*
X703040Y1642492D01*
X704830D01*
X705340Y1643002D01*
Y1645147D01*
X703719Y1646768D01*
G01X678619Y1579070D02*
X688551Y1589002D01*
X691717D01*
X697440Y1594725D01*
Y1604957D01*
X703505Y1611022D01*
G01X678621Y1571072D02*
X679510D01*
X699270Y1590832D01*
Y1602867D01*
X703505Y1607102D01*
G01X678771Y1585945D02*
X685886Y1593060D01*
X691750D01*
X695180Y1596490D01*
Y1617670D01*
X710150Y1632640D01*
X713280D01*
X716130Y1635490D01*
Y1644310D01*
X714150Y1646290D01*
Y1660330D01*
X716130Y1662310D01*
Y1670340D01*
X717600Y1671810D01*
X727620D01*
X735080Y1664350D01*
Y1662980D01*
G01X668593Y1647557D02*
Y1651557D01*
G01Y1647557D02*
X670053D01*
X671290Y1646320D01*
G01X673612Y1637403D02*
X675532D01*
X676172Y1636763D01*
Y1635463D01*
X675553Y1634844D01*
X673612D01*
G01X668647Y1637403D02*
Y1642667D01*
G01X673612Y1637403D02*
X668647D01*
G01X668695Y1664862D02*
Y1668862D01*
G01Y1664862D02*
Y1662235D01*
G01X668668Y1655557D02*
X673593D01*
G01X668668Y1659557D02*
Y1655557D01*
G01X673593D02*
X676303D01*
X677039Y1654821D01*
X679148D01*
G01X673420Y1650057D02*
X670093D01*
X668593Y1651557D01*
G01X679148Y1652262D02*
X676943Y1650057D01*
X673420D01*
G01X671610Y1673792D02*
X669625D01*
X668695Y1672862D01*
G01X674880Y1673421D02*
X674509Y1673792D01*
X671610D01*
G01X668695Y1676862D02*
Y1672862D01*
G01X674880Y1668303D02*
X671620D01*
G01D02*
X669254D01*
X668695Y1668862D01*
G01X668645Y1716362D02*
Y1712362D01*
G01D02*
Y1708362D01*
G01X672270Y1721612D02*
X671795Y1721137D01*
Y1716362D01*
G01X663720Y1715362D02*
X665989D01*
X666989Y1716362D01*
X668645D01*
G01X675120Y1716242D02*
Y1722262D01*
X673020Y1724362D01*
X671795D01*
G01X668645Y1728362D02*
Y1724362D01*
G01Y1732362D02*
Y1728362D01*
G01Y1724362D02*
X666645Y1726362D01*
X663720D01*
G01X685303Y53544D02*
Y45273D01*
X683440Y43410D01*
Y42832D01*
G01X682941Y53544D02*
Y51281D01*
X682290Y49709D01*
Y46822D01*
G01X690028Y53544D02*
Y42720D01*
X687120Y39812D01*
Y39632D01*
G01X687665Y53544D02*
Y51946D01*
X688080Y51531D01*
Y47676D01*
X687344Y46940D01*
G01X694752Y53544D02*
Y43096D01*
X692289Y40633D01*
G01X692389Y46439D02*
Y53543D01*
X692390Y53544D01*
G01X694752Y65158D02*
X694751Y65159D01*
Y70212D01*
G01X692390Y65158D02*
Y68763D01*
X692389Y68764D01*
Y72692D01*
G01X690028Y65158D02*
X690027Y65159D01*
Y70142D01*
G01X687665Y65158D02*
Y68763D01*
X687664Y68764D01*
Y73202D01*
G01X685303Y65158D02*
Y69545D01*
X685780Y70022D01*
G01X680578Y75992D02*
Y68764D01*
X680579Y68763D01*
Y65158D01*
G01X721504D02*
Y61551D01*
X720815Y60862D01*
X692240D01*
X690510Y59132D01*
G01X686210Y91492D02*
X686386Y91668D01*
X690878D01*
G01X680623Y111960D02*
X684643D01*
G01X690134D02*
X688606D01*
X688019Y111373D01*
Y109845D01*
G01D02*
X686758D01*
X684643Y111960D01*
G01X690134Y115896D02*
X687034D01*
G01D02*
X687006Y115868D01*
X683528D01*
G01X694453Y128093D02*
X697615Y124931D01*
Y123697D01*
G01X700185Y385010D02*
Y380295D01*
X697480Y377590D01*
X694820D01*
X693180Y375950D01*
Y370320D01*
X693663Y369837D01*
X695600D01*
G01X690600D02*
X688523D01*
X688160Y370200D01*
Y376670D01*
X690480Y378990D01*
X696010D01*
X697770Y380750D01*
Y387008D01*
X698690Y387928D01*
Y390522D01*
X697930Y391282D01*
G01X685600Y369837D02*
X683387D01*
X683100Y369550D01*
G01X685210Y388852D02*
X683200D01*
X682140Y389912D01*
Y393432D01*
G01X688802Y413289D02*
Y404602D01*
X685096Y400896D01*
X683326Y396618D01*
X682140Y395432D01*
Y393432D01*
G01X693300Y395362D02*
X692675Y394737D01*
X688470D01*
G01X691951Y413289D02*
X690490Y411828D01*
Y403392D01*
X693300Y400582D01*
Y395362D01*
G01X688470Y394737D02*
X690300Y392907D01*
Y382852D01*
X689795Y382347D01*
X688290D01*
G01X685220Y391652D02*
X685430D01*
X685495Y391587D01*
X688470D01*
G01X695101Y413289D02*
Y412261D01*
X697100Y410262D01*
X698000D01*
X699170Y409092D01*
Y393232D01*
X700185Y392217D01*
Y385010D01*
G01X697930Y391282D02*
X697550Y391662D01*
Y400730D01*
X695180Y403100D01*
Y405160D01*
X693500Y406840D01*
Y417987D01*
X695101Y419588D01*
G01X688802Y416439D02*
X687227Y414864D01*
G01X691951Y422738D02*
X690376Y421163D01*
G01X691951Y419588D02*
X690376Y418013D01*
G01X691951Y416439D02*
X690376Y414864D01*
G01X695101Y429037D02*
X693526Y427462D01*
G01X688802Y425888D02*
X687227Y424313D01*
G01X691951Y429037D02*
X690376Y427462D01*
G01X682503Y416439D02*
X680928Y414864D01*
G01X682503Y419588D02*
X680928Y418013D01*
G01X685652Y422738D02*
X684077Y421163D01*
G01X682503Y429037D02*
X680928Y427462D01*
G01X685652Y429037D02*
X684077Y427462D01*
G01X682503Y422738D02*
X680928Y421163D01*
G01X685652Y425888D02*
X684077Y424313D01*
G01X688802Y429037D02*
X687227Y427462D01*
G01X702705Y379398D02*
Y386855D01*
X701295Y388265D01*
Y392677D01*
X700280Y393692D01*
Y409528D01*
X700230Y409578D01*
Y409632D01*
X698500Y411362D01*
X697700D01*
X696600Y412462D01*
Y414940D01*
X695101Y416439D01*
G01Y422738D02*
X693526Y421163D01*
G01X695101Y425888D02*
X693526Y424313D01*
G01X691951Y425888D02*
X690376Y424313D01*
G01X682503Y438486D02*
X680928Y436911D01*
G01X682503Y435336D02*
X680928Y433761D01*
G01X695101Y432187D02*
X693526Y430612D01*
G01X685652Y432187D02*
X684077Y430612D01*
G01X685652Y441636D02*
X684077Y440061D01*
G01X688802Y438486D02*
X687227Y436911D01*
G01X688802Y444785D02*
X687227Y443210D01*
G01X685652Y444785D02*
X684077Y443210D01*
G01X685652Y438486D02*
X684077Y436911D01*
G01X682503Y441636D02*
X680928Y440061D01*
G01X682503Y444785D02*
X680928Y443210D01*
G01X685652Y435336D02*
X684077Y433761D01*
G01X688802Y432187D02*
X687227Y430612D01*
G01X691951Y432187D02*
X690376Y430612D01*
G01X688802Y435336D02*
X687227Y433761D01*
G01X682503Y432187D02*
X680928Y430612D01*
G01X688802Y460533D02*
X687227Y462108D01*
G01X682503Y454234D02*
X680928Y455809D01*
G01X695101Y460533D02*
X693526Y462108D01*
G01X682503Y447935D02*
X680928Y449510D01*
G01X688802Y447935D02*
X687227Y449510D01*
G01X691951Y460533D02*
X690376Y462108D01*
G01X685652Y447935D02*
X684077Y449510D01*
G01X682503Y451084D02*
X680928Y452659D01*
G01X685652Y451084D02*
X684077Y452659D01*
G01X688802Y454234D02*
X687227Y455809D01*
G01X685652Y454234D02*
X684077Y455809D01*
G01X682503Y457384D02*
X680928Y458959D01*
G01X682503Y460533D02*
X680928Y462108D01*
G01X688802Y457384D02*
X687227Y458959D01*
G01X685652Y457384D02*
X684077Y458959D01*
G01X685652Y466832D02*
X684077Y468407D01*
G01X688802Y469982D02*
X687227Y471557D01*
G01X688802Y473132D02*
X687227Y474707D01*
G01X688802Y476281D02*
X687227Y477856D01*
G01X685652Y469982D02*
X684077Y471557D01*
G01X691951Y463683D02*
X690376Y465258D01*
G01X685652Y463683D02*
X684077Y465258D01*
G01X682503Y469982D02*
X680928Y471557D01*
G01X682503Y473132D02*
X680928Y474707D01*
G01X682503Y476281D02*
X680928Y477856D01*
G01X695101Y463683D02*
X693526Y465258D01*
G01X695101Y469982D02*
X693526Y471557D01*
G01X691951Y466832D02*
X690376Y468407D01*
G01X691951Y476281D02*
X690376Y477856D01*
G01X691951Y469982D02*
X690376Y471557D01*
G01X688802Y463683D02*
X687227Y465258D01*
G01X691951Y473132D02*
X690376Y474707D01*
G01X688802Y466832D02*
X687227Y468407D01*
G01X695101Y466832D02*
X693526Y468407D01*
G01X695101Y473132D02*
X693526Y474707D01*
G01X695101Y476281D02*
X693526Y477856D01*
G01X690220Y506362D02*
X688720D01*
X687697Y505339D01*
Y483484D01*
X688802Y482379D01*
Y479431D01*
G01X714320Y597462D02*
X702512D01*
X682736Y577686D01*
Y538626D01*
X687500Y533862D01*
Y522362D01*
X682736Y517598D01*
Y495478D01*
X680820Y493562D01*
Y484263D01*
X685652Y479431D01*
G01X690220Y519662D02*
X691420D01*
X692611Y518471D01*
Y480091D01*
X691951Y479431D01*
G01X695101D02*
Y480477D01*
X696606Y481982D01*
Y494553D01*
X697270Y495217D01*
Y497913D01*
X695257Y499926D01*
G01X695220Y511287D02*
Y508862D01*
G01X680220Y498287D02*
Y495887D01*
G01X685220Y511287D02*
Y508862D01*
G01Y501437D02*
Y503837D01*
G01Y498287D02*
Y495887D01*
G01X690220Y511287D02*
Y508882D01*
G01X680220Y511287D02*
Y508862D01*
G01X695257Y499926D02*
Y503847D01*
G01X695220Y514437D02*
Y516852D01*
G01Y519662D02*
X699220Y515662D01*
Y495362D01*
X698020Y494162D01*
Y479662D01*
X698251Y479431D01*
G01X699174Y519473D02*
X695220Y523427D01*
Y524787D01*
G01X680220Y530362D02*
Y527937D01*
G01X695220D02*
Y530662D01*
G01X684649Y766798D02*
X680299D01*
G01X684649Y1252034D02*
X689447D01*
X691123Y1250358D01*
X696687D01*
G01X704147D02*
X708141D01*
X709817Y1252034D01*
X714349D01*
G01X692233Y1252480D02*
Y1253640D01*
X691217Y1254656D01*
X688626D01*
X687901Y1255381D01*
X684649D01*
G01X694100Y1261562D02*
X696935Y1258727D01*
X700791D01*
G01X691572Y1632667D02*
Y1636667D01*
G01X691593Y1653972D02*
X694807Y1650758D01*
Y1648843D01*
G01X686220Y1640667D02*
X691647D01*
G01Y1644667D02*
Y1640667D01*
G01X681092Y1639962D02*
X681797Y1640667D01*
X686220D01*
G01X686647Y1636667D02*
X691572D01*
G01X681092Y1637403D02*
X683201D01*
X683937Y1636667D01*
X686647D01*
G01X686628Y1654821D02*
X685278D01*
X684658Y1655441D01*
Y1656851D01*
X685187Y1657380D01*
X686628D01*
G01Y1654821D02*
X690744D01*
X691593Y1653972D01*
G01X692045Y1662862D02*
Y1666862D01*
G01Y1658862D02*
Y1662862D01*
G01X687120Y1676862D02*
X685801D01*
X682360Y1673421D01*
G01X692045Y1674862D02*
X690045Y1676862D01*
X687120D01*
G01X692045Y1678862D02*
Y1682862D01*
G01Y1674862D02*
Y1678862D01*
G01X695195Y1666862D02*
X697595D01*
G01X687120Y1665862D02*
X684801D01*
X682360Y1668303D01*
G01X692045Y1666862D02*
X690389D01*
X689389Y1665862D01*
X687120D01*
G01X699476Y53544D02*
Y44548D01*
X697036Y42108D01*
X696800D01*
G01X697114Y53544D02*
Y48216D01*
X696838Y47940D01*
G01X704201Y53544D02*
Y44565D01*
X701838Y42202D01*
G01Y47940D02*
X701839Y47941D01*
Y53544D01*
G01X697114Y65158D02*
Y68763D01*
X696700Y69177D01*
Y72462D01*
G01X704201Y65158D02*
Y68763D01*
X704200Y68764D01*
Y70056D01*
X703900Y70356D01*
Y72112D01*
G01X701400D02*
Y70356D01*
X701838Y69918D01*
Y68764D01*
X701839Y68763D01*
Y65158D01*
G01X699476D02*
X699475Y65159D01*
Y69982D01*
G01X700500Y74862D02*
X701925Y76287D01*
X704000D01*
G01X708953Y128093D02*
Y127515D01*
X709713Y126755D01*
Y123153D01*
X707457Y120897D01*
Y119341D01*
G01X700600Y125309D02*
X699583Y124292D01*
Y119440D01*
G01X697615Y123697D02*
Y119440D01*
G01X707008Y125804D02*
X705941Y124737D01*
X702786D01*
X701551Y123502D01*
Y119440D01*
G01X708953Y131243D02*
X709320Y131610D01*
Y141462D01*
X719170Y151312D01*
X753500D01*
G01X712340Y128093D02*
X708953D01*
G01X700963Y128153D02*
X700600Y127790D01*
Y125309D01*
G01X704953Y128093D02*
X706129D01*
X707008Y127214D01*
Y125804D01*
G01X710450Y152512D02*
X708238Y154724D01*
X697276D01*
G01X710145Y161862D02*
Y157362D01*
G01D02*
Y155906D01*
X710450Y155601D01*
Y152512D01*
G01X718053Y165297D02*
X709471D01*
X700867Y156693D01*
X697276D01*
G01X710145Y221862D02*
X709936Y221653D01*
X697276D01*
G01X732720Y231362D02*
X731920Y230562D01*
X712520D01*
X710145Y228187D01*
Y221862D01*
G01X705600Y369837D02*
X708300Y367137D01*
Y363200D01*
X706500Y361400D01*
X705700D01*
G01X698251Y413289D02*
X698681D01*
X701650Y410320D01*
Y395540D01*
X703690Y393500D01*
Y388510D01*
X704960Y387240D01*
Y377670D01*
X703090Y375800D01*
Y360310D01*
X704000Y359400D01*
X709200D01*
X710700Y360900D01*
X743200D01*
X744300Y362000D01*
Y375400D01*
X740100Y379600D01*
Y381930D01*
X741430Y383260D01*
X744030D01*
X751000Y376290D01*
Y356090D01*
X741670Y346760D01*
Y295710D01*
X745330Y292050D01*
X755140D01*
X758390Y295300D01*
Y295450D01*
G01X708720Y380787D02*
Y378880D01*
X709400Y378200D01*
G01X710600Y369837D02*
X712700Y371937D01*
Y374561D01*
X710951Y376310D01*
X707376D01*
X706410Y377276D01*
Y388910D01*
X708400Y390900D01*
Y392000D01*
G01X702705Y379398D02*
X701302Y377995D01*
X700345D01*
X697800Y375450D01*
Y370570D01*
X698533Y369837D01*
X700600D01*
G01X711200Y396500D02*
X713220Y394480D01*
Y393937D01*
G01Y383937D02*
X708720D01*
G01X708400Y392000D02*
X707400Y393000D01*
Y396200D01*
G01X710849Y425888D02*
X712424Y424313D01*
G01X698251Y429037D02*
X696676Y427462D01*
G01X701400Y429037D02*
X699825Y427462D01*
G01X698251Y416439D02*
X699826Y414864D01*
G01X698251Y422738D02*
X696676Y421163D01*
G01X698251Y425888D02*
X696676Y424313D01*
G01X698251Y419588D02*
X696676Y418013D01*
G01X701400Y425888D02*
X699825Y424313D01*
G01X710849Y432187D02*
X712424Y430612D01*
G01X698251Y432187D02*
X696676Y430612D01*
G01X701400Y432187D02*
X699825Y430612D01*
G01X704550Y460533D02*
X706125Y462108D01*
G01X707699Y460533D02*
X709274Y462108D01*
G01X710849Y460533D02*
X712424Y462108D01*
G01X698251Y460533D02*
X696676Y462108D01*
G01X701400Y460533D02*
X699825Y462108D01*
G01X707699Y473132D02*
X709274Y474707D01*
G01X707699Y469982D02*
X709274Y471557D01*
G01X707699Y463683D02*
X709274Y465258D01*
G01X707699Y466832D02*
X709274Y468407D01*
G01X710849Y473132D02*
X712424Y474707D01*
G01X710849Y476281D02*
X712420Y477852D01*
Y480762D01*
X711920Y481262D01*
Y490459D01*
X714931Y493470D01*
X717187D01*
G01X710849Y466832D02*
X712424Y468407D01*
G01X710849Y463683D02*
X712424Y465258D01*
G01X705220Y511287D02*
X703944D01*
X702520Y509863D01*
Y493062D01*
X701120Y491662D01*
Y489162D01*
X703020Y487262D01*
Y474662D01*
X704550Y473132D01*
G01Y469982D02*
X706125Y471557D01*
G01X698251Y463683D02*
X696676Y465258D01*
G01X698251Y473132D02*
X696676Y474707D01*
G01X698251Y466832D02*
X696676Y468407D01*
G01X701400Y469982D02*
X699825Y471557D01*
G01X701400Y473132D02*
X699825Y474707D01*
G01X701400Y476281D02*
Y476882D01*
X699820Y478462D01*
Y480362D01*
X700820Y481362D01*
Y486562D01*
X699320Y488062D01*
Y492562D01*
X700820Y494062D01*
Y517827D01*
X699174Y519473D01*
G01X704550Y476281D02*
X706125Y477856D01*
G01X698251Y469982D02*
X696676Y471557D01*
G01X701400Y463683D02*
X699825Y465258D01*
G01X710849Y469982D02*
X712424Y471557D01*
G01X711220Y498287D02*
X711187Y498254D01*
Y493470D01*
G01D02*
X710220Y492503D01*
Y480060D01*
X710849Y479431D01*
G01X705220Y498287D02*
Y493362D01*
G01D02*
X708520Y490062D01*
Y480252D01*
X707699Y479431D01*
G01X704550D02*
X706125Y481006D01*
G01X710720Y521362D02*
X714120Y517962D01*
Y501187D01*
X711220Y498287D01*
G01X705220Y521362D02*
X708220Y518362D01*
Y499682D01*
X706825Y498287D01*
X705220D01*
G01Y508862D02*
Y511287D01*
G01X711220D02*
Y508882D01*
G01X705220Y524787D02*
X701757Y521324D01*
G01X705220Y527937D02*
Y530362D01*
G01X960820Y665062D02*
X959120Y666762D01*
X807220D01*
X800611Y660153D01*
X723911D01*
X712120Y648362D01*
Y641532D01*
X709400Y638812D01*
X708680D01*
G01X700500Y745862D02*
Y747662D01*
X701005Y748167D01*
X705614D01*
X716709Y737072D01*
X763209D01*
X766261Y734020D01*
X797459D01*
X803810Y740371D01*
X823590D01*
X835591Y752372D01*
X848491D01*
X851891Y755772D01*
X857511D01*
X874390Y772651D01*
Y846171D01*
X887897Y859678D01*
Y867779D01*
G01X703545Y745907D02*
X705455D01*
X716000Y735362D01*
X762500D01*
X765552Y732310D01*
X798648D01*
X804999Y738661D01*
X824299D01*
X836300Y750662D01*
X849200D01*
X852600Y754062D01*
X858220D01*
X876100Y771942D01*
Y845462D01*
X891747Y861109D01*
Y867779D01*
G01X714349Y766798D02*
X709899D01*
G01X700791Y957546D02*
X696441D01*
G01X700791Y954200D02*
X696441D01*
G01Y994357D02*
X700791D01*
G01Y1057940D02*
X704391D01*
X705336Y1056995D01*
X706767D01*
X709385Y1059613D01*
X710697D01*
G01X718047D02*
X719449D01*
X720549Y1060713D01*
X722731D01*
X723436Y1060008D01*
Y1058444D01*
X723940Y1057940D01*
X726141D01*
G01X696441Y1255381D02*
X700791D01*
G01Y1252034D02*
X705037D01*
G01X696441Y1248688D02*
X700791D01*
G01X706493Y1256563D02*
X707675Y1255381D01*
X714349D01*
G01Y1262074D02*
X708090D01*
G01X708745Y1412198D02*
X709646Y1411297D01*
Y1406540D01*
X711113Y1405073D01*
Y1403363D01*
G01X707647Y1601963D02*
X712446D01*
X713102Y1601307D01*
G01X706103Y1617107D02*
Y1612560D01*
X706655Y1612008D01*
Y1611022D01*
G01X708857Y1613462D02*
X709186Y1613133D01*
Y1607602D01*
X708686Y1607102D01*
X706655D01*
G01X715780Y1620505D02*
X711780D01*
G01X708999Y1651562D02*
Y1646762D01*
G01X706439Y1651562D02*
Y1649488D01*
X703719Y1646768D01*
G01X709678Y1658485D02*
X708999Y1659164D01*
Y1669140D01*
G01X711558D02*
Y1675700D01*
G01D02*
Y1680400D01*
G01X704759Y1677001D02*
Y1674863D01*
X706439Y1673183D01*
Y1669140D01*
G01X728591Y53544D02*
Y49937D01*
X728590Y49936D01*
Y47472D01*
X724620Y43502D01*
Y40062D01*
G01X726228Y53544D02*
Y49937D01*
X726227Y49936D01*
Y49349D01*
X722740Y45862D01*
X719820D01*
G01X721504Y53544D02*
Y53543D01*
X721503Y53542D01*
Y51745D01*
X716720Y46962D01*
Y44662D01*
X717320Y44062D01*
G01X726228Y65158D02*
X726227Y65159D01*
Y69093D01*
X725740Y69580D01*
G01X723866Y65158D02*
Y65157D01*
X723865Y65156D01*
Y62397D01*
X725700Y60562D01*
X727700D01*
G01X718213Y159241D02*
X715592Y161862D01*
X713295D01*
G01X723558Y160788D02*
X720633D01*
G01X726708D02*
X729810D01*
G01X715600Y369837D02*
X717714D01*
X718214Y369337D01*
Y364400D01*
X717714Y363900D01*
X715600D01*
G01X722500Y368150D02*
Y365500D01*
G01X727000Y368150D02*
Y365500D01*
G01X722500Y371300D02*
Y374100D01*
G01X727000Y371300D02*
Y374100D01*
G01X718720Y381892D02*
X715720Y384892D01*
Y395961D01*
X717645Y397886D01*
Y410636D01*
X720298Y413289D01*
G01X728220Y390787D02*
Y388362D01*
G01X726597Y413289D02*
Y411985D01*
X727200Y411382D01*
Y394957D01*
X728220Y393937D01*
G01D02*
X726796D01*
X723350Y390491D01*
Y388952D01*
G01D02*
Y387231D01*
X726644Y383937D01*
X728220D01*
G01X721873Y424313D02*
Y412014D01*
X720120Y410261D01*
Y395837D01*
X718220Y393937D01*
G01X713220Y390787D02*
Y388362D01*
G01D02*
Y383937D01*
G01X729460Y399052D02*
Y411122D01*
X728220Y412362D01*
Y414816D01*
X726597Y416439D01*
G01X720298Y429037D02*
X721873Y427462D01*
G01X723447Y429037D02*
X725022Y427462D01*
G01X726597Y419588D02*
X728172Y418013D01*
G01X717148Y419588D02*
X718723Y418013D01*
G01X713999Y429037D02*
X715574Y427462D01*
G01X726597Y422738D02*
X728172Y421163D01*
G01X717148Y416439D02*
X718723Y414864D01*
G01X723447Y425888D02*
X725022Y424313D01*
G01X720298Y425888D02*
X721873Y424313D01*
G01X723447Y422738D02*
X725022Y421163D01*
G01X726597Y429037D02*
X728172Y427462D01*
G01X717148Y429037D02*
X718723Y427462D01*
G01X717148Y425888D02*
X718723Y424313D01*
G01X717148Y422738D02*
X718723Y421163D01*
G01X713999Y425888D02*
X715574Y424313D01*
G01X713999Y422738D02*
X715574Y421163D01*
G01X713999Y419588D02*
X715574Y418013D01*
G01X726597Y425888D02*
X728172Y424313D01*
G01X717148Y438486D02*
X718723Y436911D01*
G01X720298Y435336D02*
X721873Y433761D01*
G01X720298Y438486D02*
X721873Y436911D01*
G01X720298Y441636D02*
X721873Y440061D01*
G01X720298Y432187D02*
X721873Y430612D01*
G01X717148Y435336D02*
X718723Y433761D01*
G01X717148Y441636D02*
X718723Y440061D01*
G01X723447Y438486D02*
X725022Y436911D01*
G01X723447Y435336D02*
X725022Y433761D01*
G01X726597Y435336D02*
X728172Y433761D01*
G01X717148Y432187D02*
X718723Y430612D01*
G01X713999Y432187D02*
X715574Y430612D01*
G01X723447Y432187D02*
X725022Y430612D01*
G01X723447Y441636D02*
X725022Y440061D01*
G01X717148Y444785D02*
X718723Y443210D01*
G01X720298Y444785D02*
X721873Y443210D01*
G01X723447Y444785D02*
X725022Y443210D01*
G01X726597Y441636D02*
X728172Y440061D01*
G01X726597Y454234D02*
X728172Y455809D01*
G01X726597Y457384D02*
X728172Y458959D01*
G01X717148Y454234D02*
X718723Y455809D01*
G01X720298Y457384D02*
X721873Y458959D01*
G01X720298Y451084D02*
X721873Y452659D01*
G01X723447Y451084D02*
X725022Y452659D01*
G01X726597Y451084D02*
X728172Y452659D01*
G01X713999Y460533D02*
X715574Y462108D01*
G01X723447Y457384D02*
X725022Y458959D01*
G01X720298Y454234D02*
X721873Y455809D01*
G01X723447Y460533D02*
X725022Y462108D01*
G01X717148Y451084D02*
X718723Y452659D01*
G01X717148Y447935D02*
X718723Y449510D01*
G01X720298Y447935D02*
X721873Y449510D01*
G01X723447Y447935D02*
X725022Y449510D01*
G01X717148Y457384D02*
X718723Y458959D01*
G01X720298Y460533D02*
X721873Y462108D01*
G01X717148Y460533D02*
X718723Y462108D01*
G01X723447Y466832D02*
X725022Y468407D01*
G01X713999Y476281D02*
X715530Y477812D01*
Y481113D01*
X727187Y492770D01*
Y493470D01*
G01X720298Y463683D02*
X721873Y465258D01*
G01X720298Y476281D02*
X721873Y477856D01*
G01X717148Y466832D02*
X718723Y468407D01*
G01X713999Y473132D02*
X715574Y474707D01*
G01X713999Y469982D02*
X715574Y471557D01*
G01X713999Y466832D02*
X715574Y468407D01*
G01X713999Y463683D02*
X715574Y465258D01*
G01X717148Y473132D02*
X718723Y474707D01*
G01X717148Y469982D02*
X718723Y471557D01*
G01X726597Y476281D02*
X728172Y477856D01*
G01X720298Y469982D02*
X721873Y471557D01*
G01X723447Y469982D02*
X725022Y471557D01*
G01X717148Y463683D02*
X718723Y465258D01*
G01X726597Y463683D02*
X728172Y465258D01*
G01X726597Y466832D02*
X728172Y468407D01*
G01X720298Y473132D02*
X721873Y474707D01*
G01X720298Y466832D02*
X721873Y468407D01*
G01X726597Y473132D02*
X728172Y474707D01*
G01X726597Y469982D02*
X728172Y471557D01*
G01X723447Y463683D02*
X725022Y465258D01*
G01X717148Y476281D02*
X718723Y477856D01*
G01X723220Y498287D02*
Y494503D01*
X722187Y493470D01*
G01D02*
X720220Y491503D01*
Y488533D01*
X713999Y482312D01*
Y479431D01*
G01X727187Y493470D02*
X729220Y495503D01*
Y498287D01*
G01X717187Y493470D02*
Y495726D01*
X717220Y495759D01*
Y498287D01*
G01X737600Y500178D02*
X734833Y497411D01*
Y491116D01*
X728079Y484362D01*
X725229D01*
X720298Y479431D01*
G01X723447D02*
X725132Y481116D01*
G01X732187Y493470D02*
X725079Y486362D01*
X724079D01*
X717148Y479431D01*
G01X728272Y481006D02*
X728172D01*
X726597Y479431D01*
G01X723220Y511287D02*
Y508882D01*
G01X717220Y511287D02*
Y508882D01*
G01X723120Y525362D02*
X726040Y522442D01*
Y499162D01*
X725165Y498287D01*
X723220D01*
G01X717220Y521362D02*
X720030Y518552D01*
Y499342D01*
X718975Y498287D01*
X717220D01*
G01X729220D02*
X732240Y501307D01*
Y517342D01*
X728220Y521362D01*
G01X740840Y521982D02*
Y533653D01*
X731008Y543485D01*
Y578772D01*
X726891Y582889D01*
Y596021D01*
X726110Y596802D01*
X723720D01*
X723450Y597072D01*
G01X736480Y531722D02*
Y533177D01*
X728786Y540871D01*
Y578510D01*
X724884Y582412D01*
Y592018D01*
X720240Y596662D01*
Y598292D01*
G01X960920Y644762D02*
Y633436D01*
X942646Y615162D01*
X817394D01*
X790714Y641842D01*
X756380D01*
X746960Y651262D01*
X734850D01*
X729950Y646362D01*
X724020D01*
X716820Y639162D01*
X715420D01*
G01X960920Y649762D02*
Y649662D01*
X958320Y647062D01*
Y634513D01*
X941569Y617762D01*
X818471D01*
X791791Y644442D01*
X757457D01*
X748037Y653862D01*
X735190D01*
X729340Y648012D01*
X723450D01*
X718700Y643262D01*
X717720D01*
G01X960920Y654762D02*
Y653762D01*
X956320Y649162D01*
Y635342D01*
X940740Y619762D01*
X819300D01*
X792620Y646442D01*
X758286D01*
X748866Y655862D01*
X734540D01*
X728550Y649872D01*
X717120D01*
X715220Y647972D01*
Y643262D01*
G01X963720Y647262D02*
Y632276D01*
X943806Y612362D01*
X816234D01*
X789554Y639042D01*
X755220D01*
X745800Y648462D01*
X734880D01*
X729680Y643262D01*
X723680D01*
X723340Y642922D01*
G01X726041Y957546D02*
X730491D01*
G01X726041Y954200D02*
X730491D01*
G01X726041Y994357D02*
X730491D01*
G01X726141Y1057940D02*
X730491D01*
G01X714349Y1252034D02*
X721298D01*
X722974Y1250358D01*
X727257D01*
G01X733747D02*
X735599D01*
X737275Y1252034D01*
X744049D01*
G01X726141Y1255381D02*
X730491D01*
G01X726141Y1248688D02*
X730491D01*
G01X723700Y1258727D02*
X730491D01*
G01X724712Y1566820D02*
Y1569882D01*
G01X723942Y1574123D02*
X722827Y1573008D01*
Y1569493D01*
G01X713102Y1601307D02*
Y1599015D01*
X716604Y1595513D01*
X720132D01*
X721315Y1594330D01*
G01X715775Y1599024D02*
X717576Y1597223D01*
X720862D01*
X723087Y1594998D01*
Y1594330D01*
G01X726630D02*
Y1597945D01*
X726092Y1598483D01*
G01X719612Y1602608D02*
X721967D01*
X726092Y1598483D01*
G01X724858Y1594330D02*
Y1595697D01*
X720987Y1599568D01*
G01X719168Y1612016D02*
X717700Y1613484D01*
Y1620050D01*
X718145Y1620495D01*
X719770D01*
G01X723820Y1617345D02*
X723915D01*
X728090Y1621520D01*
Y1630240D01*
X731960Y1634110D01*
G01X719770Y1620495D02*
X723820D01*
G01X726010Y1627615D02*
Y1622685D01*
X723820Y1620495D01*
G01X718530Y1627615D02*
Y1625590D01*
X715780Y1622840D01*
Y1620505D01*
G01X731040Y1652930D02*
Y1650300D01*
X730310Y1649570D01*
X725300D01*
X724080Y1648350D01*
Y1641660D01*
X722010Y1639590D01*
Y1634510D01*
X718530Y1631030D01*
Y1627615D01*
G01X726720Y1647515D02*
X730680D01*
G01X726010Y1638245D02*
Y1643655D01*
X726720Y1644365D01*
G01X731960Y1634110D02*
X727810D01*
X726010Y1635910D01*
Y1638245D01*
G01X726810Y1652430D02*
X725710D01*
X723175Y1649895D01*
X722630D01*
G01X718830Y1653045D02*
X722630D01*
G01D02*
Y1655740D01*
G01X719350Y1659065D02*
Y1661580D01*
X720410Y1662640D01*
X729900D01*
X731040Y1661500D01*
Y1652930D01*
G01X714708Y1680400D02*
X718758D01*
G01D02*
Y1676500D01*
G01D02*
Y1673800D01*
G01X742764Y53544D02*
Y49937D01*
X742763Y49936D01*
Y47819D01*
X744320Y46262D01*
X746100D01*
G01X740402Y53544D02*
Y49937D01*
X740401Y49936D01*
Y46881D01*
X745900Y41382D01*
Y40362D01*
G01X733315Y53544D02*
Y49937D01*
X733314Y49936D01*
Y40862D01*
G01X730953Y53544D02*
Y49937D01*
X730952Y49936D01*
Y45794D01*
X728720Y43562D01*
G01X738039Y53544D02*
Y49937D01*
X738038Y49936D01*
Y46644D01*
X740100Y44582D01*
Y41162D01*
G01X735677Y53544D02*
Y49937D01*
X735676Y49936D01*
Y46206D01*
X736620Y45262D01*
G01X740402Y65158D02*
Y68763D01*
X740401Y68764D01*
Y69743D01*
X742120Y71462D01*
X742320D01*
X742620Y71762D01*
G01X742764Y65158D02*
Y65157D01*
X742763Y65156D01*
Y62405D01*
X741240Y60882D01*
X736100D01*
X735880Y60662D01*
G01X728591Y65158D02*
Y71960D01*
G01X737093Y87902D02*
X733972D01*
X733068Y86998D01*
G01X741097Y101942D02*
X741071Y101968D01*
X737026D01*
X736720Y101662D01*
G01D02*
X736414Y101968D01*
X733578D01*
G01X745035Y94632D02*
Y91691D01*
X741246Y87902D01*
X737093D01*
G01X741097Y98005D02*
X738080Y94988D01*
X735770D01*
G01D02*
X733268D01*
X733098Y95158D01*
G01X733068Y90998D02*
X737039D01*
X737093Y91052D01*
G01D02*
X739823D01*
G01D02*
X743066Y94295D01*
Y98005D01*
G01X729933Y108388D02*
X732577D01*
X733578Y107387D01*
Y105468D01*
G01D02*
X739540D01*
X741097Y103911D01*
G01X741308Y111252D02*
Y115546D01*
X741270Y115584D01*
G01X741308Y111252D02*
Y108742D01*
G01D02*
Y108384D01*
X743066Y106626D01*
Y103911D01*
G01X736060Y145532D02*
X743728Y137864D01*
X745670D01*
G01X729810Y160788D02*
X763046D01*
X764342Y162084D01*
G01X735600Y351400D02*
Y339900D01*
X734500Y338800D01*
Y249810D01*
X735010Y249300D01*
X749400D01*
X749900Y249800D01*
Y255000D01*
X743100Y261800D01*
Y283300D01*
X748400Y288600D01*
X796800D01*
X800600Y284800D01*
Y277700D01*
X794300Y271400D01*
X785200D01*
G01X819684Y267139D02*
X812161D01*
X811000Y268300D01*
Y269000D01*
X807000Y273000D01*
X803800D01*
X803300Y273500D01*
Y284200D01*
X797000Y290500D01*
X744100D01*
X739500Y285900D01*
Y261200D01*
X747200Y253500D01*
Y251500D01*
G01X741800Y363200D02*
Y364900D01*
X740200Y366500D01*
Y368150D01*
G01Y371300D02*
Y375100D01*
G01X735800Y368150D02*
Y365500D01*
G01Y371300D02*
Y375000D01*
G01X731400Y368150D02*
Y365500D01*
G01Y371300D02*
Y375000D01*
G01X738220Y390787D02*
Y388362D01*
G01X738186Y398695D02*
X738220Y398661D01*
Y393937D01*
G01X733220Y380787D02*
X736220D01*
G01X733220Y383937D02*
X731644D01*
X730720Y384861D01*
Y392863D01*
X731794Y393937D01*
X733220D01*
G01D02*
X729460Y397697D01*
Y399052D01*
G01X738220Y383862D02*
X735720Y386362D01*
Y394962D01*
X731720Y398962D01*
Y411316D01*
X729747Y413289D01*
G01X732896D02*
X733480Y412705D01*
Y403401D01*
X738186Y398695D01*
G01X732896Y416439D02*
X734473Y414862D01*
X745820D01*
X750020Y410662D01*
G01X732896Y419588D02*
X734471Y418013D01*
G01X750020Y420712D02*
X737170D01*
X736046Y419588D01*
G01X729747Y429037D02*
X731322Y427462D01*
G01X736046Y416439D02*
X749393D01*
X750120Y415712D01*
G01X729747Y419588D02*
X731322Y418013D01*
G01X787720Y408362D02*
X785030Y405672D01*
X755800D01*
X754995Y406477D01*
Y419197D01*
X751070Y423122D01*
X746328D01*
X745944Y422738D01*
X736046D01*
G01X732896D02*
X734471Y421163D01*
G01X729747Y425888D02*
X731322Y424313D01*
G01X732896Y425888D02*
X734471Y424313D01*
G01X736046Y425888D02*
X737621Y424313D01*
G01X750010Y425712D02*
X738990D01*
X737340Y427362D01*
X734571D01*
X732896Y429037D01*
G01X768701Y418662D02*
Y417833D01*
X766680Y415812D01*
X759750D01*
X758840Y416722D01*
Y420072D01*
X750700Y428212D01*
X738530D01*
X737705Y429037D01*
X736046D01*
G01X729747Y422738D02*
X731322Y421163D01*
G01X729747Y416439D02*
X731322Y414864D01*
G01X732896Y441636D02*
X734470Y440062D01*
X737300D01*
X740720Y443482D01*
X743980D01*
G01X758220Y444937D02*
X757796Y444513D01*
X756516D01*
X755485Y443482D01*
X743980D01*
G01X750020Y435792D02*
X740520D01*
X738490Y433762D01*
X734470D01*
X732896Y435336D01*
G01X850610Y444352D02*
Y444590D01*
X843800Y451400D01*
X843000D01*
X840000Y454400D01*
X827500D01*
X825700Y456200D01*
X816800D01*
X814100Y453500D01*
Y443401D01*
X808571Y437872D01*
X782560D01*
X781080Y436392D01*
X778940D01*
X776890Y434342D01*
X772084D01*
X770789Y435637D01*
X759354D01*
X754569Y440422D01*
X740220D01*
X738284Y438486D01*
X736046D01*
G01X750080Y430712D02*
X734371D01*
X732896Y432187D01*
G01X729747Y435336D02*
X731322Y433761D01*
G01X803120Y428762D02*
Y430775D01*
X800385Y433510D01*
X792364D01*
X792351Y433497D01*
X790813D01*
X790800Y433510D01*
X788882D01*
X786930Y435462D01*
X783550D01*
X782120Y434032D01*
X780010D01*
X778010Y432032D01*
X771126D01*
X769831Y433327D01*
X758314D01*
X753539Y438102D01*
X740350D01*
X737584Y435336D01*
X736046D01*
G01X823600Y421194D02*
X799686D01*
X799032Y420540D01*
X787898D01*
X782726Y425712D01*
X757861D01*
X752670Y430903D01*
Y432372D01*
X751860Y433182D01*
X740379D01*
X739384Y432187D01*
X736046D01*
G01X732896Y438486D02*
X734471Y436911D01*
G01X729747Y438486D02*
X731322Y436911D01*
G01X732896Y444785D02*
X734471Y443210D01*
G01X736046Y444785D02*
X737621Y443210D01*
G01X729747Y444785D02*
X731322Y443210D01*
G01X729747Y441636D02*
X731322Y440061D01*
G01X729747Y454234D02*
X731322Y455809D01*
G01X732896Y460533D02*
X734575Y462212D01*
X741980D01*
X746930Y467162D01*
X750220D01*
G01X736046Y457384D02*
X737621Y458959D01*
G01X732896Y454234D02*
X734534Y455872D01*
X744940D01*
X750290Y461222D01*
Y462162D01*
G01X729747Y457384D02*
X731322Y458959D01*
G01X831720Y457700D02*
X828882D01*
X826882Y459700D01*
X814700D01*
X812562Y457562D01*
X772340D01*
X771720Y456942D01*
X757800D01*
X756740Y455882D01*
Y454382D01*
X751800Y449442D01*
X734403D01*
X732896Y447935D01*
G01Y451084D02*
X734471Y452659D01*
G01X736046Y447935D02*
X736819Y447162D01*
X750220D01*
G01X750290Y452162D02*
X749212Y451084D01*
X736046D01*
G01Y454234D02*
X747362D01*
X750290Y457162D01*
G01X783340Y474802D02*
X781170Y472632D01*
X759490D01*
X751720Y464862D01*
X749220D01*
X744891Y460533D01*
X736046D01*
G01X729747Y451084D02*
X731322Y452659D01*
G01X729747Y447935D02*
X731322Y449510D01*
G01X732896Y457384D02*
X734471Y458959D01*
G01X732896Y463683D02*
X734535Y465322D01*
X739870D01*
X746710Y472162D01*
X750220D01*
G01X736046Y463683D02*
X739922D01*
X746101Y469862D01*
X751120D01*
X758600Y477342D01*
X796342D01*
X800900Y481900D01*
X856782D01*
X889500Y449182D01*
X1162440D01*
X1164320Y451062D01*
G01X750220Y477162D02*
X741378D01*
X738945Y474729D01*
X734948D01*
X734523Y474304D01*
Y471658D01*
X732896Y470031D01*
Y469982D01*
G01X736046Y466832D02*
X739220D01*
X747250Y474862D01*
X751320D01*
X754800Y478342D01*
Y484200D01*
X756482Y485882D01*
X766180D01*
X772300Y479762D01*
X794862D01*
X798800Y483700D01*
X858752D01*
X891250Y451202D01*
X1155203D01*
X1159160Y452841D01*
X1189985D01*
X1284306Y438850D01*
X1409226Y426546D01*
X1456777D01*
G01X729747Y463683D02*
X731322Y465258D01*
G01X729747Y476281D02*
X731322Y477856D01*
G01X736046Y469982D02*
X737621Y471557D01*
G01X736046Y476281D02*
X738182D01*
X744103Y482202D01*
X749880D01*
G01X732896Y466832D02*
X734471Y468407D01*
G01X729747Y466832D02*
X731322Y468407D01*
G01X732896Y476281D02*
X734423Y477808D01*
X737372D01*
X744973Y485409D01*
X747859D01*
X754755Y492305D01*
Y496963D01*
X755354Y498409D01*
X756539Y499594D01*
X769567D01*
X772491Y502518D01*
Y504151D01*
X771199Y505443D01*
Y524510D01*
X769985Y525724D01*
G01X732896Y473132D02*
X731321Y474707D01*
G01X729747Y469982D02*
X731322Y471557D01*
G01X740740Y473822D02*
Y473382D01*
X740490Y473132D01*
X736046D01*
G01X732187Y493470D02*
Y497700D01*
X734732Y500245D01*
Y503354D01*
X735220Y503842D01*
G01X738070Y493833D02*
Y490892D01*
X730850Y483672D01*
Y480534D01*
X729747Y479431D01*
G01X738070Y493833D02*
X738512D01*
X740164Y492181D01*
X744278D01*
X749179Y497082D01*
Y498282D01*
G01X732896Y479431D02*
X734471Y481006D01*
G01X735220Y511287D02*
Y508862D01*
G01X729220Y511287D02*
Y508882D01*
G01X737600Y500178D02*
X738781Y498997D01*
X744510D01*
X745220Y498287D01*
G01X735173Y524762D02*
Y521362D01*
G01X729212Y531700D02*
Y528988D01*
X730288Y527912D01*
X735173D01*
G01X765810Y506342D02*
Y519052D01*
X761786Y523076D01*
Y548953D01*
X737594Y573145D01*
Y577849D01*
X735372Y580071D01*
X733117D01*
G01X769745Y502600D02*
Y517616D01*
X763354Y524007D01*
Y549603D01*
X739162Y573795D01*
Y578499D01*
X735090Y582571D01*
X733117D01*
G01X775378Y502502D02*
X776010Y503134D01*
Y528008D01*
X774136Y529882D01*
Y549211D01*
X737675Y585672D01*
X733134D01*
G01X963720Y652262D02*
X964720D01*
X966620Y650362D01*
Y631074D01*
X945008Y609462D01*
X815032D01*
X788352Y636142D01*
X754400D01*
X735620Y617362D01*
Y613862D01*
G01X739699Y766798D02*
X744049D01*
G01Y1252034D02*
X751858D01*
X753534Y1250358D01*
X756957D01*
G01X763457D02*
X766041D01*
X767717Y1252034D01*
X773749D01*
G01X730491D02*
X734967D01*
G01X750040Y1254179D02*
X749522Y1254697D01*
X747926D01*
X747242Y1255381D01*
X744049D01*
G01Y1262074D02*
X737580D01*
G01X735300Y1648760D02*
X734055Y1647515D01*
X730680D01*
G01X737080Y1655820D02*
Y1656260D01*
X739538Y1658718D01*
Y1671180D01*
G01X743462Y1670320D02*
X740698D01*
X739838Y1671180D01*
X739538D01*
G01X743462Y1670320D02*
X758840D01*
X763379Y1674859D01*
Y1678563D01*
G01X747488Y65158D02*
Y68763D01*
X747487Y68764D01*
Y71429D01*
G01X745035Y98005D02*
Y94632D01*
G01X752909Y98005D02*
X753832Y97082D01*
X754800D01*
G01D02*
X754597Y96879D01*
Y91794D01*
X757043Y89348D01*
G01X757340Y92562D02*
X758051Y93273D01*
X760193D01*
G01Y89348D02*
Y93273D01*
G01X752909Y99974D02*
X754094D01*
X757080Y102960D01*
Y113910D01*
X759350Y116180D01*
G01X751558Y115288D02*
Y111288D01*
G01Y115288D02*
Y119170D01*
X751560Y119172D01*
G01X750940Y103911D02*
Y106402D01*
X750700Y106642D01*
G01D02*
X750940Y106882D01*
Y110670D01*
X751558Y111288D01*
G01X764130Y116255D02*
X759425D01*
X759350Y116180D01*
G01X763740Y108400D02*
Y107470D01*
X760193Y103923D01*
Y103803D01*
G01X764130Y113105D02*
X761685D01*
X760390Y111810D01*
G01X745670Y137864D02*
X745660Y137874D01*
Y142050D01*
G01X759289Y143438D02*
X753600D01*
G01D02*
X750198D01*
X748810Y142050D01*
G01X753500Y151312D02*
X763029D01*
G01X751275Y167537D02*
X752875D01*
X755900Y170562D01*
G01D02*
X758925Y167537D01*
X761226D01*
X761245Y167518D01*
G01X751235Y269322D02*
Y265322D01*
G01X756160Y267322D02*
X754160Y265322D01*
X751235D01*
G01Y276322D02*
X753960D01*
X755960Y274322D01*
G01D02*
X756960Y273322D01*
X761223D01*
G01Y271354D02*
X760192D01*
X756160Y267322D01*
G01X758412Y298790D02*
X763178D01*
X763667Y299279D01*
G01X750020Y410662D02*
Y402502D01*
X759310Y393212D01*
X760645D01*
G01Y403212D02*
X754500D01*
X753385Y404327D01*
Y417347D01*
X750020Y420712D01*
G01X750120Y415712D02*
X752275Y413557D01*
Y402857D01*
X756920Y398212D01*
X760645D01*
G01X775645Y413212D02*
X770069D01*
X767749Y410892D01*
X761461D01*
X760645Y411708D01*
Y413212D01*
G01Y408212D02*
X757430D01*
G01X760645Y428212D02*
X758900D01*
X755140Y431972D01*
Y433222D01*
X752570Y435792D01*
X750020D01*
G01X789720Y428437D02*
X787855Y430302D01*
X784850D01*
X784030Y429482D01*
X770408D01*
X768873Y431017D01*
X762245D01*
X760645Y429417D01*
Y428212D01*
G01Y418212D02*
Y423212D01*
G01D02*
X758010D01*
X750510Y430712D01*
X750080D01*
G01X760645Y413212D02*
X759810D01*
X757170Y415852D01*
Y419432D01*
X750890Y425712D01*
X750010D01*
G01X764374Y440803D02*
X762313D01*
X760469Y442647D01*
G01D02*
X759609Y441787D01*
X758220D01*
G01X750220Y447162D02*
X752065D01*
X759765Y454862D01*
G01X786220Y464862D02*
X783740Y462382D01*
X756730D01*
X755100Y460752D01*
Y456972D01*
X750290Y452162D01*
G01Y457162D02*
Y458622D01*
X756530Y464862D01*
X759765D01*
G01Y459862D02*
X757365D01*
G01X750220Y472162D02*
X750821D01*
X758521Y479862D01*
X759765D01*
G01X750220Y467162D02*
X751120D01*
X758820Y474862D01*
X759765D01*
G01X750220Y477162D02*
X752620Y479562D01*
Y484242D01*
X757240Y488862D01*
X759765D01*
G01X750290Y462162D02*
X751020D01*
X758720Y469862D01*
X759765D01*
G01X774765Y464862D02*
X772665Y466962D01*
X760721D01*
X759765Y466006D01*
Y464862D01*
G01X774765Y488862D02*
Y490338D01*
X773691Y491412D01*
X760890D01*
X759765Y490287D01*
Y488862D01*
G01X749880Y482202D02*
Y484022D01*
X759310Y493452D01*
X759825D01*
G01X759765Y483862D02*
X757238D01*
G01X747600Y506592D02*
X745220Y508972D01*
Y511287D01*
G01Y501437D02*
Y503842D01*
G01X761700Y511887D02*
Y506802D01*
X756642Y501744D01*
G01X752500Y495762D02*
X753089Y496351D01*
Y498302D01*
G01X755940Y516862D02*
X753610Y514532D01*
Y508422D01*
X749179Y503991D01*
Y501432D01*
G01X756650Y526072D02*
X758030Y524692D01*
Y506393D01*
X753089Y501452D01*
G01X745220Y524787D02*
Y522362D01*
G01X751220Y524787D02*
Y522362D01*
G01X760191Y957546D02*
X755841D01*
G01X760191Y954200D02*
X755841D01*
G01Y994357D02*
X760191D01*
G01Y1057940D02*
X755541D01*
G01X789891D02*
X780612D01*
X778939Y1059613D01*
X777667D01*
G01X769697D02*
X768826D01*
X766288Y1057075D01*
X763124D01*
X762259Y1057940D01*
X760191D01*
G01X755890Y1255381D02*
X760191D01*
G01X753000Y1261352D02*
X755625Y1258727D01*
X760191D01*
G01Y1252034D02*
X755841D01*
G01Y1248688D02*
X760191D01*
G01X761945Y1384062D02*
X757720D01*
G01Y1375462D02*
X762045D01*
G01X758020Y1397862D02*
X758620Y1397262D01*
X761945D01*
G01X761845Y1414762D02*
X758120D01*
G01X758420Y1406862D02*
X759220Y1406062D01*
X761945D01*
G01X757687Y1587183D02*
X760112D01*
G01X748230Y1674362D02*
Y1678362D01*
G01Y1682362D02*
Y1678362D01*
G01X751620Y1674312D02*
X748280D01*
X748230Y1674362D01*
G01X759859Y1692170D02*
X755859D01*
G01X759859D02*
X763859D01*
G01X755859D02*
Y1697330D01*
G01D02*
X754487Y1698702D01*
Y1703770D01*
X754533Y1703816D01*
G01X748230Y1682362D02*
X755446D01*
X755505Y1682303D01*
G01X758273Y1718740D02*
Y1713264D01*
G01X759359Y1723520D02*
X763359D01*
G01X762013Y1713264D02*
Y1720177D01*
X759359Y1722831D01*
Y1723520D01*
G01X755359Y1726670D02*
X752875D01*
G01X755359Y1723520D02*
Y1723184D01*
X758273Y1720270D01*
Y1718740D01*
G01X764130Y113105D02*
Y108790D01*
X763740Y108400D01*
G01X777878Y153728D02*
X775462Y151312D01*
X763029D01*
G01X774714Y158026D02*
X771426D01*
G01X764342Y162084D02*
X765520Y163262D01*
Y171962D01*
X766194Y172636D01*
X768725D01*
G01X761245Y170077D02*
X762855D01*
X763490Y169442D01*
Y168352D01*
X762656Y167518D01*
X761245D01*
G01X773900Y170064D02*
X774845Y169119D01*
Y163254D01*
G01X773900Y170064D02*
X768738D01*
X768725Y170077D01*
G01X769097Y275290D02*
X770048D01*
X771660Y276902D01*
Y279802D01*
X774660Y282802D01*
Y282922D01*
G01X769097Y273322D02*
X770661D01*
X772661Y275322D01*
X774660D01*
G01D02*
X779085D01*
X779585Y274822D01*
G01Y267822D02*
X779485Y267722D01*
X774660D01*
G01D02*
X774360D01*
X770728Y271354D01*
X769097D01*
G01X1668426Y222432D02*
X1660861D01*
X1656650Y224176D01*
X1647152Y233674D01*
X1637221Y257649D01*
X1565224Y329646D01*
X1446484D01*
X1410222Y365908D01*
X1195438D01*
X1177422Y347892D01*
X1107102D01*
X1095254Y336044D01*
X993560D01*
X988554Y331038D01*
X965492D01*
X942618Y353912D01*
X889622D01*
X843072Y307362D01*
X815494D01*
X801094Y292962D01*
X771720D01*
X769789Y294893D01*
Y296231D01*
G01X774660Y282922D02*
X778485D01*
X779585Y281822D01*
G01X771377Y317392D02*
Y314139D01*
G01X766817Y299279D02*
X777467D01*
G01X776101Y303410D02*
X779120D01*
G01X776016Y308755D02*
X779120D01*
G01X766245Y317432D02*
X766285Y317392D01*
X771377D01*
G01X771490Y354942D02*
X771960Y355412D01*
Y363907D01*
G01X768490Y354942D02*
X767960Y355472D01*
Y363907D01*
G01X774490Y354942D02*
X776000Y356452D01*
Y363787D01*
G01X765000Y354862D02*
Y355932D01*
X764000Y356932D01*
Y363787D01*
G01X771960Y367057D02*
Y375162D01*
G01X767960Y367057D02*
Y369662D01*
G01X776000Y366937D02*
Y369662D01*
G01X764000Y366937D02*
Y369662D01*
G01X775645Y393212D02*
X766195D01*
G01D02*
X763795D01*
G01Y398212D02*
X769710D01*
X772140Y395782D01*
X783620D01*
X788302Y391100D01*
X812500D01*
X813800Y389800D01*
Y386175D01*
G01X763795Y403212D02*
X766195D01*
G01X775645Y398212D02*
X773245D01*
G01X763795Y408212D02*
X768930D01*
X771440Y410722D01*
X781962D01*
X790170Y418930D01*
X799699D01*
X799811Y419042D01*
X817258D01*
X818000Y418300D01*
X819500D01*
G01X775645Y403212D02*
X773245D01*
G01X775645Y408212D02*
X773245D01*
G01X775645Y418212D02*
Y423212D01*
G01X771050Y416940D02*
X774373D01*
X775645Y418212D01*
G01X774765Y454862D02*
X772365D01*
G01X762915D02*
X765315D01*
G01X762915Y459862D02*
X765315D01*
G01X777220Y448437D02*
X776511D01*
X774982Y446908D01*
G01D02*
X773995Y445921D01*
X771066D01*
G01X774765Y459862D02*
X772365D01*
G01X765360Y475412D02*
X765310Y475462D01*
X763515D01*
X762915Y474862D01*
G01X789765Y464862D02*
X787875Y466752D01*
X776655D01*
X774765Y464862D01*
G01Y469862D02*
X772365D01*
G01X762915Y479862D02*
X765315D01*
G01X762915Y483862D02*
X765096D01*
X765386Y483572D01*
G01X762925Y497659D02*
X770535D01*
X775378Y502502D01*
G01X761710Y517651D02*
X761700Y517641D01*
Y515037D01*
G01X777020Y530362D02*
X779220Y528162D01*
Y502862D01*
X792441Y489641D01*
X823859D01*
X826800Y486700D01*
X864300D01*
X886888Y464112D01*
X893460D01*
X900020Y470672D01*
G01X767421Y742095D02*
Y740751D01*
X770675Y737497D01*
X794636D01*
X798733Y741594D01*
Y748394D01*
X801868Y751529D01*
X828640D01*
X832961Y755850D01*
X844300D01*
X847170Y758720D01*
X856469D01*
X870638Y772889D01*
Y929372D01*
X885275Y944009D01*
Y1228516D01*
X859411Y1254380D01*
Y1286792D01*
X809210Y1336993D01*
Y1343062D01*
G01X764921Y742095D02*
Y739985D01*
X769176Y735730D01*
X795368D01*
X800500Y740862D01*
Y747662D01*
X803257Y750419D01*
X829101D01*
X833422Y754740D01*
X846300D01*
X849170Y757610D01*
X856930D01*
X872405Y773085D01*
Y928640D01*
X887042Y943277D01*
Y1229248D01*
X861178Y1255112D01*
Y1287524D01*
X812130Y1336572D01*
Y1343022D01*
G01X769921Y742095D02*
X772752Y739264D01*
X793751D01*
X796807Y742320D01*
Y749115D01*
X800554Y752862D01*
X828402D01*
X832500Y756960D01*
X842900D01*
X845770Y759830D01*
X856009D01*
X869138Y772959D01*
Y929994D01*
X883775Y944631D01*
Y1227894D01*
X857911Y1253758D01*
Y1286170D01*
X806323Y1337758D01*
Y1343076D01*
G01X773749Y766798D02*
X769399D01*
G01X773749Y1252034D02*
X779958D01*
X781634Y1250358D01*
X786657D01*
G01X793187D02*
X796091D01*
X797767Y1252034D01*
X803449D01*
G01X766148Y1255882D02*
X766649Y1255381D01*
X773749D01*
G01Y1262074D02*
X767080D01*
G01X761945Y1388562D02*
Y1384062D01*
G01X762045Y1375462D02*
Y1379962D01*
G01X761945Y1392762D02*
Y1397262D01*
G01Y1401562D02*
Y1406062D01*
G01X761845Y1410262D02*
Y1414762D01*
G01X766880Y1689020D02*
X763859D01*
G01X763359Y1723520D02*
X764880D01*
X766603Y1721797D01*
G01X777995Y163254D02*
X777864Y163123D01*
Y158026D01*
G01X777878Y153728D02*
X777864Y153742D01*
Y158026D01*
G01X782735Y274822D02*
X785135D01*
G01X777467Y299279D02*
Y296315D01*
G01X798204Y279146D02*
X792588Y284762D01*
X785220D01*
G01X792943Y312642D02*
Y316548D01*
X797819Y321424D01*
X846327D01*
X885869Y360966D01*
Y388851D01*
X891540Y394522D01*
Y436926D01*
X883817Y444649D01*
X875406D01*
X871089Y448966D01*
X865425D01*
X863415Y446956D01*
Y445829D01*
G01X800646Y354921D02*
Y326370D01*
X788010Y313734D01*
X784415D01*
G01X794057Y301569D02*
X791042D01*
X789201Y303410D01*
G01X793896Y309026D02*
X789387D01*
X789116Y308755D01*
G01X779120Y303410D02*
X786051D01*
G01X779120Y308755D02*
X785966D01*
G01X789140Y374665D02*
Y380540D01*
G01X792995Y393462D02*
X795520D01*
G01X789845D02*
Y398212D01*
G01X789140Y380540D02*
X793860D01*
X796060Y378340D01*
Y372315D01*
G01X778795Y403212D02*
X784278D01*
G01D02*
X784990Y402500D01*
X789845D01*
G01D02*
Y400956D01*
X790401Y400400D01*
X799297D01*
X800498Y401601D01*
G01X786830Y411600D02*
X786550D01*
X783162Y408212D01*
X778795D01*
G01X786830Y411600D02*
X795095D01*
X796546Y413051D01*
G01X789845Y398212D02*
X781320D01*
G01D02*
X778795D01*
G01X794220Y428437D02*
X789720D01*
G01X778795Y423212D02*
X781195D01*
G01X778795Y413212D02*
X781195D01*
G01X789765Y444862D02*
X787320D01*
G01X792915Y439862D02*
X795320D01*
G01X789765D02*
X787320D01*
G01X792915Y444862D02*
X795320D01*
G01X777915Y459862D02*
X780315D01*
G01X792915Y454862D02*
X795320D01*
G01X789765D02*
X787320D01*
G01X792915Y449862D02*
X795320D01*
G01X789765D02*
X787320D01*
G01X789765Y459862D02*
X787320D01*
G01X792915D02*
X795320D01*
G01X789765Y474862D02*
Y469862D01*
G01D02*
X787360D01*
G01X792915Y464862D02*
X795320D01*
G01X777915D02*
X780315D01*
G01X777915Y488862D02*
X782690D01*
G01X785800Y482762D02*
X786300Y483262D01*
X788325D01*
G01X791475D02*
X793875D01*
G01X793693Y505972D02*
X789240D01*
X787520Y507692D01*
Y510512D01*
G01X782800Y508637D02*
Y511302D01*
X783400Y511902D01*
G01X783600Y502462D02*
X782800Y503262D01*
Y505487D01*
G01X783450Y516907D02*
X787520D01*
G01Y510512D02*
Y516907D01*
G01Y520057D02*
Y524802D01*
G01D02*
X792493D01*
X793673Y523622D01*
G01X1026654Y596152D02*
Y596398D01*
X1023990Y599062D01*
X806133D01*
X791969Y613226D01*
Y618384D01*
G01X838587Y766825D02*
X836537Y764775D01*
X835497D01*
X835157Y764435D01*
X821697D01*
X816207Y758945D01*
X813916D01*
X810099Y762762D01*
X804717D01*
X800900Y758945D01*
X788948D01*
X785157Y762736D01*
Y763212D01*
X782515Y765854D01*
Y766702D01*
G01X789891Y957546D02*
X785541D01*
G01X789891Y954200D02*
X785541D01*
G01Y994357D02*
X789891D01*
G01X819591Y1057940D02*
X815923D01*
X815246Y1057263D01*
X811983D01*
X809633Y1059613D01*
X807367D01*
G01X799457D02*
X796174D01*
X794501Y1057940D01*
X789891D01*
G01X785541Y1255381D02*
X789891D01*
G01X783130Y1259372D02*
X783775Y1258727D01*
X789891D01*
G01Y1252034D02*
X794157D01*
G01X785541Y1248688D02*
X789891D01*
G01X796800Y266800D02*
Y265100D01*
X797320Y264580D01*
X802887D01*
G01X814800D02*
X808793D01*
G01X1672596Y220541D02*
X1671984Y219929D01*
X1661524D01*
X1654658Y222773D01*
X1644267Y233164D01*
X1634336Y257139D01*
X1563839Y327636D01*
X1445499D01*
X1409627Y363508D01*
X1196433D01*
X1178417Y345492D01*
X1108097D01*
X1096249Y333644D01*
X994216D01*
X989449Y328877D01*
X964258D01*
X941623Y351512D01*
X890617D01*
X844067Y304962D01*
X826996D01*
X809065Y287031D01*
Y279293D01*
X811196Y277162D01*
X816220D01*
G01X796800Y266800D02*
X799800Y269800D01*
X802887D01*
G01X1664866Y225162D02*
X1659796D01*
X1658295Y225784D01*
X1649471Y234608D01*
X1639540Y258583D01*
X1566467Y331656D01*
X1453291D01*
X1416739Y368208D01*
X1194485D01*
X1176469Y350192D01*
X1106149D01*
X1094301Y338344D01*
X992223D01*
X987025Y333146D01*
X966637D01*
X943571Y356212D01*
X888669D01*
X842119Y309662D01*
X814950D01*
X801350Y296062D01*
X794220D01*
G01X1660861Y227548D02*
X1659721D01*
X1652127Y235142D01*
X1642151Y259225D01*
X1567710Y333666D01*
X1454534D01*
X1417692Y370508D01*
X1193532D01*
X1175516Y352492D01*
X1105196D01*
X1093348Y340644D01*
X990727D01*
X985654Y335571D01*
X967465D01*
X944524Y358512D01*
X887716D01*
X844656Y315452D01*
X804310D01*
X793820Y304962D01*
G01X809600Y383025D02*
Y379010D01*
X810410Y378200D01*
X811600D01*
G01X803540Y372315D02*
Y369040D01*
X802200Y367700D01*
Y366275D01*
G01D02*
X806000D01*
G01D02*
X809800D01*
G01X803540Y372315D02*
Y377460D01*
X799700Y381300D01*
Y387000D01*
X801500Y388800D01*
X801800D01*
G01X794600Y366275D02*
Y368040D01*
X796060Y369500D01*
Y372315D01*
G01X794600Y366275D02*
X798400D01*
G01X803540Y382945D02*
X809520D01*
X809600Y383025D01*
G01Y386175D02*
X806975Y388800D01*
X801800D01*
G01X806961Y401404D02*
X800695D01*
X800498Y401601D01*
G01X814835Y397664D02*
X801285D01*
X800498Y398451D01*
G01X814835Y412264D02*
X801285D01*
X800498Y413051D01*
G01X794220Y425287D02*
X795645Y423862D01*
X799220D01*
G01D02*
X803917D01*
X805480Y425425D01*
G01X800498Y416201D02*
X800695Y416004D01*
X806961D01*
G01X800498Y416201D02*
X798841D01*
X798440Y415800D01*
Y413540D01*
X797951Y413051D01*
X796546D01*
G01X809220Y433299D02*
X812559D01*
X815310Y436050D01*
G01X801750Y444330D02*
X802520Y445100D01*
X805495D01*
G01X808645D02*
Y441060D01*
G01X1224300Y380400D02*
X1221250Y377350D01*
X1162730D01*
X1152310Y387770D01*
X1084010D01*
X1080430Y391350D01*
Y401880D01*
X1037280Y445030D01*
X936890D01*
X932440Y440580D01*
X895020D01*
X885260Y450340D01*
X877790D01*
X873390Y454740D01*
X861130D01*
X853670Y462200D01*
X843540D01*
X837040Y455700D01*
X828100D01*
X826200Y457600D01*
X816200D01*
X812800Y454200D01*
Y444900D01*
X808960Y441060D01*
X808645D01*
G01X808415Y454862D02*
X810860D01*
G01X805265D02*
X802810D01*
G01X805265Y449862D02*
X802810D01*
G01X808415Y459862D02*
X810860D01*
G01X805265D02*
X802810D01*
G01X808415Y449862D02*
X810860D01*
G01X805265Y469862D02*
Y474862D01*
G01D02*
X802865D01*
G01X808415D02*
X810815D01*
G01X808415Y464862D02*
X810860D01*
G01X805265D02*
X802810D01*
G01X808415Y469862D02*
X810815D01*
G01X801567Y502232D02*
X807530D01*
G01D02*
X810795Y505497D01*
X816670D01*
G01X1296630Y463462D02*
Y471362D01*
X1269140Y498852D01*
X1218460D01*
X1144920Y572392D01*
X1003560D01*
X984490Y591462D01*
X864750D01*
X862100Y588812D01*
X832961D01*
X831156Y590617D01*
X820072D01*
X818267Y588812D01*
X806675D01*
X805445Y587582D01*
G01X963720Y657262D02*
Y656662D01*
X968820Y651562D01*
Y630162D01*
X945920Y607262D01*
X814120D01*
X801270Y620112D01*
X796970D01*
X794720Y617862D01*
G01X797417Y767345D02*
X802902D01*
X803449Y766798D01*
G01X833149Y1252034D02*
X827615D01*
X825939Y1250358D01*
X822777D01*
G01X816357D02*
X810994D01*
X809318Y1252034D01*
X803449D01*
G01X796280Y1254402D02*
X797259Y1255381D01*
X803449D01*
G01Y1262074D02*
X796880D01*
G01X807077Y1597793D02*
X804652D01*
G01X822530Y131386D02*
Y125698D01*
G01D02*
Y125357D01*
X827114Y120773D01*
G01X823114D02*
X819114D01*
G01D02*
X814114D01*
G01D02*
X820561Y127220D01*
Y131386D01*
G01X824498D02*
Y129813D01*
X828613Y125698D01*
X828614D01*
G01X810810Y135132D02*
X811592Y135914D01*
X818002D01*
G01X810640Y128262D02*
X816323Y133945D01*
X818002D01*
G01X814570Y145952D02*
X818112Y142410D01*
X820561D01*
G01X818002Y139851D02*
X814531D01*
G01X810480Y141762D02*
Y140582D01*
X813180Y137882D01*
X818002D01*
G01X819684Y264580D02*
X814800D01*
G01X815060Y280072D02*
X821346D01*
X821533Y279885D01*
G01X813490Y273862D02*
X814513Y274885D01*
X821533D01*
G01X829620Y280345D02*
X825143D01*
X824683Y279885D01*
G01X829820Y275045D02*
X824843D01*
X824683Y274885D01*
G01X827164Y267139D02*
X827150Y267153D01*
X825300D01*
X824783Y267670D01*
Y269336D01*
X825145Y269698D01*
X827164D01*
G01X1674432Y216981D02*
X1673542D01*
X1673041Y217482D01*
X1662161D01*
X1652831Y221347D01*
X1641775Y232403D01*
X1631844Y256378D01*
X1562596Y325626D01*
X1444256D01*
X1408674Y361208D01*
X1197386D01*
X1179370Y343192D01*
X1109050D01*
X1097202Y331344D01*
X995184D01*
X990609Y326769D01*
X963113D01*
X940380Y349502D01*
X891860D01*
X845020Y302662D01*
X829944D01*
X825930Y298648D01*
Y296552D01*
X829720Y292762D01*
G01X841200Y456500D02*
X843392Y458692D01*
X852340D01*
X857480Y453552D01*
Y445652D01*
X860980Y442152D01*
X876680D01*
X881170Y437662D01*
Y379404D01*
X866008Y364242D01*
X846776D01*
X843435Y360901D01*
X832841D01*
X829500Y364242D01*
X822000D01*
X813210Y373032D01*
Y374292D01*
G01X844210Y455902D02*
X851940D01*
X855690Y452152D01*
Y445023D01*
X860471Y440242D01*
X876109D01*
X879460Y436891D01*
Y434573D01*
X878950Y434063D01*
X877250D01*
X876740Y433553D01*
Y431163D01*
X877250Y430653D01*
X878950D01*
X879460Y430143D01*
Y427753D01*
X878950Y427243D01*
X877250D01*
X876740Y426733D01*
Y424343D01*
X877250Y423833D01*
X878950D01*
X879460Y423323D01*
Y380114D01*
X865298Y365952D01*
X857091D01*
X856581Y366462D01*
Y367972D01*
X856071Y368482D01*
X853681D01*
X853171Y367972D01*
Y366462D01*
X852661Y365952D01*
X850271D01*
X849761Y366462D01*
Y367972D01*
X849251Y368482D01*
X846861D01*
X846351Y367972D01*
Y366462D01*
X843569Y363680D01*
X837839D01*
X835567Y365952D01*
X822710D01*
X815710Y372952D01*
Y374292D01*
G01X811600Y378200D02*
X812590D01*
X813800Y379410D01*
Y383025D01*
G01Y386175D02*
X818000D01*
G01D02*
Y387832D01*
X823720Y393552D01*
X828261D01*
X830553Y395844D01*
Y397276D01*
G01X852331Y378362D02*
X849100D01*
X848100Y379362D01*
Y401000D01*
X846600Y402500D01*
X824092D01*
X822800Y403792D01*
Y415190D01*
X823650Y416040D01*
X831240D01*
X832400Y417200D01*
Y421325D01*
G01X819220Y397664D02*
X814835D01*
G01X819220Y412264D02*
X814835D01*
G01X819500Y418300D02*
X824200D01*
X827225Y421325D01*
X828300D01*
G01X812960Y425425D02*
X819220D01*
G01D02*
X824082D01*
X824220Y425287D01*
G01X815310Y440100D02*
Y436050D01*
G01X844500Y447100D02*
Y447600D01*
X839100Y453000D01*
X827000D01*
X825600Y454400D01*
X817200D01*
X815600Y452800D01*
Y443300D01*
X817900Y441000D01*
Y432100D01*
X819400Y430600D01*
X825900D01*
X826500Y430000D01*
Y427931D01*
X828300Y426131D01*
Y424475D01*
G01X820875Y449200D02*
X824925D01*
G01X828540Y443365D02*
Y446260D01*
X828000Y446800D01*
X825700D01*
X824925Y447575D01*
Y449200D01*
G01X822415Y464862D02*
X824860D01*
G01X819265D02*
X816810D01*
G01X819265Y472900D02*
Y468900D01*
G01Y472900D02*
X816400D01*
G01X827100Y471682D02*
X826818D01*
X825600Y472900D01*
X822415D01*
G01X824195Y498082D02*
Y494007D01*
X824188Y494000D01*
G01D02*
Y493894D01*
X828020Y490062D01*
X854820D01*
X857620Y492862D01*
G01X824195Y506082D02*
Y502082D01*
G01D02*
Y498082D01*
G01X816670Y502347D02*
X819320D01*
G01X824195Y511082D02*
X821720D01*
G01X824195Y527082D02*
X821720D01*
G01X1172310Y584562D02*
Y592869D01*
X1166029Y599150D01*
X1125494D01*
X1118964Y605680D01*
Y618822D01*
X1106497Y631289D01*
X1075726D01*
X1054599Y610162D01*
X1015325D01*
X1007620Y602457D01*
X813951D01*
X811143Y605265D01*
G01X819591Y957546D02*
X815241D01*
G01X819591Y954200D02*
X815241D01*
G01Y994357D02*
X819591D01*
G01X849291Y1057940D02*
X840223D01*
X838550Y1059613D01*
X837097D01*
G01X829227D02*
X828175D01*
X825507Y1056945D01*
X823986D01*
X822991Y1057940D01*
X819591D01*
G01X815241Y1255381D02*
X819591D01*
G01Y1252034D02*
X823877D01*
G01X815241Y1248688D02*
X819591D01*
G01X812440Y1258727D02*
X819591D01*
G01X831539Y65918D02*
Y70643D01*
G01D02*
X831942Y71046D01*
X837531D01*
X840037Y68540D01*
Y58448D01*
G01X831539Y62768D02*
X836779Y68008D01*
G01X842596Y81448D02*
X842525Y81519D01*
Y84621D01*
X839898Y87248D01*
G01D02*
Y89949D01*
X840400Y90451D01*
G01X844935Y93326D02*
X842439D01*
X841584Y94181D01*
G01D02*
Y99061D01*
X841742Y99219D01*
Y99651D01*
G01X837250Y90451D02*
Y93221D01*
G01X835114Y117623D02*
Y115223D01*
G01X831114Y120773D02*
X827114D01*
G01X835114D02*
X839244D01*
X839360Y120657D01*
G01X828614Y125698D02*
X830189D01*
X835114Y120773D01*
G01X842295Y135862D02*
X845220D01*
G01X839145D02*
X837489D01*
X837325Y135698D01*
X834114D01*
G01D02*
X832361Y133945D01*
X829026D01*
G01X842295Y129362D02*
X845220D01*
G01X839145D02*
X837489D01*
X837325Y129198D01*
X833614D01*
G01D02*
X827614D01*
X826467Y130345D01*
Y131386D01*
G01X846190Y145262D02*
X839490Y138562D01*
X832990D01*
X830342Y135914D01*
X829026D01*
G01X839460Y146042D02*
X833870Y140452D01*
X833060D01*
X830490Y137882D01*
X829026D01*
G01X833320Y145912D02*
X831030Y143622D01*
Y140292D01*
X830589Y139851D01*
X829026D01*
G01X831295Y166862D02*
Y171632D01*
G01X838220Y163862D02*
Y169362D01*
X839776Y170918D01*
X842562D01*
G01X835220Y163862D02*
Y169142D01*
X839556Y173478D01*
X842562D01*
G01X842720Y181360D02*
X840220Y183860D01*
Y184787D01*
G01X831295Y176362D02*
X832345Y177412D01*
X838670D01*
X839750Y176332D01*
X842562D01*
G01X831295Y171632D02*
Y176362D01*
G01X840220Y187937D02*
X839220Y188937D01*
Y192862D01*
G01D02*
Y196787D01*
X840220Y197787D01*
G01Y200937D02*
X838820Y202337D01*
Y206872D01*
G01X837160Y218212D02*
X839997Y215375D01*
X841967D01*
G01Y217344D02*
X841099D01*
X838140Y220303D01*
X834920D01*
G01X837160Y213207D02*
X837360Y213407D01*
X841967D01*
G01X838820Y206872D02*
X840581Y211123D01*
X840896Y211438D01*
X841967D01*
G01X834920Y220303D02*
X833715Y221508D01*
Y224993D01*
G01X839080Y233252D02*
X840910Y231422D01*
Y226462D01*
X846495Y220877D01*
Y219903D01*
G01X838680Y224752D02*
X839950Y223482D01*
X841790D01*
X844526Y220746D01*
Y219903D01*
G01X833060Y280045D02*
X832760Y280345D01*
X829620D01*
G01X833060Y275045D02*
X829820D01*
G01X827164Y267139D02*
X832500D01*
G01X840063Y285022D02*
X840669Y284416D01*
X845505D01*
G01Y294702D02*
X839860D01*
G01X864911Y402581D02*
X867140Y404810D01*
X876430D01*
X877000Y404240D01*
Y384862D01*
X871743Y379605D01*
X867134D01*
X865175Y377646D01*
Y373037D01*
X863000Y370862D01*
X856272D01*
X855378Y371756D01*
X846894D01*
X844361Y369223D01*
X840639D01*
X836000Y373862D01*
Y379862D01*
X838240Y382102D01*
X843669D01*
G01X835564Y389140D02*
X830681D01*
X830553Y389012D01*
G01X827425Y384400D02*
Y385884D01*
X830553Y389012D01*
G01X842684Y389140D02*
X835564D01*
G01X836064Y396620D02*
X831209D01*
X830553Y397276D01*
G01X836064Y396620D02*
X842684D01*
G01X842470Y407020D02*
X837378D01*
X836330Y405972D01*
G01X828300Y421325D02*
X832400D01*
G01X842470Y414500D02*
X837352D01*
X836290Y415562D01*
G01X836300Y424475D02*
X840200D01*
G01D02*
X844200D01*
G01X829800Y429300D02*
X831200D01*
X831700Y429800D01*
Y433146D01*
X832200Y433646D01*
X834854D01*
X835460Y433040D01*
Y430185D01*
G01X829800Y429300D02*
X827300Y431800D01*
Y438401D01*
X828540Y439641D01*
Y443365D01*
G01X832084Y471682D02*
X827100D01*
G01X839564D02*
X843618D01*
X844300Y471000D01*
Y469400D01*
X844570Y469130D01*
G01X827100Y479200D02*
X829500Y476800D01*
X832084D01*
G01X830870Y480010D02*
X852090D01*
X855200Y476900D01*
G01X827345Y506082D02*
X832620D01*
G01D02*
X838089D01*
X838530Y505641D01*
G01D02*
X842600Y501571D01*
Y499100D01*
X846400Y495300D01*
X857045D01*
G01X827345Y502082D02*
X829745D01*
G01X827345Y527082D02*
Y523082D01*
G01X839035Y518006D02*
X835275D01*
X832125Y521156D01*
G01D02*
X830199Y523082D01*
X827345D01*
G01X834922Y525849D02*
X832370D01*
G01X827345Y519082D02*
Y515082D01*
G01Y511082D02*
Y515082D01*
G01Y511082D02*
X829151Y512888D01*
X832590D01*
G01D02*
X839035D01*
G01X837875Y525849D02*
X841461D01*
G01X834903Y529786D02*
X828545D01*
X827345Y528586D01*
Y527082D01*
G01X837875Y527817D02*
X843287D01*
G01X831705Y593877D02*
X834472Y591110D01*
X861694D01*
X864616Y594032D01*
X985690D01*
X1005490Y574232D01*
X1146840D01*
X1219060Y502012D01*
X1381060D01*
X1383890Y499182D01*
X1387600D01*
G01X828699Y766798D02*
X833149D01*
G01X854237Y1250358D02*
X852477D01*
G01X846057D02*
X840694D01*
X839018Y1252034D01*
X833149D01*
G01X826501Y1254553D02*
X827329Y1255381D01*
X833149D01*
G01Y1262074D02*
X826750D01*
G01X864967Y60983D02*
X859499Y55515D01*
X848678D01*
X847715Y56478D01*
Y58448D01*
G01X856629Y66068D02*
Y70793D01*
G01D02*
X850871D01*
X845156Y65078D01*
Y58448D01*
G01X858629Y60293D02*
X856629Y62293D01*
Y62918D01*
G01X844935Y93326D02*
X846895Y91366D01*
Y87021D01*
X845156Y85282D01*
Y81448D01*
G01X850015Y90176D02*
Y87341D01*
G01D02*
Y82832D01*
X848631Y81448D01*
X847715D01*
G01X850088Y105951D02*
X848915D01*
X845765Y102801D01*
Y96461D01*
X847472Y94754D01*
G01D02*
X848900Y93326D01*
X850015D01*
G01X851795Y135862D02*
X854220D01*
G01X851795Y129362D02*
X854220D01*
G01X848645Y135862D02*
X845220D01*
G01X848645Y129362D02*
X845220D01*
G01X851485Y185812D02*
Y184166D01*
X850341Y183022D01*
X848510D01*
X848360Y182872D01*
G01X848335Y185812D02*
X845245D01*
X844220Y184787D01*
G01X845720Y181362D02*
Y183287D01*
X844220Y184787D01*
G01X856430Y182260D02*
X856190Y182500D01*
Y187035D01*
G01X862232Y183600D02*
X859300D01*
X857960Y182260D01*
X856430D01*
G01X844220Y187937D02*
X845220Y188937D01*
Y192862D01*
G01D02*
Y196787D01*
X844220Y197787D01*
G01X844526Y204968D02*
Y202899D01*
X844220Y202593D01*
Y200937D01*
G01X849320Y196532D02*
X847260Y198592D01*
Y204853D01*
X846495Y205618D01*
Y208879D01*
G01X853340Y199932D02*
X850760Y202512D01*
Y204137D01*
X848463Y206434D01*
Y208879D01*
G01X860050Y215310D02*
Y199650D01*
X856190Y195790D01*
Y190185D01*
G01X844526Y208879D02*
Y204968D01*
G01X855400Y204772D02*
X852910D01*
X850432Y207250D01*
Y208879D01*
G01X843510Y228962D02*
X848463Y224009D01*
Y219903D01*
G01X1678994Y217231D02*
X1678353D01*
X1675990Y214868D01*
X1662187D01*
X1650276Y219802D01*
X1639469Y230609D01*
X1628661Y256701D01*
X1561790Y323572D01*
X1442610D01*
X1407174Y359008D01*
X1198298D01*
X1180282Y340992D01*
X1110650D01*
X1098202Y328544D01*
X995918D01*
X991825Y324451D01*
X962431D01*
X939390Y347492D01*
X893750D01*
X850093Y303835D01*
Y286625D01*
G01X845505Y287566D02*
Y294702D01*
G01X856243Y286447D02*
X858887D01*
X859729Y285605D01*
X859888Y285222D01*
Y283527D01*
G01X852331Y378362D02*
X859425D01*
G01X852998Y389140D02*
X859564D01*
G01X842684Y396620D02*
X844520D01*
X846040Y398140D01*
Y399210D01*
G01X853100Y407020D02*
X859668D01*
X859876Y406812D01*
G01X852998Y396620D02*
X857279D01*
X859740Y399081D01*
G01X851080Y422131D02*
X846490D01*
G01X853100Y414500D02*
X859652D01*
X859876Y414276D01*
G01X842940Y430185D02*
Y427160D01*
X844200Y425900D01*
Y424475D01*
G01X854820Y437422D02*
X858971D01*
X859011Y437462D01*
X863450D01*
G01X854820Y430793D02*
Y437422D01*
G01X849000Y441275D02*
X847475D01*
X846700Y440500D01*
Y437600D01*
X846000Y436900D01*
X843800D01*
X842940Y437760D01*
Y440815D01*
G01X844500Y447100D02*
Y445900D01*
X842940Y444340D01*
Y440815D01*
G01X849000Y438125D02*
Y433500D01*
X848900Y433400D01*
G01D02*
X843500D01*
X842940Y432840D01*
Y430185D01*
G01X844570Y469130D02*
X844600Y469100D01*
X849325D01*
G01X852475D02*
Y473000D01*
G01D02*
Y476900D01*
G01D02*
X855200D01*
G01X857045Y507162D02*
Y503162D01*
G01D02*
Y499062D01*
G01X846010Y503082D02*
X851941D01*
G01D02*
X856021Y507162D01*
X857045D01*
G01D02*
Y509575D01*
X858600Y511130D01*
G01X860195Y495300D02*
Y495912D01*
X857045Y499062D01*
G01X845483Y515447D02*
X853070D01*
G01D02*
X857060D01*
X857195Y515582D01*
G01X858600Y511130D02*
X856842Y512888D01*
X845483D01*
G01X849291Y957546D02*
X844841D01*
G01X849291Y954200D02*
X844841D01*
G01Y994357D02*
X849291D01*
G01X842630Y1256912D02*
X844161Y1255381D01*
X849291D01*
G01Y1252034D02*
X844941D01*
G01X844997Y1248155D02*
X846786D01*
X847319Y1248688D01*
X849291D01*
G01X844941Y1258727D02*
X849291D01*
G01X849077Y1597793D02*
X846652D01*
G01X879145Y171362D02*
Y172436D01*
X877719Y173862D01*
X873645D01*
X871145Y171362D01*
G01X859688Y170918D02*
X859744Y170862D01*
X866220D01*
G01D02*
X870645D01*
X871145Y171362D01*
G01X859688Y173478D02*
X864067D01*
X866451Y175862D01*
G01X879145Y176862D02*
Y177938D01*
X877921Y179162D01*
X873445D01*
X871145Y176862D01*
G01X866451Y175862D02*
X867451Y176862D01*
X871145D01*
G01X865243Y265961D02*
X863294D01*
G01D02*
X860282D01*
X859378Y265057D01*
G01X871345Y268806D02*
Y267557D01*
X868020Y264232D01*
G01D02*
X866291Y265961D01*
X865243D01*
G01X859888Y280027D02*
X862904D01*
G01X864590D02*
X867381D01*
X867407Y280001D01*
G01X864590Y280027D02*
X863747Y280870D01*
G01D02*
X862904Y280027D01*
G01X871345Y276064D02*
Y268806D01*
G01X859408Y273217D02*
X859921Y273730D01*
X861865D01*
G01D02*
X864813D01*
X867147Y276064D01*
X867407D01*
G01X859888Y283527D02*
X865850D01*
X867407Y281970D01*
G01X859378Y269057D02*
X863240D01*
X863294Y269111D01*
G01D02*
X866851D01*
X867700Y268262D01*
G01D02*
X869447Y270009D01*
Y275993D01*
X869376Y276064D01*
G01X868552Y285537D02*
X869376Y284713D01*
Y281970D01*
G01X867618Y289311D02*
X867571Y289358D01*
Y293810D01*
G01X867618Y289311D02*
Y286471D01*
X868552Y285537D01*
G01X859564Y389140D02*
X862247D01*
X864911Y386476D01*
G01D02*
Y382415D01*
G01X868113Y406812D02*
Y409372D01*
G01X864963Y406812D02*
X859876D01*
G01X864911Y402581D02*
X863240D01*
X859740Y399081D01*
G01X864963Y418836D02*
Y414276D01*
G01X859876D02*
X864963D01*
G01X867190Y437462D02*
X870921D01*
X872820Y435563D01*
Y430963D01*
G01D02*
X872319Y430462D01*
X868895D01*
X867895Y431462D01*
G01X860574Y445404D02*
Y448372D01*
X863967Y451765D01*
X872022D01*
X876785Y447002D01*
X884910D01*
X893732Y438180D01*
X933668D01*
X937648Y442160D01*
X1037661D01*
X1077582Y402239D01*
Y390962D01*
G01X870360Y493042D02*
Y488432D01*
X882230Y476562D01*
X899200D01*
X900150Y477512D01*
X903410D01*
X905160Y475762D01*
Y454572D01*
X906880Y452852D01*
X1152610D01*
X1156100Y456342D01*
G01X986273Y532996D02*
X976428Y542841D01*
Y574966D01*
X964201Y587193D01*
X865322D01*
X864601Y586472D01*
X861774D01*
X859054Y583752D01*
G01X859888Y593970D02*
X861570Y595652D01*
X986790D01*
X1006410Y576032D01*
X1147370D01*
X1163785Y559617D01*
X1163920D01*
X1219668Y503869D01*
X1385983D01*
X1386930Y502922D01*
X1387550D01*
G01X884290Y183169D02*
Y183106D01*
G01D02*
X888883Y187699D01*
X906734D01*
X907957Y186476D01*
X913386D01*
G01X882295Y171362D02*
X887520D01*
G01X882295Y176862D02*
X887520D01*
G01X884300Y192055D02*
Y187449D01*
G01Y192055D02*
X884375Y192130D01*
Y195720D01*
G01X913386Y191201D02*
X898039D01*
X893751Y195489D01*
X889350D01*
G01X884300Y187449D02*
X889350Y192499D01*
Y195489D01*
G01X877724Y200837D02*
X881031Y204144D01*
X883364D01*
X884375Y203133D01*
Y201150D01*
G01D02*
X890304D01*
X897891Y193563D01*
X913386D01*
G01X881225Y201150D02*
Y195720D01*
G01X877971Y196652D02*
X880293D01*
X881225Y195720D01*
G01X879219Y278033D02*
X880080D01*
X883909Y281862D01*
G01D02*
X886503D01*
G01X877840Y289439D02*
X877250Y288849D01*
Y281970D01*
G01X879219Y276064D02*
Y270372D01*
X879587Y270004D01*
G01D02*
X880756D01*
X883353Y267407D01*
G01X886503Y271332D02*
Y267407D01*
G01X883870Y272652D02*
X885183D01*
X886503Y271332D01*
G01X877840Y289439D02*
X877868Y289467D01*
Y293347D01*
G01X877891Y298665D02*
Y296620D01*
X877322Y296051D01*
G01D02*
X877868Y295505D01*
Y293347D01*
G01X1121428Y56545D02*
X1116720Y61253D01*
Y82785D01*
X1083935Y115570D01*
Y153998D01*
X1069358Y168575D01*
X1043757D01*
X1026446Y185886D01*
X1021850Y196983D01*
Y228474D01*
X1013814Y236510D01*
X951406D01*
X883620Y304296D01*
Y324606D01*
X882520Y325706D01*
Y327562D01*
G01X885020D02*
Y325706D01*
X885599Y325127D01*
Y305116D01*
X952440Y238275D01*
X1014848D01*
X1023829Y229294D01*
Y197060D01*
X1028155Y186616D01*
X1044217Y170554D01*
X1070178D01*
X1085914Y154818D01*
Y116390D01*
X1118699Y83605D01*
Y63374D01*
X1121528Y60545D01*
G01X887520Y327562D02*
Y305912D01*
X953236Y240196D01*
X1015644D01*
X1025750Y230090D01*
Y196908D01*
X1029533Y187775D01*
X1044833Y172475D01*
X1070974D01*
X1087835Y155614D01*
Y117186D01*
X1120620Y84401D01*
Y65453D01*
X1121528Y64545D01*
G01X965884Y242051D02*
Y242052D01*
X939441Y268495D01*
X928427D01*
X890040Y306882D01*
Y328102D01*
X886750Y331392D01*
Y336312D01*
X891570Y341132D01*
X896540D01*
G01X968384Y242051D02*
Y243259D01*
X941381Y270262D01*
X929159D01*
X891807Y307614D01*
Y328834D01*
X888517Y332124D01*
Y335580D01*
X889169Y336232D01*
X893440D01*
G01X1051680Y614772D02*
X1066680Y629772D01*
Y659412D01*
X1056430Y669662D01*
X970520D01*
X900880Y739302D01*
X890740D01*
X889000Y737562D01*
G01X1144810Y613762D02*
X1126310Y632262D01*
Y633612D01*
X1086660Y673262D01*
X969370D01*
X901598Y741034D01*
X889444D01*
X888576Y741902D01*
X886720D01*
G01X887897Y874405D02*
Y876305D01*
X887142Y877060D01*
Y879195D01*
G01X887897Y874405D02*
Y870929D01*
G01X887142Y879195D02*
Y882036D01*
X887000Y882178D01*
Y886962D01*
G01X888467Y920325D02*
X884619Y916477D01*
G01D02*
X887000Y914096D01*
Y907762D01*
G01X891077Y1597793D02*
X888652D01*
G01X893700Y201799D02*
X897212Y198287D01*
X913386D01*
G01X899500Y201899D02*
X900750Y200649D01*
X913386D01*
G01X933686Y242922D02*
X936370Y245606D01*
Y249032D01*
X902340Y283062D01*
X894770D01*
G01X891747Y874405D02*
Y876245D01*
X892408Y876906D01*
Y879200D01*
G01X891747Y874405D02*
Y870929D01*
G01X892408Y879200D02*
Y882378D01*
X892000Y882786D01*
Y886962D01*
G01X892317Y920325D02*
Y915872D01*
G01D02*
Y912050D01*
X892000Y911733D01*
Y907762D01*
G01X897640Y915099D02*
Y910563D01*
X897000Y909923D01*
Y907762D01*
G01X922726Y176302D02*
X928176Y181752D01*
X931496D01*
G01X922100Y181791D02*
X919090D01*
X919051Y181752D01*
X913386D01*
G01Y184114D02*
X917386D01*
G01X908620Y188899D02*
X908681Y188838D01*
X913386D01*
G01X924623Y492097D02*
X924248D01*
X922379Y490228D01*
X922236D01*
G01X918212Y497677D02*
X917875D01*
X916331Y496133D01*
G01X923783Y506076D02*
X923782D01*
X922234Y507647D01*
X922236Y507944D01*
G01X918212Y500777D02*
X917593D01*
X916331Y502039D01*
G01X909984Y496330D02*
X910181Y496133D01*
X914362D01*
G01X916974Y964612D02*
Y962108D01*
G01Y967762D02*
X920273Y971061D01*
Y972460D01*
G01X921868Y979352D02*
Y974055D01*
X920273Y972460D01*
G01X921757Y967762D02*
Y968454D01*
X925723Y972420D01*
G01X923836Y979352D02*
Y976746D01*
X923930Y976652D01*
G01X921868Y994116D02*
Y999472D01*
G01X921720Y1009937D02*
X918720D01*
G01X921868Y999472D02*
Y1004983D01*
X921720Y1005131D01*
Y1006787D01*
G01X931496Y186476D02*
X938138D01*
X940424Y184190D01*
G01X931496Y184114D02*
X936348D01*
X936424Y184190D01*
G01X931496Y193563D02*
X923836D01*
G01X940410Y188852D02*
X931509D01*
X931495Y188838D01*
X931496D01*
G01X929654Y492103D02*
X930110Y491647D01*
Y490228D01*
G01X956920Y490462D02*
X953722Y493660D01*
X936521D01*
X936016Y494165D01*
G01X950820Y489762D02*
X948386Y492196D01*
X936016D01*
G01X926173Y512391D02*
Y509913D01*
G01X932373Y495175D02*
X932585D01*
X933543Y496133D01*
X934047D01*
G01X932218Y499314D02*
X932974Y500070D01*
X934047D01*
G01X926637Y506069D02*
X928144Y507583D01*
X928142Y507944D01*
G01X929281Y506086D02*
Y507106D01*
X930110Y507944D01*
G01X934171Y981813D02*
X934737D01*
X936208Y980342D01*
X938940D01*
X938980Y980382D01*
G01D02*
X939020Y980342D01*
X943485D01*
X943750Y980077D01*
G01X931496Y967762D02*
X931461Y967727D01*
X926823D01*
G01X931496Y967762D02*
Y971086D01*
X931083Y971499D01*
Y972420D01*
G01X929742Y979352D02*
Y973761D01*
X931083Y972420D01*
G01X927773Y979352D02*
Y974470D01*
X925723Y972420D01*
G01X945735Y997422D02*
X939942Y991629D01*
G01X934171Y987718D02*
X936031D01*
X939942Y991629D01*
G01X947348Y985502D02*
X944258Y988592D01*
X940570D01*
X939740Y987762D01*
G01X934171Y983781D02*
X938560D01*
X939340Y984561D01*
Y987362D01*
X939740Y987762D01*
G01X929742Y994116D02*
Y999384D01*
X932220Y1001862D01*
G01X927773Y994116D02*
Y1000499D01*
X926464Y1001808D01*
G01X927220Y1009937D02*
Y1012362D01*
G01X931220D02*
Y1006787D01*
X932220Y1005787D01*
Y1001862D01*
G01X926464Y1001808D02*
X926220Y1002052D01*
Y1005887D01*
X927120Y1006787D01*
X927220D01*
G01X940424Y184190D02*
X941233Y184999D01*
X943253D01*
X943340Y184912D01*
G01X949550Y192819D02*
X946410Y189679D01*
Y188852D01*
G01X943260D02*
X940410D01*
G01X955297Y536806D02*
Y533816D01*
X955123Y533642D01*
G01X948415Y534313D02*
Y539044D01*
X950098Y540727D01*
X955296D01*
G01X943750Y983227D02*
X946995Y979982D01*
X947275D01*
G01X959535Y977250D02*
Y977607D01*
X956145Y980997D01*
X949955D01*
X949560Y981392D01*
G01D02*
X948150Y979982D01*
X947275D01*
G01X958215Y997496D02*
X955561Y994842D01*
X948315D01*
X945735Y997422D01*
G01X947348Y985502D02*
X948708Y986862D01*
X951969D01*
X953235Y985596D01*
G01X962882Y314512D02*
X965522Y311872D01*
X993742D01*
X999310Y317440D01*
X1014232D01*
X1018760Y312912D01*
Y304261D01*
X1019939Y303082D01*
Y300488D01*
G01X967239Y320073D02*
X993350D01*
X997221Y323944D01*
X1099555D01*
X1111963Y336352D01*
X1182205D01*
X1200221Y354368D01*
X1406691D01*
X1460000Y301059D01*
Y278800D01*
X1450520Y269320D01*
Y256892D01*
X1456147Y251265D01*
X1458880D01*
G01X963854Y320113D02*
X966083Y322342D01*
X992878D01*
X995970Y325434D01*
X1099022D01*
X1111370Y337782D01*
X1181612D01*
X1199628Y355798D01*
X1407284D01*
X1462100Y300982D01*
Y277600D01*
X1451950Y267450D01*
Y261372D01*
X1454380Y258942D01*
X1458880D01*
G01X970738Y344659D02*
X971496D01*
X974900Y348063D01*
Y354162D01*
X973168Y355894D01*
Y356896D01*
G01X972220Y386251D02*
Y386983D01*
X972799Y387562D01*
X975020D01*
X975720Y386862D01*
G01X983389Y387769D02*
X982796Y388362D01*
X978720D01*
X977810Y389272D01*
X973187D01*
X972220Y390239D01*
G01X958447Y536806D02*
X957200Y535559D01*
Y532402D01*
X956519Y531721D01*
X956518Y531567D01*
G01X959351Y533566D02*
X960159Y534374D01*
Y540227D01*
X959659Y540727D01*
X958446D01*
G01X991425Y148299D02*
X991350Y148224D01*
X985500D01*
G01X986369Y155358D02*
X985500Y154489D01*
Y151374D01*
G01X992452Y163541D02*
X988038D01*
X982349Y169230D01*
Y171483D01*
G01X992452Y155667D02*
X991036D01*
X990727Y155358D01*
X986369D01*
G01X985499Y168753D02*
X988742Y165510D01*
X992452D01*
G01X981445Y175508D02*
Y175006D01*
X977479Y171040D01*
G01D02*
X981906D01*
X982349Y171483D01*
G01X985445Y175508D02*
X985499Y175454D01*
Y171483D01*
G01D02*
Y168753D01*
G01X977070Y211709D02*
X977195Y211584D01*
Y206998D01*
G01X983770Y373962D02*
Y370793D01*
X983260Y370283D01*
X979010D01*
X978500Y369773D01*
Y367383D01*
X979010Y366873D01*
X983260D01*
X983770Y366363D01*
Y364732D01*
X983073Y364035D01*
X981789D01*
G01X979766Y377507D02*
X974888Y372629D01*
X973168Y368477D01*
Y356896D01*
G01X979084Y350959D02*
X980600Y352475D01*
Y354029D01*
X977719Y356910D01*
G01X981789Y360885D02*
X981177D01*
X979600Y362462D01*
X978000D01*
G01D02*
X977100Y361562D01*
Y357529D01*
X977719Y356910D01*
G01X995798Y376725D02*
Y375837D01*
X989611Y369650D01*
X988723D01*
G01X991369Y381154D02*
X990544D01*
X983770Y374380D01*
Y373962D01*
G01X986999Y381037D02*
X983469Y377507D01*
X979766D01*
G01X991369Y385091D02*
X984815D01*
X982116Y382392D01*
X979762D01*
X977949Y384205D01*
G01X982972Y385566D02*
X981692Y384286D01*
X980916D01*
G01X991369Y387060D02*
X989514D01*
X989203Y386749D01*
X982707D01*
X982235Y386277D01*
X978482D01*
X977897Y386862D01*
X975720D01*
G01X990501Y152397D02*
Y151325D01*
X991425Y150401D01*
Y148299D01*
G01X995180Y153689D02*
X998425Y150444D01*
Y148299D01*
G01X996415Y172579D02*
Y167505D01*
X996389Y167479D01*
G01X994421Y155667D02*
Y154448D01*
X995180Y153689D01*
G01X998358Y157636D02*
X1005117D01*
X1005735Y157018D01*
G01X992452Y167479D02*
X990115Y169816D01*
Y173039D01*
G01X999915Y174998D02*
Y169036D01*
X998358Y167479D01*
G01X1005699Y167268D02*
X1002859D01*
X1001101Y165510D01*
G01D02*
X998358D01*
G01X996415Y174998D02*
Y172579D01*
G01X990115Y173039D02*
Y174968D01*
X989605Y175478D01*
G01X1002920Y174799D02*
X1002721Y174998D01*
X999915D01*
G01X1004868Y190419D02*
X1008091D01*
X1009501Y189009D01*
X1010388D01*
G01X1004967Y198293D02*
X1008120D01*
G01X1004967Y200261D02*
X1009982D01*
X1011320Y201599D01*
Y202169D01*
G01X1010976Y195562D02*
X1010213Y196325D01*
X1004967D01*
G01X1001423Y207742D02*
Y210226D01*
X1000610Y211039D01*
G01D02*
X1001423Y211852D01*
Y214320D01*
X1001395Y214348D01*
G01X997487Y207742D02*
Y213233D01*
G01Y221233D02*
Y217233D01*
G01Y213233D02*
Y217233D01*
G01X997460Y226019D02*
Y221260D01*
X997487Y221233D01*
G01X1052705Y363120D02*
X1036696Y347111D01*
X1004691D01*
X993448Y358354D01*
Y363155D01*
G01D02*
X992943Y363660D01*
X989332D01*
G01D02*
Y363764D01*
X991934Y366366D01*
Y368443D01*
G01X996922Y367764D02*
X1000735Y363951D01*
Y363352D01*
G01X997767Y376725D02*
Y375468D01*
X991934Y369635D01*
Y368443D01*
G01X993830Y376725D02*
Y378489D01*
X994689Y379348D01*
G01X1001186Y369258D02*
X1000009Y368081D01*
G01X1004899Y374500D02*
Y373061D01*
X1003293Y371455D01*
G01X991369Y408252D02*
Y404776D01*
G01X997767Y407237D02*
Y409637D01*
X995968Y411436D01*
X994902Y413031D01*
X994220Y414677D01*
Y420362D01*
X993012Y421570D01*
G01X999735Y407237D02*
Y413237D01*
X997394Y415578D01*
G01X1003672Y407237D02*
Y408025D01*
X1003046Y408651D01*
Y415395D01*
X1001996Y417931D01*
Y421483D01*
X1001721Y421758D01*
G01X1001704Y407237D02*
Y408189D01*
X1002016Y408501D01*
Y415190D01*
X1000249Y419458D01*
X997355Y422352D01*
X996502D01*
X996154Y422700D01*
G01X1007609Y407237D02*
Y408301D01*
X1007199Y408711D01*
Y412689D01*
X1008319Y413809D01*
Y417363D01*
X1005220Y420462D01*
Y424370D01*
X1007249Y426399D01*
G01X1005641Y407237D02*
Y408297D01*
X1006169Y408825D01*
Y413116D01*
X1007289Y414236D01*
Y416394D01*
X1004049Y419634D01*
Y429283D01*
X1003235Y430097D01*
G01X1001970Y1251522D02*
X1002482Y1252034D01*
X1008191D01*
G01X1002070Y1256942D02*
Y1255942D01*
X1002631Y1255381D01*
X1008191D01*
G01Y1262074D02*
X1003841D01*
G01X1009735Y157018D02*
X1012213D01*
X1012791Y157596D01*
G01X1005735Y157018D02*
X1009735D01*
G01X1012791Y157596D02*
X1013363Y157024D01*
X1015275D01*
G01X1009801Y167278D02*
X1005709D01*
X1005699Y167268D01*
G01X1020645Y190499D02*
X1018488D01*
X1018165Y190176D01*
G01X1010388Y189009D02*
X1011809Y190430D01*
X1013104D01*
X1013358Y190176D01*
X1015015D01*
G01X1015645Y199076D02*
X1013989D01*
X1013966Y199099D01*
X1010820D01*
X1010030Y198309D01*
X1009096D01*
X1009080Y198293D01*
X1008120D01*
G01X1010976Y195562D02*
X1011424Y195114D01*
X1015652D01*
G01X1011320Y202169D02*
X1011890D01*
X1013144Y203423D01*
X1013620D01*
G01X1019530Y226423D02*
X1016770D01*
G01X1025609Y286776D02*
Y288484D01*
X1021118Y292975D01*
Y294290D01*
G01D02*
Y296159D01*
X1019939Y297338D01*
G01X1015520Y302862D02*
X1018060Y300322D01*
Y294132D01*
X1023640Y288552D01*
Y287744D01*
G01X1017163Y367963D02*
Y366963D01*
X1014895Y364695D01*
Y363222D01*
G01X1011313Y363356D02*
Y366525D01*
X1009883Y367955D01*
G01X1015483Y376725D02*
X1015480Y376722D01*
Y375991D01*
X1016908Y374563D01*
Y368218D01*
X1017163Y367963D01*
G01X1017452Y376725D02*
Y375788D01*
X1019300Y373940D01*
Y371830D01*
G01X1019420Y376725D02*
Y376088D01*
X1023762Y371746D01*
Y370425D01*
G01X1011546Y376725D02*
Y372676D01*
X1010736Y371866D01*
G01X1013168Y374810D02*
Y368145D01*
G01X1024783Y402962D02*
X1025525Y403704D01*
X1030081D01*
X1037303Y410926D01*
X1040054D01*
X1040909Y411781D01*
Y418144D01*
X1040054Y418999D01*
X1039065D01*
G01X1016468Y404284D02*
X1018870D01*
X1021992Y407406D01*
X1026005D01*
X1031065Y412466D01*
Y418999D01*
G01X1015483Y407237D02*
Y408495D01*
X1017220Y410232D01*
Y411662D01*
X1019250Y413692D01*
X1023330D01*
G01X1013515Y407237D02*
Y411758D01*
X1016119Y414362D01*
X1016520D01*
G01X1019420Y407237D02*
Y408044D01*
X1019930Y408554D01*
X1024972D01*
X1028330Y411912D01*
Y413692D01*
G01X1017452Y407237D02*
Y408592D01*
X1018588Y409728D01*
X1023397D01*
X1026065Y412396D01*
Y418999D01*
G01X1021344Y512574D02*
X1026372Y517602D01*
X1034511D01*
X1035326Y518417D01*
X1038130D01*
G01X1039185Y523642D02*
Y525237D01*
X1037470Y526952D01*
X1023500D01*
X1020392Y523844D01*
Y521826D01*
G01D02*
X1021344Y520874D01*
Y517728D01*
G01X1012769Y766798D02*
X1008191D01*
G01X1024333Y994357D02*
X1019983D01*
G01X1037891Y1252034D02*
X1031497D01*
X1029806Y1250343D01*
X1027536D01*
G01X1021181D02*
X1016481D01*
X1014790Y1252034D01*
X1008191D01*
G01X1024333Y1255381D02*
X1019983D01*
G01X1024333Y1252034D02*
X1019983D01*
G01X1024333Y1248688D02*
X1019983D01*
G01X1023640Y286776D02*
Y287744D01*
G01X1028758Y286776D02*
Y290581D01*
X1028577Y291018D01*
G01X1021881Y381154D02*
X1022449D01*
X1024922Y378681D01*
Y377465D01*
X1027030Y375357D01*
Y374102D01*
X1029239Y371893D01*
G01D02*
X1029922Y371210D01*
Y365744D01*
G01X1025958Y365739D02*
Y373708D01*
X1025004Y374662D01*
G01X1021881Y379186D02*
X1022423D01*
X1022924Y378685D01*
Y376742D01*
X1025004Y374662D01*
G01X1032765Y379281D02*
X1037886D01*
X1042334Y383729D01*
G01X1033211Y380687D02*
X1034292D01*
X1037334Y383729D01*
G01X1031547Y395623D02*
X1037075D01*
X1037693Y396241D01*
X1040871D01*
X1043386Y398756D01*
X1044952D01*
G01X1031946Y392151D02*
X1032508D01*
X1036659Y388000D01*
G01X1031568Y393809D02*
X1035850D01*
X1036659Y393000D01*
G01X1030991Y398792D02*
X1034947D01*
X1037956Y401801D01*
X1040425D01*
X1042687Y404063D01*
G01X1030617Y402393D02*
X1037346Y409122D01*
X1041748D01*
X1043330Y410704D01*
Y413692D01*
G01X1021881Y402808D02*
X1022821D01*
X1024996Y404983D01*
X1028764D01*
X1037473Y413692D01*
X1038330D01*
G01X1021881Y404776D02*
X1022825D01*
X1024207Y406158D01*
X1027338D01*
X1033330Y412150D01*
Y413692D01*
G01X1031705Y397039D02*
X1036278D01*
X1037995Y398756D01*
X1039952D01*
G01X1026370Y503562D02*
X1027705Y502227D01*
X1033268D01*
G01X1030853Y514176D02*
Y511039D01*
X1032155Y509737D01*
G01D02*
X1033268Y508624D01*
Y505377D01*
G01X1024200Y510362D02*
Y512192D01*
X1026184Y514176D01*
X1027703D01*
G01X1025530Y519627D02*
X1027703Y521800D01*
Y523628D01*
G01X1030853Y514176D02*
X1036449D01*
X1036455Y514182D01*
G01X1036035Y523642D02*
X1030867D01*
X1030853Y523628D01*
G01X1033040Y519852D02*
X1030853Y522039D01*
Y523628D01*
G01X1033441Y766798D02*
X1037891D01*
G01X1028683Y957546D02*
X1024333D01*
G01X1028683Y954200D02*
X1024333D01*
G01Y1057940D02*
X1027603D01*
X1028569Y1056974D01*
X1030049D01*
X1031511Y1058436D01*
Y1059066D01*
X1032221Y1059776D01*
X1033962D01*
X1034458Y1059613D01*
G01X1042663D02*
X1044838D01*
X1045349Y1059102D01*
Y1058429D01*
X1046017Y1057761D01*
X1047249D01*
X1048245Y1058757D01*
X1049403D01*
X1050220Y1057940D01*
X1054033D01*
G01X1030830Y1261302D02*
Y1260422D01*
X1029135Y1258727D01*
X1024333D01*
G01X1030270Y1256042D02*
X1030931Y1255381D01*
X1037891D01*
G01X1030780Y1266532D02*
Y1264642D01*
X1033348Y1262074D01*
X1037891D01*
G01X1059590Y365631D02*
X1055216D01*
X1052705Y363120D01*
G01X1049186Y518058D02*
X1053304D01*
X1055970Y515392D01*
Y505962D01*
X1053410Y503402D01*
G01D02*
X1052260Y502252D01*
X1045654D01*
X1045563Y502161D01*
G01X1049186Y512644D02*
X1041143D01*
X1039605Y514182D01*
G01X1038130Y518417D02*
X1039605Y516942D01*
Y514182D01*
G01X1039185Y523642D02*
X1041610Y521217D01*
Y520562D01*
X1046968Y515204D01*
X1049186D01*
G01X1045760Y596272D02*
X1047310D01*
X1050220Y593362D01*
X1063996D01*
X1084349Y579762D01*
X1149655D01*
X1165547Y563870D01*
X1165682D01*
X1221430Y508122D01*
X1385770D01*
X1392685Y501207D01*
Y498992D01*
G01X1054033Y1057940D02*
X1054034Y1057941D01*
X1060219D01*
X1061894Y1056266D01*
X1064172D01*
G01X1070949D02*
X1075710D01*
X1077384Y1057940D01*
X1083733D01*
G01X1037891Y1252034D02*
X1044308D01*
X1045999Y1250343D01*
X1050881D01*
G01X1057236D02*
X1061399D01*
X1063090Y1252034D01*
X1067591D01*
G01X1047010Y1259222D02*
Y1258322D01*
X1049951Y1255381D01*
X1054033D01*
G01X1044930Y1263492D02*
Y1257462D01*
X1050358Y1252034D01*
X1054033D01*
G01X1049683Y1258727D02*
X1054033D01*
G01X1063330Y374293D02*
Y382062D01*
G01X1069580Y386723D02*
Y382191D01*
X1069630Y382141D01*
G01X1063330Y382062D02*
X1069551D01*
X1069630Y382141D01*
G01X1076598Y477087D02*
Y487431D01*
X1075968Y488061D01*
X1074010D01*
X1073500Y488571D01*
Y490061D01*
X1074010Y490571D01*
X1075968D01*
X1076478Y491081D01*
Y494250D01*
X1083177Y500949D01*
Y510108D01*
X1080641Y512644D01*
X1066312D01*
G01X1081930Y477132D02*
Y478902D01*
X1078978Y481854D01*
Y493214D01*
X1085677Y499913D01*
Y511144D01*
X1081617Y515204D01*
X1066312D01*
G01X1063141Y766798D02*
X1067591D01*
G01X1058383Y957546D02*
X1054033D01*
G01X1058383Y954200D02*
X1054033D01*
G01X1058383Y994357D02*
X1054033D01*
G01X1097291Y1252034D02*
X1091338D01*
X1089647Y1250343D01*
X1086936D01*
G01X1080581D02*
X1074389D01*
X1072698Y1252034D01*
X1067591D01*
G01X1054033Y1248688D02*
X1058383D01*
G01X1059410Y1252272D02*
Y1253966D01*
X1060825Y1255381D01*
X1067591D01*
G01Y1262074D02*
X1061330D01*
G01X1075430Y68192D02*
Y64622D01*
X1076890Y63162D01*
X1079225D01*
G01Y59422D02*
X1075700D01*
X1072140Y62982D01*
Y68782D01*
X1076040Y72682D01*
X1079240D01*
G01X1082264Y83698D02*
Y78553D01*
G01X1087316Y78461D02*
X1082356D01*
X1082264Y78553D01*
G01X1079240Y72682D02*
X1081910D01*
X1084730Y75502D01*
X1094810D01*
X1096240Y76932D01*
Y81752D01*
X1091730Y86262D01*
X1081678D01*
X1079114Y83698D01*
G01X1436050Y321352D02*
X1429256D01*
X1401708Y348900D01*
X1207462D01*
X1190292Y331730D01*
X1115168D01*
X1084130Y300692D01*
Y298342D01*
G01X1094685Y379251D02*
X1092224Y381712D01*
X1083720D01*
X1083185Y381177D01*
Y379251D01*
G01X1094625Y374131D02*
X1092244Y376512D01*
X1083660D01*
X1083125Y375977D01*
Y374131D01*
G01X1094565Y369061D02*
X1092194Y371432D01*
X1083820D01*
X1083065Y370677D01*
Y369061D01*
G01X1077582Y390962D02*
Y383925D01*
X1075798Y382141D01*
X1072780D01*
G01X1088083Y957546D02*
X1083733D01*
G01X1088083Y954200D02*
X1083733D01*
G01Y994357D02*
X1079383D01*
G01X1083733Y1057940D02*
X1087379D01*
X1089053Y1056266D01*
X1094005D01*
G01X1100709D02*
X1103588D01*
X1105262Y1057940D01*
X1113433D01*
G01X1076520Y1259072D02*
X1080211Y1255381D01*
X1083733D01*
G01X1074480Y1263742D02*
Y1257562D01*
X1080008Y1252034D01*
X1083733D01*
G01Y1248688D02*
X1088083D01*
G01X1079383Y1258727D02*
X1083733D01*
G01X1086457Y1644450D02*
X1086482Y1644425D01*
X1091457D01*
G01X1084394Y1650210D02*
X1086457Y1648147D01*
Y1644450D01*
G01X1084000Y1647110D02*
X1084394Y1647504D01*
Y1650210D01*
G01X1071957Y1659450D02*
X1071940Y1659433D01*
Y1655790D01*
X1073780Y1653950D01*
X1076520D01*
G01X1071957Y1659450D02*
X1071940Y1659467D01*
Y1662330D01*
X1073560Y1663950D01*
X1076382D01*
G01X1088673Y55682D02*
X1091772D01*
X1096272Y60182D01*
G01D02*
X1100772Y55682D01*
X1103880D01*
X1104057Y55505D01*
G01X1105423Y77559D02*
X1103766Y75902D01*
X1099861D01*
G01X1092381Y78461D02*
X1087316D01*
G01X1099861Y73343D02*
X1101240D01*
X1102317Y72266D01*
X1105316D01*
G01X1100630Y130376D02*
X1137883D01*
X1154602Y147095D01*
X1197920D01*
X1201551Y143464D01*
Y129448D01*
X1205605Y125394D01*
X1220888D01*
X1223337Y122945D01*
X1230643D01*
X1233331Y125633D01*
X1247115Y134843D01*
X1253879Y141607D01*
X1256862D01*
X1265967Y150712D01*
X1268194D01*
X1272334Y154852D01*
G01X1436120Y315772D02*
X1429838D01*
X1400244Y345366D01*
X1208926D01*
X1191756Y328196D01*
X1117104D01*
X1089130Y300222D01*
Y298342D01*
G01X1436270Y312592D02*
X1436217Y312539D01*
X1430572D01*
X1399512Y343599D01*
X1209658D01*
X1192488Y326429D01*
X1117907D01*
X1091630Y300152D01*
Y298342D01*
G01X1436120Y318272D02*
X1429837D01*
X1400976Y347133D01*
X1208194D01*
X1191024Y329963D01*
X1116431D01*
X1086630Y300162D01*
Y298342D01*
G01X1436335Y309407D02*
X1431205D01*
X1398780Y341832D01*
X1210390D01*
X1193220Y324662D01*
X1120450D01*
X1094130Y298342D01*
G01X1109429Y379235D02*
X1101500D01*
G01D02*
X1094701D01*
X1094685Y379251D01*
G01X1109429Y374235D02*
X1101500D01*
G01D02*
X1094729D01*
X1094625Y374131D01*
G01X1109429Y369235D02*
X1101500D01*
G01D02*
X1094739D01*
X1094565Y369061D01*
G01X1092709Y766775D02*
X1092732Y766798D01*
X1097291D01*
G01X1126991Y1252034D02*
X1121198D01*
X1119507Y1250343D01*
X1116636D01*
G01X1110131D02*
X1107920Y1248132D01*
X1105170D01*
X1101268Y1252034D01*
X1097291D01*
G01X1088262Y1252293D02*
Y1253118D01*
X1090525Y1255381D01*
X1097291D01*
G01X1091000Y1262074D02*
X1097291D01*
G01X1099457Y1644425D02*
X1103457D01*
G01X1094575D02*
X1091457D01*
G01X1094575D02*
X1095457D01*
G01X1092617Y1650635D02*
Y1646383D01*
X1094575Y1644425D01*
G01X1100097Y1661265D02*
X1102272D01*
X1105457Y1664450D01*
G01X1100097Y1650635D02*
Y1649810D01*
X1100657Y1649250D01*
X1105557D01*
G01X1109287Y1673015D02*
Y1675913D01*
X1103010Y1682190D01*
X1093600D01*
X1091880Y1680470D01*
Y1673720D01*
G01X1107207Y55505D02*
X1110977D01*
G01X1104097Y60028D02*
Y55545D01*
X1104057Y55505D01*
G01X1110444Y77559D02*
X1105423D01*
G01X1109020Y80592D02*
X1109190D01*
X1110444Y79338D01*
Y77559D01*
G01X1105316Y72266D02*
X1109907D01*
X1110444Y72803D01*
G01X1105580Y132822D02*
X1105940Y133182D01*
X1111591D01*
X1112101Y133692D01*
Y136652D01*
X1112611Y137162D01*
X1114601D01*
X1115111Y136652D01*
Y133692D01*
X1115621Y133182D01*
X1117611D01*
X1118121Y133692D01*
Y136652D01*
X1118631Y137162D01*
X1120621D01*
X1121131Y136652D01*
Y133692D01*
X1121641Y133182D01*
X1123631D01*
X1124141Y133692D01*
Y136652D01*
X1124651Y137162D01*
X1126641D01*
X1127151Y136652D01*
Y133692D01*
X1127661Y133182D01*
X1136120D01*
X1139729Y136791D01*
Y137513D01*
X1137901Y139341D01*
Y140063D01*
X1139308Y141470D01*
X1140030D01*
X1141858Y139642D01*
X1142580D01*
X1152400Y149462D01*
X1208360D01*
X1210360Y151462D01*
X1223550D01*
X1224160Y150852D01*
X1230408D01*
X1230691Y151135D01*
X1236733D01*
X1239340Y153742D01*
X1243184D01*
X1244134Y152792D01*
X1246943D01*
X1254363Y160212D01*
X1255843D01*
X1259546Y163915D01*
X1261567Y164752D01*
X1263814Y165683D01*
X1267545Y169414D01*
X1269938Y170406D01*
X1269981Y170424D01*
G01X1117783Y957546D02*
X1113433D01*
G01X1117783Y954200D02*
X1113433D01*
G01X1117783Y994357D02*
X1113433D01*
G01Y1057940D02*
X1117783D01*
G01X1103530Y1263602D02*
Y1262962D01*
X1111111Y1255381D01*
X1113433D01*
G01X1106740Y1267902D02*
Y1262602D01*
X1110615Y1258727D01*
X1113433D01*
G01X1106200Y1250162D02*
X1108072Y1252034D01*
X1113433D01*
G01Y1248688D02*
X1117783D01*
G01X1115802Y1617695D02*
Y1615010D01*
G01X1117182Y1625460D02*
X1120317D01*
X1120432Y1625345D01*
G01X1120472Y1620835D02*
X1115812D01*
X1115802Y1620845D01*
G01X1103457Y1644425D02*
X1104847D01*
X1105557Y1645135D01*
Y1649250D01*
G01X1103457Y1641275D02*
X1106480D01*
G01X1105457Y1664450D02*
Y1669875D01*
G01D02*
X1105549Y1669967D01*
X1107536D01*
X1107547Y1669956D01*
X1109196D01*
X1109287Y1669865D01*
G01X1113110Y1666460D02*
Y1668230D01*
X1113140Y1668260D01*
Y1669916D01*
G01D02*
X1112386D01*
X1109287Y1673015D01*
G01X1124578Y56545D02*
X1127973Y59940D01*
X1130163D01*
G01D02*
X1132177Y57926D01*
X1138512D01*
G01X1124678Y60545D02*
X1128997Y64864D01*
X1132547D01*
G01D02*
X1134485Y62926D01*
X1138512D01*
G01X1129997Y69864D02*
X1131935Y67926D01*
X1138512D01*
G01X1124678Y64545D02*
X1129997Y69864D01*
G01X1120190Y255652D02*
X1121120D01*
X1141166Y235606D01*
X1168954D01*
X1178040Y244692D01*
X1197400D01*
G01X1125409Y305797D02*
X1140527Y320915D01*
X1193844D01*
X1203681Y330752D01*
X1259141D01*
X1281104Y308789D01*
X1293486D01*
X1296539Y311842D01*
X1308581D01*
X1312313Y308110D01*
X1374981D01*
X1429267Y253824D01*
X1435880D01*
G01X1129901Y374235D02*
X1145500D01*
G01X1147700Y368041D02*
X1146506Y369235D01*
X1129901D01*
G01X1147700Y362731D02*
X1146196Y364235D01*
X1129901D01*
G01X1122541Y766798D02*
X1126991D01*
G01X1156691Y1252034D02*
X1150698D01*
X1149007Y1250343D01*
X1146336D01*
G01X1139981D02*
X1133839D01*
X1132148Y1252034D01*
X1126991D01*
G01X1133200Y1255702D02*
X1132879Y1255381D01*
X1126991D01*
G01X1120800Y1262074D02*
X1126991D01*
G01X1130294Y1448502D02*
X1131195Y1447601D01*
Y1442908D01*
X1132662Y1441441D01*
Y1439667D01*
G01X1135975Y1597630D02*
X1132730D01*
X1131220Y1599140D01*
G01D02*
X1133710Y1601630D01*
X1135975D01*
G01X1134512Y1623410D02*
X1129822D01*
X1127802Y1625430D01*
X1124857D01*
X1124762Y1625335D01*
G01D02*
X1124752Y1625345D01*
X1120432D01*
G01X1124862Y1620825D02*
X1120482D01*
X1120472Y1620835D01*
G01X1124862Y1620825D02*
X1124888Y1620851D01*
X1129620D01*
G01D02*
X1134512D01*
G01X1144620Y221652D02*
Y188162D01*
X1146355Y186427D01*
X1150954D01*
X1150964Y186437D01*
X1152720D01*
G01X1151945Y211231D02*
Y209897D01*
X1150806Y208758D01*
X1148330D01*
X1147722Y208150D01*
Y206345D01*
G01X1153264Y204887D02*
X1149180D01*
X1147722Y206345D01*
G01X1150704Y230157D02*
X1146717D01*
X1146670Y230110D01*
G01X1144620Y221652D02*
Y223062D01*
X1147620Y226062D01*
X1150402D01*
X1153320Y228980D01*
Y230100D01*
X1153263Y230157D01*
G01X1150505Y363231D02*
X1150005Y362731D01*
X1147700D01*
G01X1145500Y374235D02*
X1149431D01*
X1150435Y373231D01*
G01Y368041D02*
X1147700D01*
G01X1147483Y957546D02*
X1143133D01*
G01X1147483Y954200D02*
X1143133D01*
G01Y994357D02*
X1138783D01*
G01X1143133Y1057940D02*
X1145093D01*
X1146039Y1056994D01*
X1148869D01*
X1150311Y1058436D01*
Y1059066D01*
X1150858Y1059613D01*
X1153376D01*
G01X1160017D02*
X1163638D01*
X1164149Y1059102D01*
Y1058429D01*
X1164817Y1057761D01*
X1166049D01*
X1167045Y1058757D01*
X1168203D01*
X1169020Y1057940D01*
X1172833D01*
G01X1138783Y1255381D02*
X1143133D01*
G01X1138783Y1252034D02*
X1143133D01*
G01Y1248688D02*
X1147483D01*
G01X1148563Y1257097D02*
X1150279Y1255381D01*
X1156691D01*
G01X1138783Y1258727D02*
X1143133D01*
G01X1150400Y1262074D02*
X1156691D01*
G01X1184200Y1602700D02*
X1184694D01*
X1192559Y1594835D01*
Y1523109D01*
X1189590Y1520140D01*
X1186080D01*
X1184030Y1518090D01*
X1147670D01*
X1143622Y1522138D01*
Y1528937D01*
G01X1184200Y1599900D02*
X1190700Y1593400D01*
Y1525811D01*
X1189359Y1524470D01*
X1187470D01*
X1183220Y1520220D01*
X1149440D01*
X1147559Y1522101D01*
Y1528937D01*
G01X1150380Y1602590D02*
Y1599280D01*
X1146110Y1595010D01*
X1137850D01*
X1135975Y1596885D01*
Y1597630D01*
G01X1139125Y1601630D02*
Y1602705D01*
X1140750Y1604330D01*
G01D02*
X1141931Y1605511D01*
X1145335D01*
G01X1141992Y1625969D02*
Y1623410D01*
G01Y1625969D02*
Y1627971D01*
X1144899Y1630878D01*
G01D02*
Y1628350D01*
X1146969Y1626280D01*
X1149107D01*
G01X1159378Y52926D02*
X1164131D01*
X1168316Y57111D01*
G01X1159378Y62926D02*
X1165411D01*
X1168296Y65811D01*
G01X1159378Y57926D02*
X1164911D01*
X1168296Y61311D01*
G01X1152720Y183287D02*
X1156720D01*
G01X1152720D02*
Y180862D01*
G01X1158382Y197407D02*
Y195168D01*
X1159460Y194090D01*
G01X1155823Y197407D02*
Y192102D01*
G01X1160720Y186437D02*
X1156720D01*
G01X1155823Y192102D02*
Y188990D01*
X1156720Y188093D01*
Y186437D01*
G01X1153264Y204887D02*
Y202866D01*
X1153740Y202390D01*
X1155180D01*
X1155823Y203033D01*
Y204887D01*
G01X1157445Y211370D02*
Y216982D01*
G01D02*
Y221054D01*
X1155822Y222677D01*
G01D02*
Y224438D01*
X1155120Y225140D01*
X1153820D01*
X1153263Y224583D01*
Y222677D01*
G01X1449600Y396737D02*
Y384511D01*
X1440614Y375525D01*
X1190110D01*
X1175866Y361281D01*
X1159753D01*
G01X1152241Y766798D02*
X1156691D01*
G01Y1252034D02*
X1163428D01*
X1165119Y1250343D01*
X1169681D01*
G01X1176036D02*
X1180079D01*
X1181770Y1252034D01*
X1186391D01*
G01X1169460Y1606630D02*
X1168020Y1608070D01*
X1163839D01*
G01X1169460Y1616630D02*
X1166019Y1613189D01*
X1163839D01*
G01X1169460Y1611630D02*
X1168460Y1610630D01*
X1163839D01*
G01X1158030Y1619250D02*
X1156086Y1621194D01*
Y1622340D01*
G01X1159236Y1630090D02*
X1163570D01*
X1164830Y1628830D01*
G01D02*
X1167456Y1626204D01*
X1169169D01*
G01Y1628173D02*
X1168337D01*
X1165100Y1631410D01*
Y1633450D01*
G01X1169169Y1622267D02*
X1165947D01*
X1164280Y1620600D01*
X1163970D01*
G01D02*
X1163760D01*
X1162020Y1622340D01*
X1159236D01*
G01X1164000Y1625720D02*
X1161534D01*
X1161034Y1626220D01*
X1159236D01*
G01X1164000Y1625720D02*
X1165484Y1624236D01*
X1169169D01*
G01X1159930Y1651290D02*
X1157835Y1649195D01*
Y1643090D01*
X1158325Y1642600D01*
G01D02*
X1160850D01*
G01X1165100Y1633450D02*
X1164300D01*
X1163750Y1634000D01*
X1159356D01*
X1159236Y1633880D01*
G01X1164830Y1651290D02*
X1167035Y1649085D01*
Y1644030D01*
X1165605Y1642600D01*
X1164000D01*
G01X1159930Y1660690D02*
X1157825Y1658585D01*
Y1653420D01*
X1159930Y1651315D01*
Y1651290D01*
G01X1161230Y1665575D02*
Y1663647D01*
X1159930Y1662347D01*
Y1660690D01*
G01X1163789Y1665575D02*
Y1663819D01*
X1164830Y1662778D01*
Y1660690D01*
G01D02*
X1162383Y1658243D01*
Y1652505D01*
G01D02*
X1163598Y1651290D01*
X1164830D01*
G01X1161230Y1673055D02*
X1158671D01*
G01X1158825Y1678062D02*
X1162988D01*
X1163576Y1677474D01*
G01X1158671Y1673055D02*
Y1677908D01*
X1158825Y1678062D01*
G01X1157700Y1681100D02*
X1160100Y1683500D01*
X1164500D01*
X1166000Y1682000D01*
Y1669600D01*
X1163789Y1667389D01*
Y1665575D01*
G01X1177234Y59978D02*
Y56238D01*
X1175374Y54378D01*
X1169108D01*
X1168316Y55170D01*
Y57111D01*
G01X1168296Y65811D02*
Y69930D01*
X1169754Y71388D01*
X1170665D01*
G01D02*
X1181449D01*
X1182396Y70441D01*
Y65811D01*
G01X1177310Y65769D02*
X1175222Y63681D01*
X1169034D01*
X1168296Y62943D01*
Y61311D01*
G01X1182496D02*
X1181768D01*
X1177310Y65769D01*
G01X1182416Y57111D02*
X1180101D01*
X1177234Y59978D01*
G01X1181420Y157962D02*
X1181476Y158018D01*
Y163731D01*
G01X1173314Y176452D02*
X1173374Y176392D01*
Y173206D01*
G01X1178820Y186174D02*
Y190174D01*
G01X1181700Y186962D02*
Y188762D01*
X1180288Y190174D01*
X1178820D01*
G01Y198174D02*
Y194174D01*
G01X1184510Y188962D02*
X1184032D01*
X1178820Y194174D01*
G01Y206174D02*
Y202174D01*
G01X1183460Y205342D02*
Y203792D01*
X1181842Y202174D01*
X1178820D01*
G01Y214174D02*
Y210174D01*
G01X1181470Y208802D02*
X1180098Y210174D01*
X1178820D01*
G01Y222174D02*
Y218174D01*
G01X1181500Y222162D02*
X1181488Y222174D01*
X1178820D01*
G01X1635835Y343002D02*
X1628981Y336148D01*
X1455717D01*
X1418995Y372870D01*
X1192930D01*
X1175422Y355362D01*
X1174120D01*
G01X1223327Y757615D02*
Y760965D01*
X1220027Y764265D01*
X1181473D01*
X1176250Y759042D01*
Y713732D01*
X1204560Y685422D01*
Y534922D01*
X1228120Y511362D01*
X1255920D01*
G01X1186391Y766798D02*
X1181941D01*
G01X1177183Y957546D02*
X1172833D01*
G01X1177183Y954200D02*
X1172833D01*
G01X1177183Y994357D02*
X1172833D01*
G01Y1057940D02*
X1172834Y1057941D01*
X1178174D01*
X1179846Y1059613D01*
X1183018D01*
G01X1189754D02*
X1192055D01*
X1193728Y1057940D01*
X1202533D01*
G01X1168483Y1255381D02*
X1172833D01*
G01X1168483Y1252034D02*
X1172833D01*
G01Y1248688D02*
X1177120D01*
G01X1177222Y1255567D02*
X1177262Y1255527D01*
X1180642D01*
X1180788Y1255381D01*
X1186391D01*
G01X1168483Y1258727D02*
X1172833D01*
G01X1179180Y1265872D02*
Y1263962D01*
X1181068Y1262074D01*
X1186391D01*
G01X1168437Y1448502D02*
X1169338Y1447601D01*
Y1442908D01*
X1170805Y1441441D01*
Y1439667D01*
G01X1178996Y1612960D02*
X1175335D01*
G01X1174550Y1615630D02*
Y1613745D01*
X1175335Y1612960D01*
G01X1178250Y1609100D02*
X1175455D01*
G01X1172305Y1605100D02*
X1172265Y1605140D01*
X1170950D01*
X1169460Y1606630D01*
G01X1175455Y1605100D02*
Y1601100D01*
G01X1178140D02*
X1175455D01*
G01X1172185Y1612960D02*
Y1613044D01*
X1170750Y1614479D01*
Y1615340D01*
X1169460Y1616630D01*
G01X1172305Y1609100D02*
X1172265Y1609140D01*
X1171950D01*
X1169460Y1611630D01*
G01X1182146Y1612960D02*
X1185930D01*
X1186790Y1613820D01*
G01X1171728Y1619708D02*
Y1618422D01*
X1172630Y1617520D01*
X1176650D01*
X1178940Y1615230D01*
X1185380D01*
X1186790Y1613820D01*
G01X1180325Y1642600D02*
X1182850D01*
G01X1181930Y1651290D02*
X1179843Y1649203D01*
Y1643082D01*
X1180325Y1642600D01*
G01X1169325D02*
X1171850D01*
G01X1170930Y1651290D02*
X1168835Y1649195D01*
Y1643090D01*
X1169325Y1642600D01*
G01X1175830Y1651290D02*
X1178035Y1649085D01*
Y1644030D01*
X1176605Y1642600D01*
X1175000D01*
G01X1181930Y1660690D02*
X1179825Y1658585D01*
Y1653420D01*
X1181930Y1651315D01*
Y1651290D01*
G01Y1660690D02*
Y1662347D01*
X1183230Y1663647D01*
Y1665575D01*
G01X1170930Y1660690D02*
X1168825Y1658585D01*
Y1653420D01*
X1170930Y1651315D01*
Y1651290D01*
G01X1172230Y1665575D02*
Y1663647D01*
X1170930Y1662347D01*
Y1660690D01*
G01X1174789Y1665575D02*
Y1663819D01*
X1175830Y1662778D01*
Y1660690D01*
G01D02*
X1173383Y1658243D01*
Y1652505D01*
G01D02*
X1174598Y1651290D01*
X1175830D01*
G01X1180825Y1678062D02*
X1184988D01*
X1185576Y1677474D01*
G01X1183230Y1673055D02*
X1180671D01*
G01X1180825Y1678062D02*
X1180671Y1677908D01*
Y1673055D01*
G01X1172230D02*
X1169671D01*
G01D02*
Y1677908D01*
X1169825Y1678062D01*
G01D02*
X1173988D01*
X1174576Y1677474D01*
G01X1197520Y56962D02*
Y59262D01*
X1199420Y61162D01*
X1204084D01*
X1204186Y61060D01*
G01X1185400Y104000D02*
X1192825D01*
X1195225Y101600D01*
G01X1198375D02*
Y97400D01*
G01D02*
Y93200D01*
G01D02*
Y89000D01*
G01Y101600D02*
X1202200D01*
X1203050Y100750D01*
G01X1195278Y139124D02*
X1191206D01*
G01X1187413Y143132D02*
X1191206Y139339D01*
Y139124D01*
G01X1197414Y161592D02*
X1200784Y164962D01*
X1208518D01*
G01X1191020Y170862D02*
X1200584D01*
X1201333Y171611D01*
X1209944D01*
G01X1198563Y212648D02*
X1200963D01*
G01X1188600Y225962D02*
X1190200Y224362D01*
X1192419D01*
X1206344Y210437D01*
X1207220D01*
G01X1202533Y957546D02*
X1198183D01*
G01X1202533Y954200D02*
X1198183D01*
G01Y994357D02*
X1202533D01*
G01X1186391Y1252034D02*
X1193298D01*
X1194989Y1250343D01*
X1199381D01*
G01X1205736D02*
X1209944D01*
X1211635Y1252034D01*
X1216091D01*
G01X1193590Y1267912D02*
X1193320Y1267642D01*
Y1260032D01*
X1197971Y1255381D01*
X1202533D01*
G01X1195470Y1262802D02*
Y1260862D01*
X1197605Y1258727D01*
X1202533D01*
G01X1198183Y1252034D02*
X1202533D01*
G01X1190895Y1642910D02*
X1193420D01*
G01X1192500Y1651600D02*
X1190313Y1649413D01*
Y1643492D01*
X1190895Y1642910D01*
G01X1197400Y1651600D02*
X1199483Y1649517D01*
Y1644052D01*
X1198341Y1642910D01*
X1196570D01*
G01X1201600Y1633790D02*
Y1637880D01*
X1196570Y1642910D01*
G01X1186830Y1651290D02*
X1188925Y1649195D01*
Y1643710D01*
X1187815Y1642600D01*
X1186000D01*
G01D02*
Y1640000D01*
G01X1192500Y1651600D02*
X1190395Y1653705D01*
Y1658895D01*
X1192500Y1661000D01*
G01D02*
Y1662657D01*
X1193800Y1663957D01*
Y1664029D01*
X1193900Y1664129D01*
Y1665885D01*
G01X1197400Y1661000D02*
X1194953Y1658553D01*
Y1652815D01*
X1196168Y1651600D01*
X1197400D01*
G01X1196459Y1665885D02*
Y1664029D01*
X1197400Y1663088D01*
Y1661000D01*
G01X1186830Y1660690D02*
X1184383Y1658243D01*
Y1652505D01*
G01D02*
X1185598Y1651290D01*
X1186830D01*
G01X1185789Y1665575D02*
Y1663819D01*
X1186830Y1662778D01*
Y1660690D01*
G01X1191395Y1678372D02*
X1195558D01*
X1196146Y1677784D01*
G01X1193900Y1673365D02*
X1191341D01*
G01D02*
Y1676062D01*
X1191395Y1676116D01*
Y1678372D01*
G01X1192340Y1706480D02*
X1190235Y1704375D01*
Y1699210D01*
X1192340Y1697105D01*
Y1697080D01*
G01X1190735Y1688390D02*
X1193260D01*
G01X1190735D02*
X1190245Y1688880D01*
Y1694885D01*
X1192340Y1696980D01*
Y1697080D01*
G01X1194793Y1698295D02*
X1196008Y1697080D01*
X1197240D01*
G01D02*
X1199445Y1694875D01*
Y1689820D01*
X1198015Y1688390D01*
X1196410D01*
G01X1192340Y1706480D02*
Y1708137D01*
X1193640Y1709437D01*
Y1711365D01*
G01X1197240Y1706480D02*
X1194793Y1704033D01*
Y1698295D01*
G01X1196199Y1711365D02*
Y1709609D01*
X1197240Y1708568D01*
Y1706480D01*
G01X1191235Y1723852D02*
X1195398D01*
X1195986Y1723264D01*
G01X1191081Y1718845D02*
Y1723698D01*
X1191235Y1723852D01*
G01X1193640Y1718845D02*
X1191081D01*
G01X1207336Y57130D02*
Y61060D01*
G01X1223507Y61580D02*
X1215070D01*
G01D02*
X1207856D01*
X1207336Y61060D01*
G01X1209735Y87140D02*
X1204470D01*
X1203700Y87910D01*
Y89400D01*
G01X1211775Y93600D02*
X1216425D01*
G01X1211775D02*
Y96375D01*
X1213500Y98100D01*
Y106600D01*
X1212560Y107540D01*
X1208885D01*
G01X1203700Y89400D02*
Y90200D01*
X1204400Y90900D01*
X1215500D01*
X1216425Y91825D01*
Y93600D01*
G01X1203050Y100750D02*
X1203740Y100060D01*
X1208885D01*
G01X1212202Y120692D02*
X1213432Y119462D01*
X1217018D01*
G01X1215763Y114363D02*
X1212584Y117542D01*
X1212202D01*
G01X1217018Y132962D02*
X1206114D01*
G01X1211668Y164962D02*
X1214091D01*
G01D02*
X1217018D01*
G01Y153962D02*
X1214415D01*
G01X1217018Y176962D02*
X1211668D01*
G01X1213094Y171611D02*
X1214122D01*
X1215456Y172945D01*
X1217004D01*
G01X1200720Y184862D02*
X1202220Y183362D01*
X1218914D01*
X1220314Y181962D01*
X1235484D01*
X1237292Y180154D01*
X1245805D01*
X1246634Y180983D01*
X1248474D01*
X1253339Y185848D01*
X1264944D01*
X1265020Y185772D01*
X1275998D01*
X1276074Y185848D01*
G01X1214054Y186092D02*
X1216388D01*
X1217018Y185462D01*
G01X1210795Y200309D02*
X1213720D01*
G01X1210795Y189362D02*
X1213720D01*
G01X1207645D02*
X1204220D01*
G01X1200720Y187862D02*
Y191272D01*
X1201310Y191862D01*
X1218634D01*
X1220168Y190328D01*
Y189462D01*
X1222848Y186782D01*
X1242026D01*
X1244226Y188982D01*
X1246657D01*
X1248143Y190468D01*
X1261049D01*
X1262450Y189067D01*
X1270888D01*
G01X1207530Y218977D02*
Y210747D01*
X1207220Y210437D01*
G01X1215720Y204862D02*
Y207287D01*
G01Y210437D02*
X1211720D01*
G01X1215720D02*
Y214292D01*
X1217428Y216000D01*
X1221330D01*
G01X1207530Y222127D02*
X1207525Y222132D01*
Y223877D01*
X1206660Y224742D01*
G01D02*
X1207525Y225607D01*
Y228495D01*
G01X1200550Y236592D02*
X1200590Y236552D01*
Y231532D01*
G01D02*
X1203290Y234232D01*
X1206850D01*
X1207525Y234907D01*
Y236369D01*
G01X1212643Y228495D02*
Y225689D01*
X1213540Y224792D01*
G01D02*
X1212643Y223895D01*
Y222260D01*
X1212610Y222227D01*
G01Y219077D02*
X1216610D01*
G01X1221330Y216000D02*
X1218253Y219077D01*
X1216610D01*
G01X1212643Y236369D02*
Y239985D01*
X1216656Y243998D01*
G01X1200550Y244692D02*
Y240672D01*
G01D02*
Y236592D01*
G01X1735010Y500178D02*
X1741136D01*
X1745680Y495634D01*
Y477422D01*
X1740020Y471762D01*
Y456008D01*
X1731954Y447942D01*
X1679786D01*
X1612666Y515062D01*
X1333910D01*
X1310690Y538282D01*
Y640360D01*
X1252008Y699042D01*
X1218676D01*
X1204902Y712816D01*
Y748695D01*
X1210288Y754081D01*
G01X1207607Y754095D02*
X1210017Y756505D01*
X1211087D01*
X1212410Y755182D01*
Y753318D01*
X1208920Y749828D01*
Y711429D01*
X1219447Y700902D01*
X1252779D01*
X1312550Y641131D01*
Y539053D01*
X1334681Y516922D01*
X1613437D01*
X1680557Y449802D01*
X1731182D01*
X1737981Y456601D01*
Y472751D01*
X1743820Y478590D01*
Y494862D01*
X1741770Y496912D01*
X1732120D01*
X1731120Y495912D01*
G01X1206432Y758995D02*
X1211257D01*
X1214380Y755872D01*
Y708600D01*
X1220218Y702762D01*
X1253550D01*
X1314410Y641902D01*
Y539824D01*
X1335452Y518782D01*
X1614208D01*
X1681328Y451662D01*
X1730410D01*
X1734420Y455672D01*
Y457893D01*
X1733910Y458403D01*
X1731130D01*
X1730620Y458913D01*
Y459903D01*
X1731130Y460413D01*
X1733910D01*
X1734420Y460923D01*
Y461913D01*
X1733910Y462423D01*
X1731130D01*
X1730620Y462933D01*
Y463923D01*
X1731130Y464433D01*
X1733910D01*
X1734420Y464943D01*
Y465933D01*
X1733910Y466443D01*
X1731130D01*
X1730620Y466953D01*
Y467943D01*
X1731130Y468453D01*
X1733910D01*
X1734420Y468963D01*
Y469953D01*
X1733910Y470463D01*
X1731130D01*
X1730620Y470973D01*
Y471963D01*
X1731130Y472473D01*
X1733910D01*
X1734420Y472983D01*
Y475672D01*
G01X1216091Y766798D02*
X1211641D01*
G01X1202533Y1057940D02*
X1208560D01*
X1210288Y1059668D01*
X1211521D01*
G01X1220819Y1059616D02*
X1221970D01*
X1222829Y1058757D01*
X1227596D01*
X1228413Y1057940D01*
X1232233D01*
G01X1206883Y1248688D02*
X1202533D01*
G01X1207048Y1255174D02*
X1208126Y1254096D01*
X1209099D01*
X1212203Y1255381D01*
X1216091D01*
G01X1208750Y1266546D02*
Y1264712D01*
X1210738Y1262724D01*
X1215441D01*
X1216091Y1262074D01*
G01X1203267Y1652910D02*
X1205820D01*
G01X1203267Y1656060D02*
Y1660513D01*
X1202200Y1661580D01*
G01X1207898Y1661115D02*
X1208000Y1661217D01*
Y1664050D01*
X1206880Y1665170D01*
X1203860D01*
X1202200Y1663510D01*
Y1661580D01*
G01X1206660Y1681767D02*
X1206656Y1681763D01*
Y1677873D01*
G01X1207898Y1668595D02*
X1205685D01*
X1203040Y1671240D01*
G01D02*
Y1674257D01*
X1206656Y1677873D01*
G01X1213910Y1706790D02*
X1211805Y1704685D01*
Y1699520D01*
X1213910Y1697415D01*
Y1697390D01*
G01D02*
X1211823Y1695303D01*
Y1689182D01*
X1212305Y1688700D01*
G01D02*
X1214830D01*
G01X1203110Y1697125D02*
X1201005Y1699230D01*
Y1704420D01*
X1203110Y1706525D01*
G01X1201505Y1688435D02*
X1204030D01*
G01X1203110Y1697125D02*
X1201063Y1695078D01*
Y1688877D01*
X1201505Y1688435D01*
G01X1213910Y1681773D02*
X1216657Y1684520D01*
X1217210D01*
G01X1206660Y1681767D02*
X1209098D01*
X1209104Y1681773D01*
X1210760D01*
G01X1205563Y1698340D02*
X1206778Y1697125D01*
X1208010D01*
G01D02*
X1210215Y1694920D01*
Y1689575D01*
X1209075Y1688435D01*
X1207180D01*
G01D02*
Y1685680D01*
G01X1213910Y1706790D02*
Y1708447D01*
X1215210Y1709747D01*
Y1711675D01*
G01X1216363Y1698605D02*
X1217578Y1697390D01*
X1218810D01*
G01Y1706790D02*
X1216363Y1704343D01*
Y1698605D01*
G01X1203110Y1706525D02*
Y1708182D01*
X1204410Y1709482D01*
Y1711410D01*
G01X1206969D02*
Y1709654D01*
X1208010Y1708613D01*
Y1706525D01*
G01D02*
X1205563Y1704078D01*
Y1698340D01*
G01X1212651Y1719155D02*
Y1724008D01*
X1212805Y1724162D01*
G01X1215210Y1719155D02*
X1212651D01*
G01X1212805Y1724162D02*
X1216968D01*
X1217556Y1723574D01*
G01X1201851Y1718890D02*
Y1723743D01*
X1202005Y1723897D01*
G01D02*
X1206168D01*
X1206756Y1723309D01*
G01X1204410Y1718890D02*
X1201851D01*
G01X1231575Y98400D02*
Y94200D01*
G01D02*
Y91825D01*
X1233700Y89700D01*
X1240700D01*
G01X1219515Y100060D02*
X1226765D01*
X1228425Y98400D01*
G01X1225100Y91500D02*
Y97400D01*
X1226100Y98400D01*
X1228425D01*
G01X1217018Y119462D02*
Y121582D01*
X1217528Y122092D01*
X1221144D01*
X1223274Y119962D01*
X1227074D01*
G01D02*
X1230399D01*
X1235241Y124804D01*
X1241280Y128840D01*
X1242466Y129331D01*
X1247462Y132669D01*
X1254690Y139897D01*
X1257572D01*
X1267007Y149332D01*
X1268963D01*
X1274263Y154632D01*
G01X1223500Y111162D02*
X1225100D01*
X1226069Y112131D01*
Y113982D01*
G01X1274914Y153652D02*
X1269134Y147872D01*
X1267967D01*
X1258282Y138187D01*
X1255639D01*
X1248826Y131374D01*
X1243601Y127883D01*
X1241905Y127180D01*
X1236872Y123817D01*
X1227037Y113982D01*
X1226069D01*
G01X1231668Y134262D02*
X1233064D01*
X1233544Y133782D01*
X1235627D01*
X1236974Y135129D01*
Y137531D01*
X1238148Y138705D01*
G01X1220168Y132962D02*
X1224238D01*
X1225318Y131882D01*
X1231158D01*
X1231668Y132392D01*
Y134262D01*
G01X1231686Y129409D02*
X1234698D01*
X1248020Y138308D01*
X1255044Y145332D01*
X1257691D01*
X1264531Y152172D01*
X1267540D01*
X1271444Y156076D01*
G01X1229500Y125100D02*
X1231686Y127286D01*
Y129409D01*
G01X1231668Y141110D02*
X1233070Y142512D01*
X1234713D01*
X1238043Y145842D01*
X1241100D01*
G01X1217018Y140962D02*
Y139683D01*
X1218179Y138522D01*
X1232194D01*
X1234184Y140512D01*
X1235474D01*
X1237404Y142442D01*
X1245595D01*
X1253635Y150482D01*
X1255073D01*
X1256093Y149462D01*
G01X1220172Y144909D02*
X1222920D01*
G01X1220172Y148909D02*
X1222920D01*
G01X1217018Y164962D02*
X1219018Y166962D01*
X1223620D01*
X1224820Y165762D01*
X1233624D01*
X1235114Y164272D01*
X1239664D01*
G01X1222593Y168962D02*
X1224233Y170602D01*
X1229228D01*
X1231668Y168162D01*
G01X1236300Y168362D02*
X1231868D01*
X1231668Y168162D01*
G01Y156962D02*
X1243400D01*
X1244500Y158062D01*
X1247413D01*
X1252993Y163642D01*
X1254273D01*
X1258084Y167453D01*
X1259192Y167912D01*
X1260842Y168596D01*
X1261969Y169722D01*
G01X1231668Y163462D02*
X1233118Y162012D01*
X1242259D01*
X1245136Y164889D01*
X1246272D01*
G01X1220168Y157962D02*
Y158046D01*
X1222303Y160181D01*
X1243100D01*
G01X1231668Y153115D02*
X1234055Y155502D01*
X1245764D01*
X1245784Y155522D01*
G01X1228518Y177962D02*
X1226093D01*
G01X1231668D02*
X1234314D01*
X1235858Y176418D01*
X1240390D01*
X1242146Y174662D01*
X1247091D01*
X1249166Y176737D01*
G01X1220168Y185462D02*
X1221258Y184372D01*
X1243743D01*
X1244383Y185012D01*
X1248064D01*
G01X1217018Y176962D02*
X1218918Y178862D01*
X1222444D01*
X1223574Y179992D01*
X1227184D01*
X1227384Y179792D01*
X1234094D01*
X1236024Y177862D01*
X1242383D01*
G01X1220168Y168962D02*
X1222593D01*
G01X1217004Y172945D02*
Y171788D01*
X1217929Y170863D01*
X1221246D01*
X1223495Y173112D01*
Y173672D01*
X1225125Y175302D01*
X1235983D01*
X1237910Y173375D01*
G01X1255848Y178605D02*
X1254183Y176940D01*
Y176458D01*
X1249849Y172124D01*
X1240085D01*
X1238960Y170999D01*
X1236895D01*
X1234932Y172962D01*
X1231668D01*
G01X1223134Y190802D02*
X1232830D01*
X1235140Y193112D01*
X1245302D01*
X1246023Y193833D01*
X1259581D01*
X1260610Y194862D01*
X1269775D01*
X1270065Y194572D01*
X1272183D01*
X1275013Y191742D01*
G01X1225574Y188662D02*
X1232720D01*
X1235280Y191222D01*
X1238928D01*
X1238985Y191279D01*
G01X1229720Y197302D02*
X1231760Y199342D01*
X1240288D01*
X1242168Y197462D01*
G01X1271026Y195717D02*
X1270329D01*
X1269984Y196062D01*
X1259954D01*
X1258835Y194943D01*
X1243802D01*
X1243521Y194662D01*
X1234530D01*
X1232330Y192462D01*
X1229940D01*
X1226440Y195962D01*
X1225373D01*
X1221473Y199862D01*
X1218220D01*
G01D02*
X1217145Y198787D01*
Y194862D01*
G01X1225320Y200162D02*
Y201682D01*
X1229040Y205402D01*
X1233850D01*
X1235750Y203502D01*
X1239979D01*
X1244469Y199012D01*
X1254423D01*
X1256283Y200872D01*
X1259784D01*
X1260548Y200108D01*
X1268107D01*
X1268678Y199537D01*
X1269819D01*
X1270244Y199112D01*
G01X1219060Y213312D02*
X1220500Y211872D01*
Y210437D01*
G01X1223180Y210552D02*
Y208543D01*
X1221924Y207287D01*
X1220500D01*
G01X1219220Y243862D02*
X1219084Y243998D01*
X1216656D01*
G01Y247148D02*
X1219220D01*
G01X1232233Y957546D02*
X1227883D01*
G01X1232233Y954200D02*
X1227883D01*
G01X1232233Y994357D02*
X1227883D01*
G01X1232233Y1057940D02*
X1236583D01*
G01X1224189Y1259155D02*
Y1257635D01*
X1226443Y1255381D01*
X1232233D01*
G01X1226899Y1257968D02*
Y1259465D01*
X1227389Y1259955D01*
X1228799D01*
X1230027Y1258727D01*
X1232233D01*
G01X1227847Y1251715D02*
X1231914D01*
X1232233Y1252034D01*
G01X1236583Y1248688D02*
X1232233D01*
G01X1218810Y1697390D02*
X1221075Y1695125D01*
Y1690260D01*
X1219515Y1688700D01*
X1217980D01*
G01X1217769Y1711675D02*
Y1709919D01*
X1218810Y1708878D01*
Y1706790D01*
G01X1232955Y54100D02*
X1237796D01*
X1243653Y59957D01*
G01X1236620Y58862D02*
X1235598Y57840D01*
X1232955D01*
G01X1240700Y89700D02*
X1246600D01*
X1255700Y98800D01*
X1259200D01*
X1260700Y100300D01*
Y109000D01*
X1262100Y110400D01*
X1264158D01*
G01X1245457Y95008D02*
Y98785D01*
G01D02*
X1251107D01*
G01X1250424Y108943D02*
Y103056D01*
X1248260Y100892D01*
X1244414D01*
X1242307Y98785D01*
G01X1235965Y102608D02*
X1244393D01*
X1247729Y105944D01*
Y109967D01*
X1249362Y111600D01*
G01X1244200Y112862D02*
Y109876D01*
X1240933Y106609D01*
X1235966D01*
G01X1244200Y112862D02*
X1247014Y115676D01*
Y118073D01*
X1254437Y125496D01*
Y131505D01*
X1257699Y134767D01*
X1259701D01*
X1279730Y154796D01*
X1279900D01*
G01X1241035Y114399D02*
X1243153Y125046D01*
X1248659Y128726D01*
X1256410Y136477D01*
X1258992D01*
X1268767Y146252D01*
X1269427D01*
X1279411Y156236D01*
G01X1238148Y138705D02*
X1239615Y140172D01*
X1246343D01*
X1253733Y147562D01*
X1257077D01*
X1263147Y153632D01*
X1266894D01*
X1269925Y156663D01*
Y158192D01*
G01X1234093Y144962D02*
X1237043Y147912D01*
X1240050D01*
X1243100Y150962D01*
X1248314D01*
X1252444Y155092D01*
X1255954D01*
X1258634Y157772D01*
Y160080D01*
X1261189Y162635D01*
X1264909Y164176D01*
X1268937Y168204D01*
X1269981Y168637D01*
G01X1241100Y145842D02*
X1246355D01*
X1253455Y152942D01*
X1256675D01*
X1260420Y156687D01*
X1265644D01*
X1266544Y157587D01*
Y159999D01*
X1269981Y163436D01*
G01X1239664Y164272D02*
Y166225D01*
X1242905Y169466D01*
X1251541D01*
X1256471Y174396D01*
X1256759D01*
X1260742Y178379D01*
X1269981D01*
G01Y179577D02*
X1260180D01*
X1256553Y175950D01*
X1256365D01*
X1251365Y170950D01*
X1240702D01*
X1238114Y168362D01*
X1236300D01*
G01X1246272Y164889D02*
X1249018Y167635D01*
X1253012D01*
X1259310Y173933D01*
Y174481D01*
X1262127Y177298D01*
X1270137D01*
G01X1243100Y160181D02*
X1245957D01*
X1251555Y165779D01*
X1253646D01*
X1256659Y168792D01*
X1258561Y169581D01*
X1260560Y171580D01*
X1261808Y172414D01*
X1264857Y173677D01*
X1264893D01*
X1266991Y174546D01*
X1267016Y174571D01*
X1269616Y175648D01*
X1269981D01*
G01X1245784Y155522D02*
X1247104Y156842D01*
X1248264D01*
X1253494Y162072D01*
X1255203D01*
X1258705Y165574D01*
X1262973Y167342D01*
X1266330Y170699D01*
X1269981Y172212D01*
G01X1249166Y176737D02*
X1255366Y182937D01*
X1269981D01*
G01X1248064Y185012D02*
X1249233Y186181D01*
X1250344D01*
X1252321Y188158D01*
X1270197D01*
G01X1242383Y177862D02*
X1246207D01*
X1247509Y179164D01*
X1249163D01*
X1254061Y184062D01*
X1269981D01*
G01X1237910Y173375D02*
X1249433D01*
X1252635Y176577D01*
Y178604D01*
X1255844Y181813D01*
X1269981D01*
G01X1242135Y191279D02*
X1245892D01*
X1247336Y192723D01*
X1260424D01*
X1260546Y192601D01*
X1262332D01*
G01X1270394Y197662D02*
X1266140D01*
X1265760Y198042D01*
X1259692D01*
X1258872Y198862D01*
X1257183D01*
X1255283Y196962D01*
X1242668D01*
X1242168Y197462D01*
G01X1236584Y205762D02*
X1236684Y205862D01*
X1239018D01*
G01X1242168Y209462D02*
X1242213Y209507D01*
X1248913D01*
X1251168Y211762D01*
G01X1242168Y217462D02*
X1240944Y218686D01*
Y220889D01*
X1242378Y222323D01*
G01X1251168Y215762D02*
X1249268Y213862D01*
X1246920D01*
X1246220Y214562D01*
X1243268D01*
X1242168Y213462D01*
G01X1251168Y205362D02*
X1249333Y207197D01*
X1245159D01*
X1243824Y205862D01*
X1242168D01*
G01X1242378Y222323D02*
X1242389Y222312D01*
X1245570D01*
X1246420Y221462D01*
X1250820D01*
X1251168Y221114D01*
Y219662D01*
G01X1237935Y248332D02*
X1240500D01*
G01X1237935Y244332D02*
X1240500D01*
G01X1264098Y88787D02*
X1264313Y88572D01*
X1267179D01*
G01X1252520Y92022D02*
X1255522D01*
X1262192Y98692D01*
X1263960D01*
X1264800Y99532D01*
Y102363D01*
X1263616Y103547D01*
X1263040D01*
G01X1286079Y148016D02*
X1285153Y147090D01*
X1279901D01*
X1264214Y131403D01*
Y128372D01*
X1262778Y126936D01*
Y124569D01*
X1265022Y121211D01*
X1266136Y118521D01*
X1264508Y114589D01*
X1262289Y112370D01*
X1257270D01*
X1255056Y110156D01*
Y102069D01*
X1251772Y98785D01*
X1251107D01*
G01X1258539Y106502D02*
Y109263D01*
G01X1267322Y106739D02*
X1267280Y106697D01*
X1263040D01*
G01X1264158Y110400D02*
X1263040Y109282D01*
Y106697D01*
G01X1264158Y110400D02*
X1264220Y110462D01*
G01X1249362Y111600D02*
X1252160Y114398D01*
Y120582D01*
X1256894Y125316D01*
Y131372D01*
X1258579Y133057D01*
X1260597D01*
X1281178Y153638D01*
G01X1257581Y114579D02*
X1254652D01*
X1253870Y115361D01*
Y117243D01*
X1254539Y117912D01*
X1262734D01*
X1263533Y118711D01*
Y119806D01*
X1258644Y127121D01*
Y129993D01*
X1259973Y131322D01*
X1261282D01*
X1282788Y152828D01*
G01X1256093Y149462D02*
X1261863Y155232D01*
X1266469D01*
X1268342Y157105D01*
Y159713D01*
X1269856Y161227D01*
G01X1265010Y162222D02*
X1269638Y166850D01*
X1269981D01*
G01Y180689D02*
X1257932D01*
X1255848Y178605D01*
G01X1261969Y169722D02*
X1263603Y171356D01*
X1269981Y173998D01*
G01X1262332Y192601D02*
X1264236D01*
X1266505Y190332D01*
X1271322D01*
G01X1270883Y203420D02*
X1268061Y206242D01*
X1263630D01*
X1262300Y207572D01*
G01D02*
X1262193Y207679D01*
X1253647D01*
X1252216Y209110D01*
Y210714D01*
X1251168Y211762D01*
G01Y219662D02*
X1254314Y216516D01*
Y216132D01*
X1255434Y215012D01*
X1263034D01*
X1263362Y215340D01*
X1269305D01*
X1271478Y213167D01*
G01X1270131Y200602D02*
X1268659Y202074D01*
X1260930D01*
X1260048Y202956D01*
X1255218D01*
X1253624Y201362D01*
G01D02*
X1251734D01*
X1251534Y201562D01*
X1251168D01*
G01X1274004Y208773D02*
X1273375Y209402D01*
Y209862D01*
X1269217Y214020D01*
X1264142D01*
X1263214Y213092D01*
X1258364D01*
X1257966Y212694D01*
X1255954D01*
G01D02*
X1254236D01*
X1251168Y215762D01*
G01Y205362D02*
X1251264Y205266D01*
X1256615D01*
G01D02*
X1261006D01*
X1262033Y204239D01*
X1268376D01*
X1270293Y202322D01*
G01X1262168Y217462D02*
X1264874D01*
G01D02*
X1269064D01*
X1270634Y215892D01*
X1274623D01*
G01X1255613Y209568D02*
X1256703D01*
X1258825Y211690D01*
X1263776D01*
X1264744Y212658D01*
X1269209D01*
X1272395Y209472D01*
Y208962D01*
X1273645Y207712D01*
G01X1265207Y208442D02*
X1266917Y210152D01*
X1268795D01*
X1269929Y209018D01*
Y208368D01*
X1273176Y205121D01*
G01X1259703Y209808D02*
X1261199D01*
X1261413Y210022D01*
X1263925D01*
X1265345Y211442D01*
X1268983D01*
X1270989Y209436D01*
Y208868D01*
X1272564Y207293D01*
G01X1271315Y220701D02*
X1268824Y223192D01*
X1263801D01*
X1262601Y223689D01*
X1262168Y224122D01*
Y225462D01*
G01X1251168Y223462D02*
X1251173Y223467D01*
X1255454D01*
X1255694Y223707D01*
X1259923D01*
X1262168Y221462D01*
G01X1267315Y220701D02*
X1266554Y221462D01*
X1262168D01*
G01Y229462D02*
X1262698Y228932D01*
X1265444D01*
X1266914Y227462D01*
X1269093D01*
X1274954Y221601D01*
G01X1262168Y229462D02*
X1260068Y231562D01*
X1254450D01*
X1253440Y230552D01*
G01D02*
X1252258D01*
X1251168Y229462D01*
Y227462D01*
G01X1262168Y233462D02*
X1259403Y236227D01*
X1254465D01*
X1253860Y235622D01*
G01X1276514Y221302D02*
Y222532D01*
X1272888Y226158D01*
Y227166D01*
X1268592Y231462D01*
X1264168D01*
X1262168Y233462D01*
G01X1253860Y235622D02*
X1252360D01*
X1251168Y234430D01*
Y233462D01*
G01X1262168Y243562D02*
X1260118Y245612D01*
X1255030D01*
X1253950Y246692D01*
G01D02*
Y244244D01*
X1251168Y241462D01*
G01X1280878Y226322D02*
Y228058D01*
X1266594Y242342D01*
X1263388D01*
X1262168Y243562D01*
G01X1266715Y244692D02*
X1263845Y247562D01*
X1262168D01*
G01Y238662D02*
Y239495D01*
X1260741Y240922D01*
X1254750D01*
X1254370Y241302D01*
G01D02*
X1251168Y238100D01*
Y237462D01*
G01X1262168Y238662D02*
X1264400D01*
X1265040Y239302D01*
X1268154D01*
X1279542Y227914D01*
Y224905D01*
X1279801Y224646D01*
G01X1262368Y251562D02*
Y252961D01*
X1261107Y254222D01*
X1253601D01*
X1251320Y251941D01*
Y245509D01*
X1251253Y245442D01*
G01X1284979Y232576D02*
X1282471D01*
X1265065Y249982D01*
G01D02*
X1263485Y251562D01*
X1262368D01*
G01X1256454Y252122D02*
X1258658D01*
X1259218Y251562D01*
G01X1264146Y277191D02*
Y261746D01*
X1267158Y258734D01*
Y252104D01*
X1277086Y242176D01*
X1278114D01*
X1281236Y239054D01*
X1285122D01*
X1288059Y236117D01*
G01X1264146Y282191D02*
X1266513Y279824D01*
Y263853D01*
X1269702Y260664D01*
Y254028D01*
X1273424Y250306D01*
Y248822D01*
X1281624Y240622D01*
X1285834D01*
X1286274Y240182D01*
G01X1258250Y292986D02*
X1255150Y296086D01*
Y299941D01*
G01X1263150D02*
Y294726D01*
G01X1255150Y299941D02*
X1251150D01*
G01X1259150D02*
X1263150D01*
G01X1266227Y764045D02*
X1259857D01*
X1258667Y762855D01*
Y751405D01*
G01X1275820Y87962D02*
X1274520Y86662D01*
Y84437D01*
G01X1270329Y88572D02*
Y92724D01*
G01Y101011D02*
Y96768D01*
G01D02*
Y92724D01*
G01X1281940Y90847D02*
X1279415D01*
G01X1281940Y87697D02*
X1279390D01*
G01X1281704Y95402D02*
X1281866Y95564D01*
Y98828D01*
G01X1274864Y110287D02*
X1280770Y116193D01*
X1284750Y122148D01*
X1287024Y124422D01*
Y124893D01*
X1288093Y125962D01*
G01X1293813Y131439D02*
X1291093Y128715D01*
Y126297D01*
X1287116Y122320D01*
X1281541Y113970D01*
X1277294Y109723D01*
Y106282D01*
X1275214Y104202D01*
X1271919D01*
X1269382Y106739D01*
X1267322D01*
G01X1294910Y130342D02*
X1292643Y128073D01*
Y125655D01*
X1289793Y122805D01*
Y122665D01*
X1289190Y122062D01*
X1283431Y112968D01*
X1280424Y109961D01*
Y108013D01*
X1281866Y106571D01*
Y102928D01*
G01X1276480Y118820D02*
X1277220D01*
X1281320Y122920D01*
Y125338D01*
X1281262Y125396D01*
G01X1270207Y134376D02*
X1276513Y140682D01*
X1277820D01*
G01X1280314Y133448D02*
X1280814D01*
X1282764Y135398D01*
G01X1280314Y133448D02*
X1277160Y130294D01*
Y129498D01*
G01X1269520Y125780D02*
X1269620Y125880D01*
Y125980D01*
X1271040Y127400D01*
X1274738D01*
X1276836Y129498D01*
X1277160D01*
G01X1283623Y129807D02*
Y128985D01*
X1281262Y126624D01*
Y125396D01*
G01X1277820Y140682D02*
X1280314D01*
X1283394Y143762D01*
X1286293D01*
G01X1281093Y144516D02*
X1281999Y145422D01*
X1285599D01*
X1288347Y148170D01*
G01X1271954Y159143D02*
X1273093D01*
X1278738Y164788D01*
G01X1271315Y220701D02*
X1273355D01*
X1273629Y220427D01*
G01X1267315Y220701D02*
X1268219D01*
X1270738Y218182D01*
X1273154D01*
G01X1267773Y208373D02*
X1271960Y204186D01*
G01X1283301Y228376D02*
X1269015Y242662D01*
X1268745D01*
X1266715Y244692D01*
G01X1277969Y223822D02*
X1277661Y224130D01*
Y225685D01*
G01D02*
X1277633Y225713D01*
X1276078D01*
X1274984Y226807D01*
Y228146D01*
X1269668Y233462D01*
G01X1287789Y243698D02*
X1286755Y244732D01*
X1280797D01*
X1277101Y248428D01*
Y252279D01*
X1275555Y253825D01*
Y255581D01*
X1276861Y256887D01*
Y259815D01*
X1270646Y266030D01*
Y277191D01*
G01X1281448Y242608D02*
X1275324Y248732D01*
Y250700D01*
X1271458Y254566D01*
Y261908D01*
X1268158Y265208D01*
Y279703D01*
X1270646Y282191D01*
G01X1280675Y277013D02*
Y262481D01*
X1285994Y257162D01*
X1288238D01*
X1305241Y240159D01*
G01X1279987Y287375D02*
Y281451D01*
X1285650Y275788D01*
Y275000D01*
X1291210Y269440D01*
Y259936D01*
X1307659Y243487D01*
G01X1269960Y294536D02*
X1271150Y295726D01*
Y299941D01*
G01X1267150D02*
X1271150D01*
G01X1266727Y752955D02*
X1290022D01*
X1290437Y752540D01*
G01X1292572Y785575D02*
Y784680D01*
X1271937Y764045D01*
X1266227D01*
G01X1302459Y68562D02*
X1297710D01*
G01D02*
X1295400Y66252D01*
Y61408D01*
X1296581Y60227D01*
Y55951D01*
X1297470Y55062D01*
X1298814D01*
G01Y57621D02*
Y62004D01*
X1297785Y63033D01*
G01X1281913Y82474D02*
X1286013D01*
G01D02*
Y84399D01*
X1285060Y85352D01*
Y92642D01*
X1285410Y92992D01*
Y100372D01*
X1286750Y101712D01*
G01X1293454Y81232D02*
X1294761D01*
X1294824Y81169D01*
X1296090D01*
G01X1296253Y100049D02*
Y99196D01*
X1295767Y98710D01*
Y95291D01*
G01X1296253Y100049D02*
Y111182D01*
X1294691Y114954D01*
Y117129D01*
G01X1292880Y93162D02*
X1294746D01*
X1295767Y92141D01*
G01X1295693Y126867D02*
Y124602D01*
X1292693Y121602D01*
Y121462D01*
X1292293Y121062D01*
X1287314Y111753D01*
Y102276D01*
X1286750Y101712D01*
G01X1295343Y128582D02*
X1294193Y127430D01*
Y125012D01*
X1291343Y122162D01*
Y122022D01*
X1290264Y120944D01*
X1285214Y111496D01*
Y107517D01*
X1283744Y106047D01*
Y94026D01*
X1281940Y92222D01*
Y90847D01*
G01X1281866Y98828D02*
Y102928D01*
G01X1291823Y90844D02*
X1290650Y92017D01*
Y99022D01*
X1292080Y100452D01*
Y104772D01*
X1291257Y105595D01*
G01X1287793Y95682D02*
Y95254D01*
X1287913Y95134D01*
Y90794D01*
G01X1287793Y95682D02*
Y98935D01*
X1289810Y100952D01*
Y102972D01*
X1288960Y103822D01*
Y109188D01*
X1291184Y113350D01*
G01X1296929Y116962D02*
Y114821D01*
X1298407Y111252D01*
Y108042D01*
G01X1293151Y116401D02*
Y111596D01*
X1294104Y110643D01*
Y108442D01*
X1291257Y105595D01*
G01X1292716Y132535D02*
X1289543Y129357D01*
Y127412D01*
X1288093Y125962D01*
G01X1282764Y135398D02*
X1286984Y139618D01*
X1287349D01*
X1290566Y142835D01*
G01X1289684Y135766D02*
X1291478Y137560D01*
Y137745D01*
G01X1283623Y129807D02*
X1284865D01*
X1286150Y131092D01*
G01D02*
X1287456Y132398D01*
Y133538D01*
G01X1291478Y137745D02*
Y139884D01*
X1294346Y142752D01*
X1296364Y147619D01*
Y149333D01*
X1296835Y149804D01*
G01X1299134Y157449D02*
X1297012D01*
G01X1295929Y159299D02*
X1293802D01*
G01X1295929Y166699D02*
X1293802D01*
G01X1293511Y179048D02*
X1292803D01*
X1292303Y178548D01*
Y176963D01*
G01X1296999Y183349D02*
X1296806Y183682D01*
X1295929Y185199D01*
G01X1299134Y172249D02*
X1297007D01*
G01X1296999Y175949D02*
X1296565D01*
X1295929Y176585D01*
Y177799D01*
G01Y170399D02*
X1293802D01*
G01X1294163Y175865D02*
Y174432D01*
X1294496Y174099D01*
X1295929D01*
G01X1296999Y179649D02*
X1296466D01*
X1295929Y180186D01*
Y181499D01*
G01Y196299D02*
X1296999Y194449D01*
G01X1295929Y199999D02*
X1296999Y198149D01*
G01X1295929Y192599D02*
X1296999Y190749D01*
G01X1295929Y188899D02*
X1296999Y187049D01*
G01X1295929Y211099D02*
X1293805D01*
G01X1293798Y205833D02*
X1294479Y207011D01*
X1295929Y207399D01*
G01X1296999Y216649D02*
X1299134D01*
G01X1293807Y214799D02*
X1295929D01*
G01Y203699D02*
X1296999Y201849D01*
G01Y212949D02*
X1299134D01*
G01Y205549D02*
X1296999D01*
G01X1294357Y224688D02*
X1293409D01*
X1292303Y224230D01*
G01X1296999Y224049D02*
X1299134D01*
G01X1293807Y218499D02*
X1295929D01*
G01X1293807Y222199D02*
X1295929D01*
G01X1282654Y226309D02*
X1283284Y225679D01*
X1284318D01*
X1285767Y224230D01*
G01X1284648Y265431D02*
X1286241D01*
X1288520Y263152D01*
Y259313D01*
X1305963Y241870D01*
G01X1288693Y283769D02*
X1291607D01*
X1293368Y282008D01*
Y272024D01*
X1293664Y271728D01*
Y260481D01*
X1310899Y243246D01*
G01X1283346Y281903D02*
X1287336Y277913D01*
Y275991D01*
X1292504Y270823D01*
Y260050D01*
X1309068Y243486D01*
G01X1284794Y272284D02*
X1289800Y267278D01*
Y259855D01*
X1306349Y243306D01*
G01X1295940Y286782D02*
Y286662D01*
G01X1436320Y305862D02*
X1428056D01*
X1420956Y312962D01*
X1315256D01*
X1307556Y320662D01*
X1291420D01*
G01X1436320Y303362D02*
X1427020D01*
X1419920Y310462D01*
X1314220D01*
X1306520Y318162D01*
X1291420D01*
G01X1294937Y752540D02*
X1290437D01*
G01X1288332Y1370043D02*
X1288040Y1369751D01*
Y1365989D01*
G01D02*
Y1364869D01*
X1289369Y1363540D01*
X1289595Y1362995D01*
Y1361720D01*
G01X1316459Y58877D02*
X1315044Y60292D01*
X1305580D01*
X1304240Y58952D01*
Y53122D01*
X1304859Y52503D01*
X1306294D01*
G01X1309790Y62225D02*
X1313788D01*
G01X1309790D02*
X1307956D01*
X1305609Y64572D01*
G01X1302459Y68562D02*
X1303744Y67277D01*
Y66437D01*
X1305609Y64572D01*
G01X1301820Y58672D02*
Y58852D01*
X1302459Y59491D01*
Y64572D01*
G01X1311424Y68652D02*
X1309790Y67018D01*
Y65375D01*
G01X1298270Y76142D02*
X1301983Y72429D01*
X1307578D01*
G01X1298270Y76142D02*
Y77042D01*
X1303120Y81892D01*
Y90298D01*
X1304584Y91762D01*
Y97172D01*
X1302710Y99046D01*
Y109083D01*
X1305564Y115974D01*
Y117659D01*
X1305284Y119072D01*
Y119663D01*
X1305848Y121025D01*
X1306129Y121306D01*
G01X1311260Y83032D02*
X1313159Y81133D01*
X1313919D01*
G01X1299240Y81169D02*
Y82358D01*
X1300586Y83704D01*
Y85138D01*
G01D02*
Y87574D01*
X1300964Y87952D01*
Y91012D01*
G01X1305188Y81775D02*
Y87035D01*
X1306200Y88047D01*
Y99676D01*
X1305422Y100454D01*
G01X1303264Y77865D02*
Y78725D01*
X1305188Y80649D01*
Y81775D01*
G01X1324773Y80451D02*
Y82954D01*
X1322345Y85382D01*
X1312490D01*
X1311340Y86532D01*
X1308440D01*
G01D02*
X1307150Y85242D01*
Y82963D01*
X1308338Y81775D01*
G01X1298640Y93062D02*
X1298220Y93482D01*
Y97762D01*
X1298620Y98162D01*
Y103862D01*
X1298407Y104075D01*
Y104892D01*
G01X1310906Y100614D02*
Y97807D01*
G01X1299730Y116274D02*
Y113333D01*
X1300700Y110991D01*
Y98166D01*
X1302384Y96482D01*
Y94292D01*
X1300964Y92872D01*
Y91012D01*
G01X1309164Y120432D02*
Y117342D01*
X1306821Y114999D01*
X1304826Y109016D01*
Y101050D01*
X1305422Y100454D01*
G01X1308792Y94376D02*
X1308846Y94430D01*
Y101442D01*
X1308274Y102014D01*
Y104162D01*
G01X1317901Y95732D02*
X1312084D01*
X1311304Y94952D01*
Y92012D01*
X1310518Y91226D01*
X1308792D01*
G01X1314059Y93877D02*
X1313919Y93737D01*
Y89007D01*
G01X1314065Y123095D02*
Y116720D01*
X1314005Y116660D01*
X1312792Y113732D01*
G01D02*
Y111963D01*
X1310906Y110077D01*
Y103764D01*
G01X1318800Y123996D02*
X1315664Y120860D01*
Y110679D01*
X1313405Y108420D01*
G01D02*
Y106375D01*
X1314906Y104874D01*
Y103764D01*
G01X1307667Y120792D02*
Y120115D01*
X1307244Y119692D01*
Y118452D01*
G01X1310525Y120822D02*
Y116643D01*
X1308960Y115078D01*
X1306836Y109952D01*
Y108242D01*
G01X1308274Y104162D02*
Y106130D01*
X1308846Y106702D01*
Y110489D01*
X1310617Y114765D01*
X1312384Y116532D01*
Y120118D01*
G01X1305544Y164849D02*
X1303417D01*
G01X1302340Y162999D02*
X1300213D01*
G01X1302340Y166699D02*
X1300212D01*
G01X1308749D02*
X1306622D01*
G01X1311955Y157449D02*
X1309832D01*
G01X1308749Y162999D02*
X1306626D01*
G01X1308749Y159299D02*
X1306626D01*
G01X1315160Y162999D02*
X1313037D01*
G01X1311955Y164849D02*
X1309832D01*
G01X1315160Y159299D02*
X1313037D01*
G01X1305544Y157449D02*
X1303417D01*
G01X1302340Y159299D02*
X1300217D01*
G01X1315160Y166699D02*
X1313033D01*
G01X1302340Y170399D02*
X1300212D01*
G01X1308749D02*
X1306626D01*
G01X1303407Y183349D02*
X1303215Y183682D01*
X1302340Y185199D01*
G01X1308749Y177799D02*
X1309817Y175949D01*
G01X1302340Y174099D02*
X1300212D01*
G01X1315160Y170399D02*
X1313037D01*
G01X1306617Y185199D02*
X1306099D01*
X1305544Y184644D01*
Y183349D01*
G01X1311955Y172249D02*
X1309832D01*
G01X1303407Y175949D02*
X1302841D01*
X1302340Y176450D01*
Y177799D01*
G01X1303407Y179649D02*
X1302340Y181499D01*
G01X1306617Y177799D02*
X1306045D01*
X1305544Y177298D01*
Y175949D01*
G01X1308749Y181499D02*
X1309817Y179649D01*
G01X1299134D02*
X1300204Y181499D01*
G01X1309817Y194449D02*
X1309249D01*
X1308749Y194949D01*
Y196299D01*
G01X1306617Y188899D02*
X1306049D01*
X1305544Y188394D01*
Y187049D01*
G01X1303407Y194449D02*
X1302840D01*
X1302340Y194949D01*
Y196299D01*
G01X1306617D02*
X1306045D01*
X1305544Y195798D01*
Y194449D01*
G01X1300207Y196299D02*
X1299635D01*
X1299134Y195798D01*
Y194449D01*
G01X1303407Y190749D02*
X1302840D01*
X1302340Y191249D01*
Y192599D01*
G01X1303407Y187049D02*
X1302340Y188899D01*
G01X1300204D02*
X1299428D01*
X1299134Y188605D01*
Y187049D01*
G01X1311955D02*
X1313025Y188899D01*
G01X1309817Y198149D02*
X1309249D01*
X1308749Y198649D01*
Y199999D01*
G01X1303407Y198149D02*
X1302841D01*
X1302340Y198650D01*
Y199999D01*
G01X1300207Y203699D02*
X1300205Y203696D01*
X1299137Y201849D01*
X1299134D01*
G01X1302340Y207399D02*
X1300207D01*
G01X1305544Y205549D02*
X1303416D01*
G01X1305544Y201849D02*
X1306614Y203699D01*
G01X1306627Y214799D02*
X1308749D01*
G01X1302340Y211099D02*
X1300207D01*
G01X1303422Y220349D02*
X1305544D01*
G01X1300220Y218499D02*
X1302340D01*
G01X1300220Y222199D02*
X1302340D01*
G01X1315160D02*
X1313033D01*
G01X1311955Y220349D02*
X1309833D01*
G01X1305544Y224049D02*
X1303425D01*
G01X1305090Y284722D02*
X1301132Y280764D01*
Y260716D01*
X1301723Y259288D01*
X1312643Y248368D01*
G01X1304930Y278552D02*
X1302332Y275954D01*
Y263777D01*
G01X1305164Y272652D02*
Y270174D01*
X1308653Y266685D01*
Y259758D01*
G01X1304714Y265246D02*
Y262518D01*
X1307512Y259720D01*
G01X1316569Y268316D02*
X1314280Y266027D01*
Y263770D01*
X1314740Y263310D01*
X1317727D01*
X1319375Y261662D01*
G01X1314184Y849978D02*
Y851903D01*
X1315771Y853490D01*
G01X1310221Y978457D02*
X1309864Y978814D01*
X1307426D01*
G01X1319721Y72430D02*
X1320094Y72057D01*
Y63382D01*
X1318937Y62225D01*
X1317831D01*
G01X1316459Y58877D02*
X1317831Y60249D01*
Y62225D01*
G01X1316459Y58697D02*
Y58877D01*
G01X1321869Y65357D02*
X1322248Y65736D01*
Y68487D01*
G01D02*
X1324773Y71012D01*
Y72577D01*
G01X1321279Y58767D02*
Y61617D01*
X1321869Y62207D01*
G01X1333190Y58825D02*
Y62344D01*
X1330102Y65432D01*
G01X1319037Y81133D02*
Y76264D01*
X1319721Y75580D01*
G01D02*
X1319821Y75480D01*
X1322415D01*
G01D02*
X1322860Y75925D01*
X1329036D01*
X1329891Y75070D01*
Y72577D01*
G01Y80451D02*
Y87412D01*
G01D02*
X1327182D01*
X1326261Y88333D01*
X1324120D01*
G01X1322906Y97128D02*
Y94212D01*
G01Y100278D02*
Y104158D01*
G01X1319968Y98266D02*
X1318906Y99328D01*
Y100608D01*
G01X1314406Y97756D02*
X1314906Y98256D01*
Y100614D01*
G01X1324120Y91483D02*
X1327626D01*
X1329891Y93748D01*
G01X1323546Y113188D02*
X1325220Y111514D01*
Y101651D01*
X1326695Y100176D01*
Y96944D01*
X1329891Y93748D01*
G01X1551160Y189342D02*
Y184331D01*
X1543806Y176977D01*
X1543084D01*
X1540675Y179386D01*
X1539953D01*
X1538900Y178333D01*
Y177611D01*
X1541309Y175202D01*
Y174480D01*
X1538148Y171319D01*
Y170599D01*
X1541779Y166969D01*
Y166249D01*
X1540724Y165194D01*
X1540004D01*
X1536373Y168824D01*
X1535653D01*
X1534598Y167769D01*
Y167049D01*
X1538229Y163419D01*
Y162699D01*
X1537174Y161644D01*
X1536454D01*
X1532823Y165274D01*
X1532103D01*
X1417399Y50570D01*
X1357245D01*
X1332528Y75287D01*
Y100258D01*
X1330779Y102007D01*
X1328757D01*
X1327200Y103564D01*
Y112727D01*
X1323871Y116056D01*
X1323354Y117304D01*
Y119071D01*
G01X1319037Y89007D02*
Y91595D01*
X1319364Y91922D01*
Y94269D01*
X1317901Y95732D01*
G01X1319694Y122772D02*
X1317534Y120612D01*
Y113284D01*
X1318146Y112672D01*
Y110924D01*
G01D02*
Y105748D01*
X1318906Y104988D01*
Y103758D01*
G01X1319468Y118828D02*
Y114264D01*
X1320401Y113331D01*
Y106663D01*
X1322906Y104158D01*
G01X1321490Y119417D02*
Y115244D01*
X1323546Y113188D01*
G01X1326893Y120943D02*
X1328004Y119832D01*
Y115942D01*
X1331628Y112318D01*
Y103706D01*
X1334017Y101317D01*
Y75794D01*
X1357752Y52059D01*
X1416782D01*
X1536767Y172044D01*
Y181060D01*
X1537277Y181570D01*
X1544731D01*
X1545241Y182080D01*
Y183570D01*
X1544731Y184080D01*
X1537277D01*
X1536767Y184590D01*
Y186080D01*
X1537277Y186590D01*
X1548021D01*
X1548531Y187100D01*
Y188590D01*
X1548021Y189100D01*
X1544404D01*
X1543894Y189610D01*
Y192478D01*
X1543384Y192988D01*
X1541894D01*
X1541384Y192478D01*
Y189610D01*
X1540874Y189100D01*
X1535707D01*
X1533385Y191422D01*
Y193108D01*
G01X1327904Y125582D02*
Y122221D01*
X1329501Y120624D01*
Y116445D01*
X1333038Y112908D01*
Y104293D01*
X1335427Y101904D01*
Y76379D01*
X1358337Y53469D01*
X1416197D01*
X1529703Y166975D01*
Y171931D01*
X1530213Y172441D01*
X1533298D01*
X1533808Y172951D01*
Y174441D01*
X1533298Y174951D01*
X1530213D01*
X1529703Y175461D01*
Y176951D01*
X1530213Y177461D01*
X1533298D01*
X1533808Y177971D01*
Y179461D01*
X1533298Y179971D01*
X1530213D01*
X1529703Y180481D01*
Y181971D01*
X1530213Y182481D01*
X1533298D01*
X1533808Y182991D01*
Y184481D01*
X1533298Y184991D01*
X1530213D01*
X1529703Y185501D01*
Y187911D01*
X1527165Y190449D01*
X1521116D01*
X1521030Y190363D01*
X1516377D01*
X1514330Y192410D01*
Y196448D01*
X1525559Y207677D01*
X1531824D01*
G01X1333783Y118173D02*
X1338394Y113562D01*
Y110943D01*
X1338548Y110571D01*
Y77249D01*
X1358921Y56876D01*
X1414785D01*
X1518238Y160329D01*
Y163608D01*
X1517728Y164118D01*
X1516040D01*
X1515530Y164628D01*
Y166118D01*
X1516040Y166628D01*
X1517728D01*
X1518238Y167138D01*
Y168628D01*
X1517728Y169138D01*
X1516040D01*
X1515530Y169648D01*
Y171138D01*
X1516040Y171648D01*
X1517728D01*
X1518238Y172158D01*
Y174454D01*
X1518748Y174964D01*
X1520563D01*
X1521073Y175474D01*
Y176964D01*
X1520563Y177474D01*
X1518748D01*
X1518238Y177984D01*
Y179474D01*
X1518748Y179984D01*
X1520563D01*
X1521073Y180494D01*
Y181984D01*
X1520563Y182494D01*
X1518748D01*
X1518238Y183004D01*
Y185414D01*
X1517435Y186217D01*
X1514092D01*
X1510440Y189869D01*
Y201182D01*
X1512188Y202930D01*
X1512910D01*
X1514472Y201368D01*
X1515194D01*
X1516247Y202421D01*
Y203143D01*
X1514685Y204705D01*
Y205427D01*
X1515738Y206480D01*
X1516460D01*
X1518022Y204918D01*
X1518744D01*
X1519797Y205971D01*
Y206693D01*
X1518235Y208255D01*
Y208977D01*
X1520083Y210825D01*
X1522009D01*
G01X1329054Y125582D02*
Y123546D01*
X1330911Y121689D01*
Y117044D01*
X1334448Y113507D01*
Y104879D01*
X1337077Y102250D01*
Y76725D01*
X1358683Y55119D01*
X1415513D01*
X1523427Y163033D01*
Y166587D01*
X1523937Y167097D01*
X1526570D01*
X1527080Y167607D01*
Y169097D01*
X1526570Y169607D01*
X1523937D01*
X1523427Y170117D01*
Y171607D01*
X1523937Y172117D01*
X1526570D01*
X1527080Y172627D01*
Y174117D01*
X1526570Y174627D01*
X1523937D01*
X1523427Y175137D01*
Y176627D01*
X1523937Y177137D01*
X1526570D01*
X1527080Y177647D01*
Y179137D01*
X1526570Y179647D01*
X1523937D01*
X1523427Y180157D01*
Y181647D01*
X1523937Y182157D01*
X1526914D01*
X1527377Y182620D01*
Y184144D01*
X1526854Y184667D01*
X1523937D01*
X1523427Y185177D01*
Y187587D01*
X1522512Y188502D01*
X1514007D01*
X1512319Y190190D01*
Y196433D01*
X1525531Y209645D01*
X1526998D01*
G01X1319452Y162999D02*
X1321570D01*
G01X1318364Y168549D02*
X1316242D01*
G01X1319442Y159299D02*
X1321570D01*
G01X1318364Y157449D02*
X1316241D01*
G01X1318364Y164849D02*
X1316242D01*
G01X1322652D02*
X1324775D01*
G01X1329062D02*
X1331184D01*
G01X1326918Y161161D02*
X1327979Y162999D01*
G01X1329062Y157449D02*
X1331184D01*
G01X1324775D02*
X1322652D01*
G01X1316242Y209249D02*
X1318364D01*
G01X1329062Y220349D02*
X1331184D01*
G01X1325857Y218499D02*
X1327979D01*
G01X1323912Y245111D02*
X1326004D01*
X1326593Y244522D01*
Y243160D01*
X1326143Y242710D01*
X1324643D01*
X1324193Y242260D01*
Y240760D01*
X1324643Y240310D01*
X1326445D01*
X1327523Y239232D01*
G01X1327337Y255966D02*
Y253018D01*
X1328324Y252031D01*
Y248022D01*
X1329186Y247160D01*
Y240202D01*
G01X1325856Y222199D02*
X1327979D01*
G01X1322652Y224049D02*
X1324775D01*
G01X1324093Y247887D02*
X1323912Y247706D01*
Y245111D01*
G01X1324093Y251037D02*
X1322584Y252546D01*
Y254919D01*
X1321537Y255966D01*
G01X1320387Y258901D02*
X1321537Y257751D01*
Y255966D01*
G01X1320387Y258901D02*
X1319875Y259413D01*
Y261162D01*
X1319375Y261662D01*
G01X1327337Y255966D02*
X1326804Y256499D01*
Y257966D01*
X1325769Y259001D01*
G01D02*
Y260734D01*
X1324989Y261514D01*
G01D02*
Y262290D01*
X1321480Y265799D01*
Y271809D01*
X1324679Y275008D01*
X1325231D01*
G01X1317100Y553900D02*
Y540800D01*
X1336600Y521300D01*
X1615100D01*
X1626200Y510200D01*
X1700600D01*
X1701617Y511217D01*
X1709917D01*
X1712700Y514000D01*
Y523100D01*
X1704460Y531340D01*
Y531613D01*
G01X1321320Y854584D02*
X1321321Y854585D01*
Y856694D01*
G01X1323171Y879124D02*
X1323170Y879123D01*
Y877015D01*
X1323171Y877014D01*
G01X1325021Y882329D02*
X1325020Y882328D01*
Y880219D01*
G01X1319903Y997574D02*
Y999684D01*
G01X1320136Y1343344D02*
Y1341747D01*
X1321377Y1340506D01*
X1321603Y1339961D01*
Y1338686D01*
G01X1319235Y1347521D02*
X1320136Y1346620D01*
Y1343344D01*
G01X1340912Y125092D02*
Y123954D01*
X1342026Y122840D01*
Y120330D01*
X1345542Y116814D01*
Y112505D01*
X1345768Y111959D01*
Y101145D01*
X1349412Y97501D01*
Y90054D01*
X1344700Y85342D01*
Y79080D01*
X1361233Y62547D01*
X1411205D01*
X1498116Y149458D01*
Y155930D01*
X1498626Y156440D01*
X1499633D01*
X1500143Y156950D01*
Y158440D01*
X1499633Y158950D01*
X1498626D01*
X1498116Y159460D01*
Y160950D01*
X1498626Y161460D01*
X1499633D01*
X1500143Y161970D01*
Y163460D01*
X1499633Y163970D01*
X1498626D01*
X1498116Y164480D01*
Y165970D01*
X1498626Y166480D01*
X1499633D01*
X1500143Y166990D01*
Y168480D01*
X1499633Y168990D01*
X1498626D01*
X1498116Y169500D01*
Y170990D01*
X1498626Y171500D01*
X1499633D01*
X1500143Y172010D01*
Y173500D01*
X1499633Y174010D01*
X1498626D01*
X1498116Y174520D01*
Y176010D01*
X1498626Y176520D01*
X1499633D01*
X1500143Y177030D01*
Y178520D01*
X1499633Y179030D01*
X1498626D01*
X1498116Y179540D01*
Y181030D01*
X1498626Y181540D01*
X1499633D01*
X1500143Y182050D01*
Y183540D01*
X1499633Y184050D01*
X1498626D01*
X1498116Y184560D01*
Y186050D01*
X1498626Y186560D01*
X1499633D01*
X1500143Y187070D01*
Y188560D01*
X1499633Y189070D01*
X1498626D01*
X1498116Y189580D01*
Y191070D01*
X1498626Y191580D01*
X1499633D01*
X1500143Y192090D01*
Y193580D01*
X1499633Y194090D01*
X1498626D01*
X1498116Y194600D01*
Y196090D01*
X1498626Y196600D01*
X1499633D01*
X1500143Y197110D01*
Y198600D01*
X1499633Y199110D01*
X1498626D01*
X1498116Y199620D01*
Y202173D01*
X1508959Y213016D01*
Y215802D01*
G01X1334883Y119082D02*
X1339897Y114068D01*
Y111419D01*
X1340053Y111042D01*
Y77740D01*
X1359476Y58317D01*
X1414188D01*
X1513584Y157713D01*
Y162098D01*
X1513074Y162608D01*
X1509187D01*
X1508677Y163118D01*
Y164608D01*
X1509187Y165118D01*
X1513074D01*
X1513584Y165628D01*
Y167118D01*
X1513074Y167628D01*
X1509187D01*
X1508677Y168138D01*
Y169628D01*
X1509187Y170138D01*
X1513074D01*
X1513584Y170648D01*
Y173058D01*
X1514094Y173568D01*
X1515528D01*
X1516038Y174078D01*
Y175568D01*
X1515528Y176078D01*
X1514094D01*
X1513584Y176588D01*
Y178078D01*
X1514094Y178588D01*
X1515528D01*
X1516038Y179098D01*
Y180588D01*
X1515528Y181098D01*
X1514094D01*
X1513584Y181608D01*
Y183679D01*
X1508940Y188323D01*
Y205435D01*
X1511110Y207605D01*
X1511832D01*
X1512988Y206449D01*
X1513710D01*
X1514763Y207502D01*
Y208224D01*
X1513607Y209380D01*
Y210102D01*
X1514660Y211155D01*
X1515382D01*
X1516538Y209999D01*
X1517260D01*
X1518313Y211052D01*
Y211774D01*
X1517157Y212930D01*
Y213652D01*
X1518110Y214605D01*
Y215551D01*
G01X1527732Y219488D02*
X1517427D01*
X1501553Y203614D01*
Y200730D01*
X1502063Y200220D01*
X1505197D01*
X1505707Y199710D01*
Y198220D01*
X1505197Y197710D01*
X1502063D01*
X1501553Y197200D01*
Y195710D01*
X1502063Y195200D01*
X1505197D01*
X1505707Y194690D01*
Y193200D01*
X1505197Y192690D01*
X1502063D01*
X1501553Y192180D01*
Y190690D01*
X1502063Y190180D01*
X1505197D01*
X1505707Y189670D01*
Y188180D01*
X1505197Y187670D01*
X1502063D01*
X1501553Y187160D01*
Y185670D01*
X1502063Y185160D01*
X1505197D01*
X1505707Y184650D01*
Y183160D01*
X1505197Y182650D01*
X1502063D01*
X1501553Y182140D01*
Y180650D01*
X1502063Y180140D01*
X1505197D01*
X1505707Y179630D01*
Y178140D01*
X1505197Y177630D01*
X1502063D01*
X1501553Y177120D01*
Y175630D01*
X1502063Y175120D01*
X1505197D01*
X1505707Y174610D01*
Y173120D01*
X1505197Y172610D01*
X1502063D01*
X1501553Y172100D01*
Y150357D01*
X1412333Y61137D01*
X1360647D01*
X1343250Y78534D01*
Y86042D01*
X1348002Y90794D01*
Y96760D01*
X1344348Y100414D01*
Y111702D01*
X1344132Y112224D01*
Y116205D01*
X1340254Y120083D01*
Y122410D01*
X1337943Y124721D01*
G01X1534194Y217519D02*
X1517454D01*
X1511242Y211307D01*
Y210022D01*
X1510109Y208889D01*
X1509545Y208890D01*
X1508825D01*
X1507117Y207182D01*
Y181397D01*
X1507627Y180887D01*
X1511664D01*
X1512174Y180377D01*
Y178887D01*
X1511664Y178377D01*
X1507627D01*
X1507117Y177867D01*
Y176377D01*
X1507627Y175867D01*
X1511664D01*
X1512174Y175357D01*
Y173867D01*
X1511664Y173357D01*
X1507627D01*
X1507117Y172847D01*
Y170437D01*
X1506607Y169927D01*
X1503473D01*
X1502963Y169417D01*
Y167927D01*
X1503473Y167417D01*
X1506607D01*
X1507117Y166907D01*
Y165417D01*
X1506607Y164907D01*
X1503473D01*
X1502963Y164397D01*
Y162907D01*
X1503473Y162397D01*
X1506607D01*
X1507117Y161887D01*
Y160397D01*
X1506607Y159887D01*
X1503473D01*
X1502963Y159377D01*
Y157887D01*
X1503473Y157377D01*
X1506607D01*
X1507117Y156867D01*
Y153241D01*
X1413603Y59727D01*
X1360061D01*
X1341463Y78325D01*
Y111323D01*
X1341322Y111664D01*
Y114641D01*
X1337114Y118849D01*
G01X1347640Y101950D02*
X1347315Y102275D01*
Y111910D01*
X1346952Y112787D01*
Y117423D01*
X1343454Y120921D01*
Y123942D01*
X1342519Y124877D01*
G01X1496720Y225292D02*
X1481020Y209592D01*
Y147662D01*
X1443256Y109898D01*
Y109176D01*
X1443606Y108826D01*
Y108104D01*
X1442553Y107051D01*
X1441831D01*
X1441481Y107401D01*
X1440759D01*
X1439706Y106348D01*
Y105626D01*
X1440056Y105276D01*
Y104554D01*
X1439003Y103501D01*
X1438281D01*
X1437931Y103851D01*
X1437209D01*
X1436156Y102798D01*
Y102076D01*
X1436506Y101726D01*
Y101004D01*
X1435453Y99951D01*
X1434731D01*
X1434381Y100301D01*
X1433659D01*
X1432606Y99248D01*
Y98526D01*
X1432956Y98176D01*
Y97454D01*
X1431903Y96401D01*
X1431181D01*
X1430831Y96751D01*
X1430109D01*
X1429056Y95698D01*
Y94976D01*
X1429406Y94626D01*
Y93904D01*
X1428353Y92851D01*
X1427631D01*
X1427281Y93201D01*
X1426559D01*
X1425506Y92148D01*
Y91426D01*
X1425856Y91076D01*
Y90354D01*
X1424803Y89301D01*
X1424081D01*
X1423731Y89651D01*
X1423009D01*
X1421956Y88598D01*
Y87876D01*
X1422306Y87526D01*
Y86804D01*
X1421253Y85751D01*
X1420531D01*
X1420181Y86101D01*
X1419459D01*
X1418406Y85048D01*
Y84326D01*
X1418756Y83976D01*
Y83254D01*
X1417703Y82201D01*
X1416981D01*
X1416631Y82551D01*
X1415909D01*
X1414856Y81498D01*
Y80776D01*
X1415206Y80426D01*
Y79704D01*
X1414153Y78651D01*
X1413431D01*
X1413081Y79001D01*
X1412359D01*
X1411306Y77948D01*
Y77226D01*
X1411656Y76876D01*
Y76154D01*
X1410603Y75101D01*
X1409881D01*
X1409531Y75451D01*
X1408809D01*
X1407079Y73721D01*
X1365555D01*
X1359513Y79763D01*
Y106251D01*
X1358819Y107927D01*
Y114396D01*
X1356932Y116283D01*
Y125311D01*
X1347257Y134986D01*
G01X1510017Y225516D02*
X1508016D01*
X1506147Y223647D01*
X1499695D01*
X1495143Y219095D01*
Y218373D01*
X1496307Y217209D01*
Y216487D01*
X1495254Y215434D01*
X1494532D01*
X1493368Y216598D01*
X1492646D01*
X1491593Y215545D01*
Y214823D01*
X1492757Y213659D01*
Y212937D01*
X1491704Y211884D01*
X1490982D01*
X1489818Y213048D01*
X1489096D01*
X1488043Y211995D01*
Y211273D01*
X1489207Y210109D01*
Y209387D01*
X1488154Y208334D01*
X1487432D01*
X1486268Y209498D01*
X1485546D01*
X1483840Y207792D01*
Y176753D01*
X1484350Y176243D01*
X1484500D01*
X1485010Y175733D01*
Y174243D01*
X1484500Y173733D01*
X1484350D01*
X1483840Y173223D01*
Y171733D01*
X1484350Y171223D01*
X1484500D01*
X1485010Y170713D01*
Y169223D01*
X1484500Y168713D01*
X1484350D01*
X1483840Y168203D01*
Y166713D01*
X1484350Y166203D01*
X1484500D01*
X1485010Y165693D01*
Y164203D01*
X1484500Y163693D01*
X1484350D01*
X1483840Y163183D01*
Y161693D01*
X1484350Y161183D01*
X1484500D01*
X1485010Y160673D01*
Y159183D01*
X1484500Y158673D01*
X1484350D01*
X1483840Y158163D01*
Y143996D01*
X1410745Y70901D01*
X1405842D01*
X1405332Y70391D01*
Y68697D01*
X1404822Y68187D01*
X1403332D01*
X1402822Y68697D01*
Y70391D01*
X1402312Y70901D01*
X1400822D01*
X1400312Y70391D01*
Y68697D01*
X1399802Y68187D01*
X1398312D01*
X1397802Y68697D01*
Y70391D01*
X1397292Y70901D01*
X1395802D01*
X1395292Y70391D01*
Y68697D01*
X1394782Y68187D01*
X1393292D01*
X1392782Y68697D01*
Y70391D01*
X1392272Y70901D01*
X1390782D01*
X1390272Y70391D01*
Y68697D01*
X1389762Y68187D01*
X1388272D01*
X1387762Y68697D01*
Y70391D01*
X1387252Y70901D01*
X1385762D01*
X1385252Y70391D01*
Y68697D01*
X1384742Y68187D01*
X1383252D01*
X1382742Y68697D01*
Y70391D01*
X1382232Y70901D01*
X1380742D01*
X1380232Y70391D01*
Y68697D01*
X1379722Y68187D01*
X1378232D01*
X1377722Y68697D01*
Y70391D01*
X1377212Y70901D01*
X1375722D01*
X1375212Y70391D01*
Y68697D01*
X1374702Y68187D01*
X1373212D01*
X1372702Y68697D01*
Y70391D01*
X1372192Y70901D01*
X1370702D01*
X1370192Y70391D01*
Y68697D01*
X1369682Y68187D01*
X1368192D01*
X1367682Y68697D01*
Y70391D01*
X1367172Y70901D01*
X1363551D01*
X1356693Y77759D01*
Y105689D01*
X1355972Y107430D01*
Y113117D01*
X1353997Y115092D01*
Y124989D01*
X1346174Y132812D01*
G01X1348939Y127227D02*
X1352587Y123579D01*
Y114507D01*
X1354562Y112532D01*
Y107149D01*
X1355283Y105408D01*
Y76399D01*
X1364905Y66777D01*
X1408616D01*
X1486420Y144581D01*
Y148163D01*
X1485910Y148673D01*
X1485760D01*
X1485250Y149183D01*
Y150673D01*
X1485760Y151183D01*
X1485910D01*
X1486420Y151693D01*
Y153183D01*
X1485910Y153693D01*
X1485760D01*
X1485250Y154203D01*
Y155693D01*
X1485760Y156203D01*
X1485910D01*
X1486420Y156713D01*
Y162382D01*
X1486930Y162892D01*
X1488303D01*
X1488813Y163402D01*
Y164892D01*
X1488303Y165402D01*
X1486930D01*
X1486420Y165912D01*
Y167402D01*
X1486930Y167912D01*
X1488303D01*
X1488813Y168422D01*
Y169912D01*
X1488303Y170422D01*
X1486930D01*
X1486420Y170932D01*
Y172422D01*
X1486930Y172932D01*
X1488303D01*
X1488813Y173442D01*
Y174932D01*
X1488303Y175442D01*
X1486930D01*
X1486420Y175952D01*
Y178362D01*
X1485250Y179532D01*
Y182130D01*
X1485760Y182640D01*
X1488303D01*
X1488813Y183150D01*
Y184640D01*
X1488303Y185150D01*
X1485760D01*
X1485250Y185660D01*
Y187150D01*
X1485760Y187660D01*
X1488303D01*
X1488813Y188170D01*
Y189660D01*
X1488303Y190170D01*
X1485760D01*
X1485250Y190680D01*
Y192170D01*
X1485760Y192680D01*
X1488303D01*
X1488813Y193190D01*
Y194680D01*
X1488303Y195190D01*
X1485760D01*
X1485250Y195700D01*
Y197190D01*
X1485760Y197700D01*
X1488303D01*
X1488813Y198210D01*
Y199700D01*
X1488303Y200210D01*
X1485760D01*
X1485250Y200720D01*
Y203432D01*
X1488785Y206967D01*
X1489507D01*
X1490630Y205844D01*
X1491352D01*
X1492405Y206897D01*
Y207619D01*
X1491282Y208742D01*
Y209464D01*
X1492335Y210517D01*
X1493057D01*
X1494180Y209394D01*
X1494902D01*
X1495955Y210447D01*
Y211169D01*
X1494832Y212292D01*
Y213014D01*
X1503973Y222155D01*
X1513477D01*
X1515284Y223962D01*
X1516730D01*
X1517240Y223452D01*
Y222818D01*
X1517750Y222308D01*
X1519240D01*
X1519750Y222818D01*
Y223452D01*
X1520260Y223962D01*
X1525000D01*
X1526152Y225114D01*
G01X1501840Y225502D02*
X1499555D01*
X1482430Y208377D01*
Y144931D01*
X1478718Y141219D01*
X1477996D01*
X1477726Y141489D01*
X1477004D01*
X1475951Y140436D01*
Y139714D01*
X1476221Y139444D01*
Y138722D01*
X1475168Y137669D01*
X1474446D01*
X1474176Y137939D01*
X1473454D01*
X1472401Y136886D01*
Y136164D01*
X1472671Y135894D01*
Y135172D01*
X1471618Y134119D01*
X1470896D01*
X1470626Y134389D01*
X1469904D01*
X1468851Y133336D01*
Y132614D01*
X1469121Y132344D01*
Y131622D01*
X1468068Y130569D01*
X1467346D01*
X1467076Y130839D01*
X1466354D01*
X1465301Y129786D01*
Y129064D01*
X1465571Y128794D01*
Y128072D01*
X1464518Y127019D01*
X1463796D01*
X1463526Y127289D01*
X1462804D01*
X1461751Y126236D01*
Y125514D01*
X1462021Y125244D01*
Y124522D01*
X1460968Y123469D01*
X1460246D01*
X1459976Y123739D01*
X1459254D01*
X1458201Y122686D01*
Y121964D01*
X1458471Y121694D01*
Y120972D01*
X1457418Y119919D01*
X1456696D01*
X1456426Y120189D01*
X1455704D01*
X1454651Y119136D01*
Y118414D01*
X1454921Y118144D01*
Y117422D01*
X1453868Y116369D01*
X1453146D01*
X1452876Y116639D01*
X1452154D01*
X1451101Y115586D01*
Y114864D01*
X1451371Y114594D01*
Y113872D01*
X1450318Y112819D01*
X1449596D01*
X1449326Y113089D01*
X1448604D01*
X1447551Y112036D01*
Y111314D01*
X1447821Y111044D01*
Y110322D01*
X1409810Y72311D01*
X1364970D01*
X1358103Y79178D01*
Y105970D01*
X1357401Y107666D01*
Y113808D01*
X1355507Y115702D01*
Y125109D01*
X1346564Y134052D01*
G01X1503020Y215802D02*
Y209073D01*
X1493776Y199829D01*
Y196686D01*
X1494286Y196176D01*
X1496180D01*
X1496690Y195666D01*
Y194176D01*
X1496180Y193666D01*
X1494286D01*
X1493776Y193156D01*
Y191666D01*
X1494286Y191156D01*
X1496180D01*
X1496690Y190646D01*
Y189156D01*
X1496180Y188646D01*
X1494286D01*
X1493776Y188136D01*
Y186646D01*
X1494286Y186136D01*
X1496180D01*
X1496690Y185626D01*
Y184136D01*
X1496180Y183626D01*
X1494286D01*
X1493776Y183116D01*
Y181626D01*
X1494286Y181116D01*
X1496180D01*
X1496690Y180606D01*
Y179116D01*
X1496180Y178606D01*
X1494286D01*
X1493776Y178096D01*
Y176606D01*
X1494286Y176096D01*
X1496180D01*
X1496690Y175586D01*
Y174096D01*
X1496180Y173586D01*
X1494286D01*
X1493776Y173076D01*
Y171586D01*
X1494286Y171076D01*
X1496180D01*
X1496690Y170566D01*
Y169076D01*
X1496180Y168566D01*
X1494286D01*
X1493776Y168056D01*
Y166566D01*
X1494286Y166056D01*
X1496180D01*
X1496690Y165546D01*
Y164056D01*
X1496180Y163546D01*
X1494286D01*
X1493776Y163036D01*
Y161546D01*
X1494286Y161036D01*
X1496180D01*
X1496690Y160526D01*
Y159036D01*
X1496180Y158526D01*
X1494286D01*
X1493776Y158016D01*
Y156526D01*
X1494286Y156016D01*
X1496180D01*
X1496690Y155506D01*
Y154016D01*
X1496180Y153506D01*
X1494286D01*
X1493776Y152996D01*
Y147344D01*
X1410389Y63957D01*
X1361818D01*
X1352422Y73353D01*
Y104533D01*
X1351742Y106175D01*
Y111362D01*
X1349767Y113337D01*
Y122230D01*
X1346900Y125097D01*
G01X1499922Y211240D02*
Y208708D01*
X1498073Y206859D01*
X1497351D01*
X1496310Y207900D01*
X1495588D01*
X1494535Y206847D01*
Y206125D01*
X1495576Y205084D01*
Y204362D01*
X1494523Y203309D01*
X1493801D01*
X1492760Y204350D01*
X1492038D01*
X1490985Y203297D01*
Y202575D01*
X1492026Y201534D01*
Y200812D01*
X1490223Y199009D01*
Y196599D01*
X1490733Y196089D01*
X1491856D01*
X1492366Y195579D01*
Y194089D01*
X1491856Y193579D01*
X1490733D01*
X1490223Y193069D01*
Y191579D01*
X1490733Y191069D01*
X1491856D01*
X1492366Y190559D01*
Y189069D01*
X1491856Y188559D01*
X1490733D01*
X1490223Y188049D01*
Y186559D01*
X1490733Y186049D01*
X1491856D01*
X1492366Y185539D01*
Y184049D01*
X1491856Y183539D01*
X1490733D01*
X1490223Y183029D01*
Y181539D01*
X1490733Y181029D01*
X1491856D01*
X1492366Y180519D01*
Y179029D01*
X1491856Y178519D01*
X1490733D01*
X1490223Y178009D01*
Y176519D01*
X1490733Y176009D01*
X1491856D01*
X1492366Y175499D01*
Y174009D01*
X1491856Y173499D01*
X1490733D01*
X1490223Y172989D01*
Y171499D01*
X1490733Y170989D01*
X1491856D01*
X1492366Y170479D01*
Y168989D01*
X1491856Y168479D01*
X1490733D01*
X1490223Y167969D01*
Y166479D01*
X1490733Y165969D01*
X1491856D01*
X1492366Y165459D01*
Y163969D01*
X1491856Y163459D01*
X1490733D01*
X1490223Y162949D01*
Y160688D01*
X1489713Y160178D01*
X1488340D01*
X1487830Y159668D01*
Y158178D01*
X1488340Y157668D01*
X1489713D01*
X1490223Y157158D01*
Y155668D01*
X1489713Y155158D01*
X1488340D01*
X1487830Y154648D01*
Y153158D01*
X1488340Y152648D01*
X1489713D01*
X1490223Y152138D01*
Y146389D01*
X1409201Y65367D01*
X1362404D01*
X1360822Y66949D01*
Y67671D01*
X1360983Y67832D01*
Y68554D01*
X1359930Y69607D01*
X1359208D01*
X1359047Y69446D01*
X1358325D01*
X1357272Y70499D01*
Y71221D01*
X1357433Y71382D01*
Y72104D01*
X1356380Y73157D01*
X1355658D01*
X1355497Y72996D01*
X1354775D01*
X1353832Y73939D01*
Y105224D01*
X1353152Y106866D01*
Y111947D01*
X1351177Y113922D01*
Y122749D01*
X1348094Y125832D01*
G01X1353089Y139457D02*
X1359786Y132760D01*
Y117579D01*
X1361639Y115726D01*
Y108489D01*
X1362350Y106772D01*
Y80916D01*
X1366725Y76541D01*
X1404023D01*
X1405729Y78247D01*
Y78969D01*
X1404967Y79731D01*
Y80453D01*
X1406020Y81506D01*
X1406742D01*
X1407504Y80744D01*
X1408226D01*
X1409279Y81797D01*
Y82519D01*
X1408517Y83281D01*
Y84003D01*
X1409570Y85056D01*
X1410292D01*
X1411054Y84294D01*
X1411776D01*
X1412829Y85347D01*
Y86069D01*
X1412067Y86831D01*
Y87553D01*
X1413120Y88606D01*
X1413842D01*
X1414604Y87844D01*
X1415326D01*
X1416379Y88897D01*
Y89619D01*
X1415617Y90381D01*
Y91103D01*
X1416670Y92156D01*
X1417392D01*
X1418154Y91394D01*
X1418876D01*
X1419929Y92447D01*
Y93169D01*
X1419167Y93931D01*
Y94653D01*
X1420220Y95706D01*
X1420942D01*
X1421704Y94944D01*
X1422426D01*
X1423479Y95997D01*
Y96719D01*
X1422717Y97481D01*
Y98203D01*
X1423770Y99256D01*
X1424492D01*
X1425254Y98494D01*
X1425976D01*
X1427029Y99547D01*
Y100269D01*
X1426267Y101031D01*
Y101753D01*
X1427320Y102806D01*
X1428042D01*
X1428804Y102044D01*
X1429526D01*
X1430579Y103097D01*
Y103819D01*
X1429817Y104581D01*
Y105303D01*
X1430870Y106356D01*
X1431592D01*
X1432354Y105594D01*
X1433076D01*
X1434129Y106647D01*
Y107369D01*
X1433367Y108131D01*
Y108853D01*
X1434420Y109906D01*
X1435142D01*
X1435904Y109144D01*
X1436626D01*
X1437679Y110197D01*
Y110919D01*
X1436917Y111681D01*
Y112403D01*
X1437970Y113456D01*
X1438692D01*
X1439454Y112694D01*
X1440176D01*
X1441229Y113747D01*
Y114469D01*
X1440467Y115231D01*
Y115953D01*
X1441520Y117006D01*
X1442242D01*
X1443004Y116244D01*
X1443726D01*
X1444779Y117297D01*
Y118019D01*
X1444017Y118781D01*
Y119503D01*
X1445070Y120556D01*
X1445792D01*
X1446554Y119794D01*
X1447276D01*
X1448329Y120847D01*
Y121569D01*
X1447567Y122331D01*
Y123053D01*
X1448620Y124106D01*
X1449342D01*
X1450104Y123344D01*
X1450826D01*
X1451879Y124397D01*
Y125119D01*
X1451117Y125881D01*
Y126603D01*
X1452170Y127656D01*
X1452892D01*
X1453654Y126894D01*
X1454376D01*
X1455429Y127947D01*
Y128669D01*
X1454667Y129431D01*
Y130153D01*
X1455720Y131206D01*
X1456442D01*
X1457204Y130444D01*
X1457926D01*
X1458979Y131497D01*
Y132219D01*
X1458217Y132981D01*
Y133703D01*
X1459270Y134756D01*
X1459992D01*
X1460754Y133994D01*
X1461476D01*
X1462529Y135047D01*
Y135769D01*
X1461767Y136531D01*
Y137253D01*
X1462820Y138306D01*
X1463542D01*
X1464304Y137544D01*
X1465026D01*
X1466079Y138597D01*
Y139319D01*
X1465317Y140081D01*
Y140803D01*
X1466370Y141856D01*
X1467092D01*
X1467854Y141094D01*
X1468576D01*
X1473266Y145784D01*
Y146506D01*
X1471974Y147798D01*
Y148520D01*
X1473027Y149573D01*
X1473749D01*
X1475041Y148281D01*
X1475763D01*
X1478200Y150718D01*
Y216670D01*
X1496092Y234562D01*
X1504484D01*
G01X1339727Y161149D02*
X1339183Y161693D01*
Y162751D01*
X1339431Y162999D01*
X1340799D01*
G01X1341992Y156897D02*
X1342544Y157449D01*
X1344005D01*
G01X1332268Y162999D02*
X1334390D01*
G01X1337594Y164849D02*
X1335472D01*
G01X1346140Y161149D02*
X1345735Y161554D01*
Y162697D01*
X1346037Y162999D01*
X1347210D01*
G01X1342937D02*
X1342438Y163498D01*
Y164549D01*
X1342738Y164849D01*
X1344005D01*
G01X1337594Y157449D02*
X1335472D01*
G01X1346140D02*
X1345688Y157901D01*
Y159018D01*
X1345969Y159299D01*
X1347210D01*
G01X1339727Y157449D02*
X1339221Y157955D01*
Y159051D01*
X1339469Y159299D01*
X1340799D01*
G01X1332268Y174099D02*
X1334390D01*
G01X1340799Y211099D02*
X1339727Y209249D01*
G01X1339821Y895146D02*
Y893036D01*
G01X1343521Y895146D02*
Y893036D01*
G01X1351434Y139002D02*
X1358376Y132060D01*
Y116994D01*
X1360229Y115141D01*
Y108208D01*
X1360923Y106532D01*
Y80348D01*
X1366140Y75131D01*
X1404613D01*
X1406834Y77352D01*
X1407556D01*
X1407774Y77134D01*
X1408496D01*
X1409549Y78187D01*
Y78909D01*
X1409331Y79127D01*
Y79849D01*
X1410384Y80902D01*
X1411106D01*
X1411324Y80684D01*
X1412046D01*
X1413099Y81737D01*
Y82459D01*
X1412881Y82677D01*
Y83399D01*
X1413934Y84452D01*
X1414656D01*
X1414874Y84234D01*
X1415596D01*
X1416649Y85287D01*
Y86009D01*
X1416431Y86227D01*
Y86949D01*
X1417484Y88002D01*
X1418206D01*
X1418424Y87784D01*
X1419146D01*
X1420199Y88837D01*
Y89559D01*
X1419981Y89777D01*
Y90499D01*
X1421034Y91552D01*
X1421756D01*
X1421974Y91334D01*
X1422696D01*
X1423749Y92387D01*
Y93109D01*
X1423531Y93327D01*
Y94049D01*
X1424584Y95102D01*
X1425306D01*
X1425524Y94884D01*
X1426246D01*
X1427299Y95937D01*
Y96659D01*
X1427081Y96877D01*
Y97599D01*
X1428134Y98652D01*
X1428856D01*
X1429074Y98434D01*
X1429796D01*
X1430849Y99487D01*
Y100209D01*
X1430631Y100427D01*
Y101149D01*
X1431684Y102202D01*
X1432406D01*
X1432624Y101984D01*
X1433346D01*
X1434399Y103037D01*
Y103759D01*
X1434181Y103977D01*
Y104699D01*
X1435234Y105752D01*
X1435956D01*
X1436174Y105534D01*
X1436896D01*
X1437949Y106587D01*
Y107309D01*
X1437731Y107527D01*
Y108249D01*
X1438784Y109302D01*
X1439506D01*
X1439724Y109084D01*
X1440446D01*
X1441499Y110137D01*
Y110859D01*
X1441281Y111077D01*
Y111799D01*
X1442334Y112852D01*
X1443056D01*
X1443274Y112634D01*
X1443996D01*
X1445049Y113687D01*
Y114409D01*
X1444831Y114627D01*
Y115349D01*
X1445884Y116402D01*
X1446606D01*
X1446824Y116184D01*
X1447546D01*
X1448599Y117237D01*
Y117959D01*
X1448381Y118177D01*
Y118899D01*
X1449434Y119952D01*
X1450156D01*
X1450374Y119734D01*
X1451096D01*
X1452149Y120787D01*
Y121509D01*
X1451931Y121727D01*
Y122449D01*
X1452984Y123502D01*
X1453706D01*
X1453924Y123284D01*
X1454646D01*
X1455699Y124337D01*
Y125059D01*
X1455481Y125277D01*
Y125999D01*
X1456534Y127052D01*
X1457256D01*
X1457474Y126834D01*
X1458196D01*
X1459249Y127887D01*
Y128609D01*
X1459031Y128827D01*
Y129549D01*
X1460084Y130602D01*
X1460806D01*
X1461024Y130384D01*
X1461746D01*
X1462799Y131437D01*
Y132159D01*
X1462581Y132377D01*
Y133099D01*
X1463634Y134152D01*
X1464356D01*
X1464574Y133934D01*
X1465296D01*
X1466349Y134987D01*
Y135709D01*
X1466131Y135927D01*
Y136649D01*
X1467184Y137702D01*
X1467906D01*
X1468124Y137484D01*
X1468846D01*
X1469899Y138537D01*
Y139259D01*
X1469681Y139477D01*
Y140199D01*
X1470734Y141252D01*
X1471456D01*
X1471674Y141034D01*
X1472396D01*
X1473449Y142087D01*
Y142809D01*
X1473231Y143027D01*
Y143749D01*
X1474284Y144802D01*
X1475006D01*
X1475224Y144584D01*
X1475946D01*
X1476999Y145637D01*
Y146359D01*
X1476780Y146578D01*
Y147298D01*
X1479610Y150132D01*
Y216085D01*
X1481440Y217915D01*
X1482162D01*
X1484148Y215929D01*
X1484870D01*
X1485923Y216982D01*
Y217704D01*
X1483937Y219690D01*
Y220412D01*
X1484990Y221465D01*
X1485712D01*
X1487698Y219479D01*
X1488420D01*
X1489473Y220532D01*
Y221254D01*
X1487487Y223240D01*
Y223962D01*
X1488540Y225015D01*
X1489262D01*
X1491248Y223029D01*
X1491970D01*
X1493023Y224082D01*
Y224804D01*
X1491037Y226790D01*
Y227512D01*
X1494387Y230862D01*
X1496797D01*
X1497307Y230352D01*
Y228226D01*
X1497817Y227716D01*
X1499307D01*
X1499817Y228226D01*
Y230352D01*
X1500327Y230862D01*
X1501817D01*
X1502327Y230352D01*
Y228226D01*
X1502837Y227716D01*
X1504327D01*
X1504837Y228226D01*
Y230352D01*
X1505347Y230862D01*
X1508390D01*
X1508410Y230842D01*
G01X1347640Y101950D02*
Y101452D01*
X1350822Y98270D01*
Y78414D01*
X1349480Y77072D01*
G01X1366001Y95520D02*
X1364034Y97487D01*
Y107001D01*
X1363604Y107431D01*
X1363049Y108771D01*
Y116311D01*
X1361196Y118164D01*
Y133519D01*
G01X1366124Y107104D02*
X1365926D01*
X1364801Y108229D01*
X1364459Y109054D01*
Y116896D01*
X1362606Y118749D01*
Y133453D01*
G01X1364016Y133543D02*
Y119334D01*
X1365869Y117481D01*
Y113103D01*
X1367177Y111795D01*
X1367780Y111545D01*
X1368751D01*
X1369294Y111002D01*
Y107388D01*
X1373244Y103438D01*
Y100142D01*
X1371799Y98697D01*
X1370779D01*
X1369806Y97724D01*
Y95270D01*
X1370464Y94612D01*
Y89118D01*
X1377020Y82562D01*
X1399110D01*
X1461320Y144772D01*
Y147062D01*
X1467761Y153503D01*
Y205982D01*
G01X1463000Y158937D02*
X1459895Y155832D01*
X1449190D01*
X1444300Y150942D01*
Y133050D01*
X1396822Y85572D01*
X1383730D01*
X1381802Y87500D01*
X1381782D01*
X1376073Y93209D01*
Y105089D01*
X1372261Y108901D01*
Y117075D01*
X1368246Y121090D01*
Y136011D01*
X1364551Y139706D01*
X1362704D01*
G01X1457361Y205982D02*
Y197410D01*
X1461680Y193091D01*
Y165922D01*
X1459580Y163822D01*
X1456410D01*
X1456050Y164182D01*
X1446480D01*
X1440811Y158513D01*
Y133553D01*
X1403420Y96162D01*
X1381994D01*
X1378893Y99263D01*
Y107559D01*
X1375578Y110874D01*
Y119902D01*
X1372140Y123340D01*
Y137343D01*
X1366498Y142985D01*
X1363314D01*
G01X1459961Y210432D02*
Y198730D01*
X1463170Y195521D01*
Y163312D01*
X1459850Y159992D01*
X1456130D01*
X1455380Y159242D01*
X1449960D01*
X1449210Y159992D01*
X1445830D01*
X1442600Y156762D01*
Y133346D01*
X1400516Y91262D01*
X1384832D01*
X1377483Y98611D01*
Y106250D01*
X1374124Y109609D01*
Y118242D01*
X1370210Y122156D01*
Y137012D01*
X1365700Y141522D01*
X1362341D01*
X1359738Y144125D01*
G01X1456150Y214382D02*
X1459800D01*
X1465161Y209021D01*
Y203302D01*
X1466279Y202184D01*
Y154521D01*
X1463030Y151272D01*
X1456550D01*
X1456240Y150962D01*
X1447450D01*
X1446202Y149714D01*
Y132956D01*
X1397308Y84062D01*
X1378791D01*
X1374663Y88190D01*
Y104099D01*
X1370851Y107911D01*
Y116489D01*
X1366836Y120504D01*
Y135139D01*
X1364039Y137936D01*
G01X1368124Y114039D02*
Y117221D01*
X1365426Y119919D01*
Y133771D01*
X1363005Y136192D01*
G01X1353620Y159299D02*
X1352550Y157449D01*
G01X1355961Y155458D02*
X1356090D01*
X1356825Y156193D01*
Y157449D01*
G01X1394550Y104022D02*
X1388390Y110182D01*
Y122652D01*
X1380010Y131032D01*
Y138015D01*
X1373993Y144032D01*
Y155231D01*
X1371418Y157806D01*
G01X1350414Y164849D02*
X1349344Y162999D01*
G01X1348386Y156646D02*
X1349189Y157449D01*
X1350414D01*
G01X1353620Y162999D02*
X1352551Y161148D01*
G01X1375619Y236261D02*
X1372124D01*
X1371405Y236980D01*
X1364001D01*
G01X1411094Y255322D02*
X1400994D01*
X1390414Y244742D01*
Y238393D01*
X1385713Y233692D01*
X1382183D01*
X1371998Y223507D01*
X1371638D01*
G01X1769976Y470193D02*
Y470293D01*
X1759300Y480969D01*
Y563462D01*
X1750125Y572637D01*
X1650695D01*
X1633730Y555672D01*
X1544260D01*
X1490120Y609812D01*
Y621632D01*
X1475877Y635875D01*
X1380267D01*
X1359397Y656745D01*
Y673735D01*
X1356047Y677085D01*
Y680000D01*
G01X1835516Y467321D02*
Y502948D01*
X1763952Y574512D01*
X1649918D01*
X1632953Y557547D01*
X1545385D01*
X1492730Y610202D01*
Y621674D01*
X1476654Y637750D01*
X1380812D01*
X1361727Y656835D01*
Y680665D01*
G01X1351354Y1096907D02*
Y1099017D01*
G01X1351363Y1334095D02*
X1352264Y1333194D01*
Y1328321D01*
X1353505Y1327080D01*
X1353731Y1326535D01*
Y1325260D01*
G01X1365235Y1428637D02*
X1361447Y1424849D01*
Y1402145D01*
X1366724Y1396868D01*
X1371063D01*
X1373248Y1399053D01*
G01X1366001Y95520D02*
X1363800Y93319D01*
Y81461D01*
X1367310Y77951D01*
X1400468D01*
X1466220Y143703D01*
Y144763D01*
X1476120Y154663D01*
Y217062D01*
X1500720Y241662D01*
Y250462D01*
X1504650Y254392D01*
G01X1472335Y209362D02*
Y206926D01*
X1469520Y204111D01*
Y176907D01*
X1472475Y173952D01*
Y155818D01*
X1463020Y146363D01*
Y144477D01*
X1399605Y81062D01*
X1376319D01*
X1368703Y88678D01*
Y93132D01*
X1368396Y93439D01*
Y100583D01*
X1368703Y100890D01*
Y104525D01*
X1366124Y107104D01*
G01X1371004Y155412D02*
X1371629Y154787D01*
Y141294D01*
X1374700Y138223D01*
Y125586D01*
X1378550Y121736D01*
G01X1381940Y104063D02*
Y118346D01*
X1378550Y121736D01*
G01X1388340Y104132D02*
Y105612D01*
X1385380Y108572D01*
Y121404D01*
X1377420Y129364D01*
Y138463D01*
X1372813Y143070D01*
Y154943D01*
X1371324Y156432D01*
G01X1372600Y159538D02*
X1376383Y155755D01*
Y145439D01*
X1393470Y128352D01*
X1410452D01*
X1411837Y126967D01*
G01X1373298Y160256D02*
X1377553Y156001D01*
Y146568D01*
X1384709Y139412D01*
X1386900D01*
X1394941Y131371D01*
X1410052D01*
X1411685Y133004D01*
G01X1371953Y158680D02*
X1375153Y155480D01*
Y144444D01*
X1382160Y137437D01*
Y135118D01*
X1392306Y124972D01*
X1408137D01*
X1411875Y121234D01*
G01X1381235Y236020D02*
X1377777Y232562D01*
X1371983D01*
X1371217Y233328D01*
X1364407D01*
G01X1418034Y244822D02*
X1416048Y246808D01*
X1399820D01*
X1394484Y241472D01*
Y237432D01*
X1387104Y230052D01*
X1384010D01*
X1374260Y220302D01*
X1369974D01*
G01X1410833Y249912D02*
X1400983D01*
X1393334Y242263D01*
Y237903D01*
X1386673Y231242D01*
X1383425D01*
X1373435Y221252D01*
G01X1416694Y252432D02*
X1400784D01*
X1391794Y243442D01*
Y238092D01*
X1386184Y232482D01*
X1383045D01*
X1373116Y222553D01*
X1372592D01*
G01X1412194Y242692D02*
X1410374Y244512D01*
X1399354D01*
X1396114Y241272D01*
Y237472D01*
X1387571Y228929D01*
X1384881D01*
X1375304Y219352D01*
X1371024D01*
G01X1835516Y463193D02*
Y463293D01*
X1838150Y465927D01*
Y507492D01*
X1769420Y576222D01*
X1648500D01*
X1635270Y562992D01*
X1550739D01*
X1499732Y613999D01*
Y622373D01*
X1478910Y643195D01*
X1383247D01*
X1369710Y656732D01*
Y681748D01*
X1370207Y682245D01*
G01X1378670Y898350D02*
X1378671Y898349D01*
Y896240D01*
G01X1376821Y901555D02*
Y899446D01*
X1376820Y899445D01*
G01X1369421Y895146D02*
Y893036D01*
G01X1373121Y895146D02*
Y893036D01*
G01X1374970Y898350D02*
X1374971Y898349D01*
Y896240D01*
G01X1376821Y895146D02*
X1376820Y895145D01*
Y893036D01*
G01X1376821Y907963D02*
X1376820Y907962D01*
Y905853D01*
G01X1378670Y917576D02*
Y915467D01*
X1378671Y915466D01*
G01X1378670Y911167D02*
Y909058D01*
X1378671Y909057D01*
G01X1376821Y914372D02*
X1376820Y914371D01*
Y912262D01*
G01X1378670Y904759D02*
Y902650D01*
X1378671Y902649D01*
G01X1378670Y923985D02*
Y921876D01*
X1378671Y921875D01*
G01X1378670Y962436D02*
Y960327D01*
X1378671Y960326D01*
G01X1378670Y968845D02*
Y966736D01*
X1378671Y966735D01*
G01X1377254Y1007187D02*
X1377253Y1007188D01*
Y1009297D01*
G01X1379103Y1010391D02*
X1379104Y1010392D01*
Y1012501D01*
G01X1377254Y1013595D02*
Y1015704D01*
X1377253Y1015705D01*
G01X1379103Y1029617D02*
X1379104Y1029618D01*
Y1031727D01*
G01X1379103Y1036026D02*
Y1038135D01*
X1379104Y1038136D01*
G01X1377254Y1045639D02*
X1377253D01*
Y1047749D01*
G01X1379103Y1055251D02*
X1379104Y1055252D01*
Y1057361D01*
G01X1379103Y1061660D02*
X1379104Y1061661D01*
Y1063770D01*
G01X1377254Y1058455D02*
Y1060564D01*
X1377255Y1060565D01*
G01X1375403Y1061660D02*
X1375404Y1061661D01*
Y1063770D01*
G01X1377254Y1052047D02*
X1377253Y1052048D01*
Y1054157D01*
G01X1379103Y1048842D02*
Y1050951D01*
X1379104Y1050952D01*
G01X1379103Y1074477D02*
Y1076586D01*
X1379104Y1076587D01*
G01X1379103Y1068068D02*
X1379104Y1068069D01*
Y1070178D01*
G01X1377254Y1066974D02*
Y1064864D01*
G01X1375403Y1119337D02*
Y1121446D01*
X1375404Y1121447D01*
G01X1382347Y1394028D02*
X1377054D01*
G01X1379470Y1400684D02*
X1378757Y1399971D01*
Y1399185D01*
X1377327Y1397755D01*
X1374698D01*
X1373400Y1399053D01*
X1373248D01*
G01X1367620Y1431472D02*
X1368680Y1430412D01*
Y1428142D01*
X1363357Y1422819D01*
Y1404555D01*
X1366454Y1401458D01*
X1371076D01*
X1373076Y1403458D01*
X1373191D01*
G01X1379470Y1404207D02*
X1378970Y1404707D01*
X1374440D01*
X1373191Y1403458D01*
G01X1367436Y1414778D02*
Y1416408D01*
X1368402Y1417374D01*
X1370051D01*
G01X1381066Y1419428D02*
X1377097D01*
G01D02*
X1377075Y1419406D01*
G01X1378660Y1428340D02*
X1379070Y1427930D01*
Y1421401D01*
X1377097Y1419428D01*
G01X1370250Y1433715D02*
X1372260Y1431705D01*
Y1428842D01*
X1365247Y1421829D01*
Y1406417D01*
X1366066Y1405598D01*
X1371331D01*
X1373191Y1407458D01*
G01X1379465Y1407727D02*
X1373460D01*
X1373191Y1407458D01*
G01X1377075Y1422556D02*
Y1425014D01*
G01X1380521Y895146D02*
Y893037D01*
X1380520Y893036D01*
G01X1380521Y901555D02*
Y899446D01*
X1380520Y899445D01*
G01X1393470Y911167D02*
Y909058D01*
X1393471Y909057D01*
G01X1382370Y911167D02*
X1382371Y911166D01*
Y909057D01*
G01X1389770Y911167D02*
Y909058D01*
X1389771Y909057D01*
G01X1389770Y917576D02*
X1389771Y917575D01*
Y915466D01*
G01X1382370Y917576D02*
Y915467D01*
X1382371Y915466D01*
G01X1384221Y914372D02*
Y912263D01*
X1384220Y912262D01*
G01X1382370Y904759D02*
Y902650D01*
X1382371Y902649D01*
G01X1391621Y907963D02*
Y905854D01*
X1391620Y905853D01*
G01X1387921Y914372D02*
X1387920Y914371D01*
Y912262D01*
G01X1391621Y914372D02*
X1391620Y914371D01*
Y912262D01*
G01X1393470Y917576D02*
X1393471Y917575D01*
Y915466D01*
G01X1384221Y920780D02*
Y918671D01*
X1384220Y918670D01*
G01X1382370Y923985D02*
X1382371Y923984D01*
Y921875D01*
G01X1393470Y923985D02*
Y921876D01*
X1393471Y921875D01*
G01X1389770Y923985D02*
X1390617Y924832D01*
X1391550Y925219D01*
G01X1391621Y918670D02*
Y920780D01*
G01X1387921Y918670D02*
Y920780D01*
G01X1392054Y1045639D02*
Y1047748D01*
X1392053Y1047749D01*
G01X1382803Y1042434D02*
Y1044543D01*
X1382804Y1044544D01*
G01X1386503Y1042434D02*
Y1044543D01*
X1386504Y1044544D01*
G01X1384654Y1045639D02*
X1384653D01*
Y1047749D01*
G01X1390203Y1042434D02*
Y1044543D01*
X1390204Y1044544D01*
G01X1382803Y1048842D02*
Y1050951D01*
X1382804Y1050952D01*
G01X1382803Y1055251D02*
X1382804Y1055252D01*
Y1057361D01*
G01X1386503Y1055251D02*
X1386504Y1055252D01*
Y1057361D01*
G01X1390203Y1048842D02*
X1390204Y1048843D01*
Y1050952D01*
G01X1393903Y1055251D02*
X1393904Y1055252D01*
Y1057361D01*
G01X1382803Y1061660D02*
X1382804Y1061661D01*
Y1063770D01*
G01X1384654Y1058455D02*
Y1060564D01*
X1384653Y1060565D01*
G01X1386503Y1061660D02*
X1386504Y1061661D01*
Y1063770D01*
G01X1388354Y1052047D02*
Y1054156D01*
X1388353Y1054157D01*
G01X1380954Y1052047D02*
X1380953Y1052048D01*
Y1054157D01*
G01X1390203Y1055251D02*
X1390204Y1055252D01*
Y1057361D01*
G01X1393903Y1061660D02*
X1393904Y1061661D01*
Y1063770D01*
G01X1390203Y1061660D02*
Y1063769D01*
X1390204Y1063770D01*
G01X1384654Y1071273D02*
X1384653Y1071274D01*
Y1073383D01*
G01X1382803Y1068068D02*
Y1070177D01*
X1382804Y1070178D01*
G01X1380954Y1071273D02*
X1380953Y1071274D01*
Y1073383D01*
G01X1393904Y1076587D02*
X1393903Y1076586D01*
Y1074477D01*
G01X1384654Y1064864D02*
X1384653Y1064865D01*
Y1066974D01*
G01X1388354Y1071273D02*
Y1073382D01*
X1388353Y1073383D01*
G01X1392054Y1071273D02*
Y1073382D01*
X1392053Y1073383D01*
G01X1390203Y1068068D02*
X1390204Y1068069D01*
Y1070178D01*
G01X1393903Y1068068D02*
X1393904Y1068069D01*
Y1070178D01*
G01X1388354Y1064864D02*
X1388353Y1064865D01*
Y1066974D01*
G01X1390203Y1095813D02*
Y1093703D01*
G01X1385109Y1334095D02*
X1384392Y1333378D01*
Y1328321D01*
X1385633Y1327080D01*
X1385859Y1326535D01*
Y1325260D01*
G01X1382620Y1400684D02*
X1386016D01*
X1387066Y1401734D01*
G01D02*
X1389676Y1404344D01*
Y1404793D01*
X1390585Y1405702D01*
X1392296D01*
G01Y1407277D02*
X1389382D01*
X1387262Y1405157D01*
G01D02*
X1387018Y1404913D01*
X1383326D01*
X1382620Y1404207D01*
G01X1387470Y1418302D02*
X1390621Y1415151D01*
X1392296D01*
G01Y1410427D02*
X1385109D01*
G01D02*
X1384305Y1411231D01*
X1382615D01*
G01X1381066Y1419428D02*
X1385066D01*
G01D02*
X1386083Y1420445D01*
X1388477D01*
X1389962Y1418960D01*
Y1417910D01*
X1391146Y1416726D01*
X1392296D01*
G01X1383429Y1427652D02*
X1385130D01*
X1387440Y1425342D01*
Y1423522D01*
X1391086Y1419876D01*
X1392296D01*
G01X1390170Y1423942D02*
Y1422422D01*
X1391142Y1421450D01*
X1392296D01*
G01Y1408852D02*
X1388154D01*
X1387465Y1408163D01*
X1387291D01*
G01D02*
X1383051D01*
X1382615Y1407727D01*
G01X1392296Y1413576D02*
X1390196D01*
X1389135Y1414637D01*
X1388965D01*
X1388056Y1415546D01*
G01D02*
X1387311Y1416291D01*
X1386419Y1416661D01*
X1385753Y1417106D01*
X1385007Y1417415D01*
X1382727D01*
X1381062Y1415750D01*
Y1415495D01*
G01X1387068Y1413991D02*
X1386087Y1414972D01*
X1384735D01*
X1384212Y1415495D01*
G01X1434720Y1454862D02*
X1435920Y1453662D01*
Y1451334D01*
X1434700Y1450114D01*
X1403820D01*
X1401262Y1452672D01*
X1388161D01*
X1382910Y1447421D01*
Y1428171D01*
X1383429Y1427652D01*
G01X1390170Y1423942D02*
Y1425837D01*
X1385720Y1430287D01*
G01X1440440Y1454892D02*
X1437630Y1452082D01*
Y1450604D01*
X1435430Y1448404D01*
X1403110D01*
X1400552Y1450962D01*
X1388870D01*
X1384620Y1446712D01*
Y1434537D01*
X1385720Y1433437D01*
G01X1394833Y1565037D02*
X1391055D01*
G01X1394833Y1570037D02*
X1391655D01*
G01X1393000Y1590300D02*
Y1589300D01*
X1394000Y1588300D01*
X1402100D01*
X1402475Y1587925D01*
Y1586400D01*
G01X1386600Y1641400D02*
X1392200Y1635800D01*
Y1597800D01*
X1394100Y1595900D01*
X1400475D01*
X1402375Y1594000D01*
X1402475D01*
G01X1395325Y1609522D02*
Y1606862D01*
G01X1386200Y1645700D02*
X1387000D01*
X1397900Y1634800D01*
Y1624000D01*
X1399100Y1622800D01*
X1402400D01*
X1406900Y1618300D01*
X1417700D01*
X1420500Y1621100D01*
X1428000D01*
X1428800Y1620300D01*
X1436225D01*
G01X1406421Y875920D02*
Y873811D01*
X1406420Y873810D01*
G01X1399021Y914372D02*
X1399020Y914371D01*
Y912262D01*
G01X1400870Y917576D02*
X1400871Y917575D01*
Y915466D01*
G01X1402721Y914372D02*
X1402720Y914371D01*
Y912262D01*
G01X1406421Y914372D02*
X1406420Y914371D01*
Y912262D01*
G01X1408270Y917576D02*
X1408271Y917575D01*
Y915466D01*
G01X1397170Y911167D02*
X1397171Y911166D01*
Y909057D01*
G01X1408270D02*
Y911167D01*
G01X1410121Y907963D02*
X1410120Y907962D01*
Y905853D01*
G01X1400870Y909057D02*
Y911167D01*
G01X1399021Y907963D02*
Y905854D01*
X1399020Y905853D01*
G01X1406421Y907963D02*
X1406420Y907962D01*
Y905853D01*
G01X1402721Y907963D02*
Y905854D01*
X1402720Y905853D01*
G01X1397170Y917576D02*
X1397171Y917575D01*
Y915466D01*
G01X1410121Y914372D02*
Y912262D01*
G01X1406421Y920780D02*
X1406420Y920779D01*
Y918670D01*
G01X1408270Y923985D02*
Y921876D01*
X1408271Y921875D01*
G01X1410121Y920780D02*
Y918670D01*
G01X1400870Y923985D02*
X1400871Y923984D01*
Y921875D01*
G01X1399021Y920780D02*
Y918671D01*
X1399020Y918670D01*
G01X1397170Y923985D02*
X1397171Y923984D01*
Y921875D01*
G01X1402721Y920780D02*
Y918671D01*
X1402720Y918670D01*
G01X1406421Y927189D02*
X1406420Y927188D01*
Y925079D01*
G01X1408270Y930393D02*
X1408271Y930392D01*
Y928283D01*
G01X1406421Y933598D02*
X1406420Y933597D01*
Y931488D01*
G01X1408270Y936801D02*
X1408271Y936800D01*
Y934691D01*
G01X1403154Y1045639D02*
Y1047748D01*
X1403153Y1047749D01*
G01X1403154Y1039230D02*
Y1041340D01*
G01X1397603Y1042434D02*
Y1044543D01*
X1397604Y1044544D01*
G01X1395754Y1045639D02*
X1395753D01*
Y1047749D01*
G01X1403154Y1052047D02*
X1403153Y1052048D01*
Y1054157D01*
G01X1406853Y1052047D02*
Y1054157D01*
G01X1405003Y1057361D02*
X1405004Y1057360D01*
Y1055252D01*
X1405003Y1055251D01*
G01X1408703D02*
Y1057361D01*
G01Y1061660D02*
Y1063770D01*
G01X1397603Y1055251D02*
X1397604Y1055252D01*
Y1057361D01*
G01X1401303Y1048842D02*
X1401304Y1048843D01*
Y1050952D01*
G01X1399454Y1052047D02*
Y1054156D01*
X1399453Y1054157D01*
G01X1405003Y1048842D02*
X1405004Y1048843D01*
Y1050952D01*
G01X1397603Y1048842D02*
X1397604Y1048843D01*
Y1050952D01*
G01X1395754Y1052047D02*
X1395753Y1052048D01*
Y1054157D01*
G01X1401303Y1061660D02*
X1401304Y1063770D01*
G01X1395754Y1058455D02*
Y1060564D01*
X1395753Y1060565D01*
G01X1399453D02*
X1399454Y1060564D01*
Y1058455D01*
G01X1403154D02*
Y1060564D01*
X1403153Y1060565D01*
G01X1405003Y1063770D02*
X1405004Y1063769D01*
Y1061661D01*
X1405003Y1061660D01*
G01X1406853Y1058455D02*
Y1060565D01*
G01X1395754Y1077681D02*
Y1079790D01*
X1395753Y1079791D01*
G01X1397603Y1074477D02*
Y1076586D01*
X1397604Y1076587D01*
G01X1408702Y1070178D02*
X1408703Y1070177D01*
Y1068068D01*
G01X1399454Y1071273D02*
X1399453Y1071274D01*
Y1073383D01*
G01X1397603Y1068068D02*
Y1070177D01*
X1397604Y1070178D01*
G01X1395754Y1064864D02*
Y1066973D01*
X1395753Y1066974D01*
G01X1401303Y1068068D02*
X1401304Y1070178D01*
G01X1405003Y1068068D02*
X1405004Y1070178D01*
G01X1406853Y1064864D02*
Y1066974D01*
G01X1395754Y1099017D02*
Y1096907D01*
G01X1420408Y1516435D02*
X1417961Y1518882D01*
X1411455D01*
X1409008Y1516435D01*
G01X1397025Y1521362D02*
Y1519837D01*
X1398000Y1518862D01*
X1400220D01*
G01D02*
X1408498D01*
X1409008Y1518352D01*
Y1516435D01*
G01X1420408Y1521335D02*
X1417381Y1524362D01*
X1410350D01*
X1409008Y1523020D01*
Y1521335D01*
G01D02*
X1406781Y1523562D01*
X1402375D01*
X1400175Y1521362D01*
G01X1409248Y1537155D02*
X1407155Y1535062D01*
X1402175D01*
X1400075Y1537162D01*
G01X1409248Y1532255D02*
Y1528862D01*
G01X1420648Y1532255D02*
X1418201Y1534702D01*
X1410340D01*
X1409248Y1533610D01*
Y1532255D01*
G01Y1528862D02*
X1401200D01*
X1396925Y1533137D01*
Y1537162D01*
G01X1420648Y1537155D02*
X1417621Y1540182D01*
X1410590D01*
X1409248Y1538840D01*
Y1537155D01*
G01X1409398Y1548375D02*
X1407511Y1550262D01*
X1401975D01*
X1400075Y1548362D01*
G01X1420798Y1548375D02*
X1418211Y1550962D01*
X1410800D01*
X1409398Y1549560D01*
Y1548375D01*
G01X1420798Y1543475D02*
X1418351Y1545922D01*
X1410560D01*
X1409398Y1544760D01*
Y1543475D01*
G01D02*
X1406785Y1540862D01*
X1402640D01*
X1400160Y1543342D01*
G01D02*
X1396925Y1546577D01*
Y1548362D01*
G01X1397983Y1565037D02*
X1400715D01*
G01D02*
X1403910Y1561842D01*
X1406788D01*
X1409983Y1565037D01*
G01X1397983Y1570037D02*
X1400695D01*
G01X1415368Y1569131D02*
X1414052D01*
X1413146Y1570037D01*
X1409983D01*
G01X1400695D02*
X1403840Y1573182D01*
X1406838D01*
X1409983Y1570037D01*
G01X1409923Y1576197D02*
X1409968Y1576242D01*
X1414740D01*
X1416060Y1574922D01*
G01X1398157Y1576097D02*
X1402536D01*
G01D02*
X1406673D01*
X1406773Y1576197D01*
G01X1402475Y1586400D02*
Y1582500D01*
G01X1408260Y1583441D02*
X1406441D01*
X1405500Y1582500D01*
X1402475D01*
G01X1415740Y1588559D02*
Y1590460D01*
X1415200Y1591000D01*
X1410300D01*
X1409200Y1592100D01*
Y1593600D01*
X1409483Y1593883D01*
G01D02*
X1411818D01*
X1412001Y1593700D01*
X1414825D01*
G01X1408260Y1586000D02*
X1406400D01*
X1405500Y1586900D01*
Y1589500D01*
X1404800Y1590200D01*
X1402475D01*
G01D02*
X1402384Y1590291D01*
Y1592259D01*
X1402383Y1592260D01*
Y1593908D01*
X1402475Y1594000D01*
G01X1402680Y1603347D02*
X1398710D01*
X1398700Y1603357D01*
G01X1398475Y1609522D02*
X1398700Y1609297D01*
Y1603357D01*
G01X1398475Y1609522D02*
X1401920D01*
X1403250Y1608192D01*
G01D02*
X1405601Y1605841D01*
X1408250D01*
G01X1401300Y1619917D02*
X1404817Y1616400D01*
X1419300D01*
X1422024Y1619124D01*
X1426823D01*
X1427285Y1618662D01*
Y1616932D01*
G01X1405575Y1626362D02*
Y1630362D01*
G01Y1634362D02*
Y1630362D01*
G01X1402425Y1626362D02*
X1400000D01*
G01X1405575Y1642362D02*
Y1638362D01*
G01X1415760Y1637362D02*
X1412000D01*
X1410500Y1638862D01*
G01X1405575Y1638362D02*
X1410000D01*
X1410500Y1638862D01*
G01Y1633862D02*
X1410000Y1634362D01*
X1405575D01*
G01X1410500Y1633862D02*
X1411441Y1634803D01*
X1415760D01*
G01X1396900Y1642100D02*
X1400500Y1645700D01*
X1433500D01*
X1436225Y1642975D01*
Y1632900D01*
G01X1424458Y227948D02*
X1424517Y227889D01*
G01D02*
X1436383D01*
G01X1430120Y225182D02*
X1427224D01*
X1424517Y227889D01*
G01X1421308Y227948D02*
X1411958D01*
G01X1413900Y225212D02*
X1411958Y227154D01*
Y227948D01*
G01X1435880Y261501D02*
X1426020D01*
G01X1413821Y875920D02*
Y873810D01*
G01X1421221Y875920D02*
Y873811D01*
X1421220Y873810D01*
G01X1411971Y909057D02*
Y911167D01*
G01X1419370D02*
Y909058D01*
X1419371Y909057D01*
G01X1411971Y917576D02*
X1411972Y917575D01*
Y915467D01*
X1411971Y915466D01*
G01X1415670Y917576D02*
X1415671Y917575D01*
Y915466D01*
G01X1421221Y907963D02*
X1421220Y907962D01*
Y905854D01*
X1421221Y905853D01*
G01X1417521Y907963D02*
X1417520Y907962D01*
Y905854D01*
X1417521Y905853D01*
G01X1426771Y911167D02*
Y909058D01*
X1426772Y909057D01*
G01X1424921Y907963D02*
X1424920Y907962D01*
Y905854D01*
X1424921Y905853D01*
G01Y914372D02*
Y912263D01*
X1424922Y912262D01*
G01X1417521Y914372D02*
Y912263D01*
X1417522Y912262D01*
G01X1415670Y911167D02*
Y909058D01*
X1415671Y909057D01*
G01X1421221Y914372D02*
Y912263D01*
X1421222Y912262D01*
G01X1419370Y917576D02*
Y915467D01*
X1419371Y915466D01*
G01X1426771Y917576D02*
X1426772Y917575D01*
Y915467D01*
X1426771Y915466D01*
G01X1415670Y923985D02*
X1415671Y923984D01*
Y921875D01*
G01X1417521Y920780D02*
X1417520Y920779D01*
Y918670D01*
G01X1426771Y923985D02*
Y921875D01*
G01X1411971Y923985D02*
X1411972Y923984D01*
Y921876D01*
X1411971Y921875D01*
G01X1421221Y920780D02*
X1421220Y920779D01*
Y918670D01*
G01X1419370Y923985D02*
X1419371Y923984D01*
Y921875D01*
G01X1424921Y920780D02*
Y918670D01*
G01Y931488D02*
Y933598D01*
G01X1419370Y930393D02*
X1419371Y930392D01*
Y928283D01*
G01X1413821Y933598D02*
X1413820Y933597D01*
Y931488D01*
G01X1424921Y927189D02*
Y925079D01*
G01X1421221Y933598D02*
X1421220Y933597D01*
Y931488D01*
G01X1421221Y927189D02*
X1421220Y927188D01*
Y925079D01*
G01X1415670Y930393D02*
X1415671Y930392D01*
Y928283D01*
G01X1413821Y927189D02*
X1413820Y927188D01*
Y925079D01*
G01X1411971Y930393D02*
Y928283D01*
G01X1426771Y930393D02*
Y928283D01*
G01X1423070Y936801D02*
X1423071Y936800D01*
Y934691D01*
G01X1411971Y936801D02*
Y934691D01*
G01X1419370Y936801D02*
X1419371Y936800D01*
Y934691D01*
G01X1415670Y936801D02*
X1415671Y936800D01*
Y934691D01*
G01X1425354Y1052047D02*
X1425353Y1054157D01*
G01X1425354Y1058455D02*
X1425355Y1058456D01*
Y1060565D01*
G01X1427203Y1050952D02*
Y1048842D01*
G01Y1055251D02*
X1427204Y1055252D01*
Y1057361D01*
G01X1427203Y1074477D02*
Y1076587D01*
G01Y1068068D02*
X1427204Y1070178D01*
G01X1427203Y1080885D02*
Y1082994D01*
X1427202Y1082995D01*
G01X1415619Y1334095D02*
X1416520Y1333194D01*
Y1328321D01*
X1417761Y1327080D01*
X1417987Y1326535D01*
Y1325260D01*
G01X1426167Y1409125D02*
X1423573Y1411719D01*
X1421371D01*
G01X1432793Y1518976D02*
X1429964D01*
X1427350Y1516362D01*
X1425850D01*
G01D02*
X1420481D01*
X1420408Y1516435D01*
G01X1432793Y1521535D02*
X1426020D01*
G01D02*
X1420608D01*
X1420408Y1521335D01*
G01X1433033Y1534796D02*
X1430204D01*
X1427590Y1532182D01*
X1426090D01*
G01D02*
X1420721D01*
X1420648Y1532255D01*
G01X1433033Y1537355D02*
X1427120D01*
G01D02*
X1420848D01*
X1420648Y1537155D01*
G01X1433183Y1548575D02*
X1427320D01*
G01D02*
X1427120Y1548375D01*
X1420798D01*
G01X1426240Y1543402D02*
X1427740D01*
X1430354Y1546016D01*
X1433183D01*
G01X1426240Y1543402D02*
X1420871D01*
X1420798Y1543475D01*
G01X1422534Y1565491D02*
X1422775Y1565732D01*
X1427030D01*
X1435078Y1573780D01*
X1444930D01*
X1446840Y1571870D01*
Y1569605D01*
X1447408Y1569037D01*
G01X1415368Y1569131D02*
X1416448Y1568051D01*
X1422534D01*
G01X1416060Y1574922D02*
X1420110Y1570872D01*
X1422272D01*
X1422534Y1570610D01*
G01X1422680Y1584825D02*
Y1582100D01*
G01X1427940Y1590441D02*
X1425621D01*
X1422680Y1593382D01*
G01D02*
Y1587975D01*
G01X1434220Y1595900D02*
Y1593162D01*
X1428940Y1587882D01*
X1427940D01*
G01X1428700Y1600600D02*
X1426400Y1598300D01*
X1416230D01*
X1415730Y1598800D01*
Y1600723D01*
G01X1415740Y1586000D02*
X1413769D01*
X1413359Y1586410D01*
Y1588049D01*
X1413869Y1588559D01*
X1415740D01*
G01X1415730Y1605841D02*
Y1611422D01*
G01X1424195Y1608442D02*
Y1612792D01*
X1424175Y1612812D01*
G01X1424135Y1616932D02*
X1424175Y1616892D01*
Y1612812D01*
G01X1415730Y1611422D02*
X1421215D01*
X1424195Y1608442D01*
G01X1419270Y1623391D02*
Y1625950D01*
G01X1414400Y1627200D02*
X1414050Y1626850D01*
Y1622200D01*
G01X1419270Y1625950D02*
X1417450D01*
X1416200Y1627200D01*
X1414400D01*
G01X1426750Y1628509D02*
X1429809D01*
X1431600Y1630300D01*
G01X1426750Y1625950D02*
X1430950D01*
X1431600Y1625300D01*
G01X1423240Y1637362D02*
X1421500D01*
X1421000Y1637862D01*
Y1639362D01*
X1421559Y1639921D01*
X1423240D01*
G01X1428500Y1642362D02*
X1426059Y1639921D01*
X1423240D01*
G01X1460023Y60322D02*
X1461330D01*
X1462510Y59142D01*
Y56692D01*
X1460590Y54772D01*
X1439090D01*
X1434600Y59262D01*
G01X1428336Y232762D02*
Y232987D01*
X1428356Y233007D01*
X1436383D01*
G01X1449110Y233742D02*
X1448501D01*
X1440089Y225330D01*
X1436383D01*
G01Y230448D02*
X1431636D01*
G01X1436383Y235566D02*
X1430296D01*
G01X1516925Y272362D02*
X1512770D01*
X1488690Y248282D01*
X1459060D01*
X1452340Y241562D01*
X1431500D01*
X1428500Y238562D01*
Y237362D01*
X1430296Y235566D01*
G01X1444570Y238372D02*
X1441764Y235566D01*
X1436383D01*
G01Y238125D02*
X1431933D01*
G01X1435880Y256383D02*
X1431430D01*
G01X1435880Y264060D02*
X1431430D01*
G01X1435880Y266619D02*
X1438844D01*
X1440085Y265378D01*
Y259878D01*
X1439149Y258942D01*
X1435880D01*
G01X1431431Y267378D02*
X1432190Y266619D01*
X1435880D01*
G01X1428621Y875920D02*
Y873810D01*
G01X1430470Y911167D02*
Y909058D01*
X1430471Y909057D01*
G01X1428621Y907963D02*
X1428620Y907962D01*
Y905854D01*
X1428621Y905853D01*
G01X1434170Y911167D02*
Y909058D01*
X1434171Y909057D01*
G01X1437870Y917576D02*
Y915467D01*
X1437871Y915466D01*
G01X1443421Y914372D02*
X1443420Y914371D01*
Y912262D01*
G01X1437870Y911167D02*
Y909058D01*
X1437871Y909057D01*
G01X1428621Y914372D02*
X1428620Y914371D01*
Y912262D01*
G01X1434170Y917576D02*
X1434171Y917575D01*
Y915466D01*
G01X1430470Y917576D02*
X1430471Y917575D01*
Y915466D01*
G01X1439721Y914372D02*
X1439720Y914371D01*
Y912262D01*
G01X1436021Y914372D02*
X1436020Y914371D01*
Y912262D01*
G01X1436021Y907963D02*
Y905854D01*
X1436020Y905853D01*
G01X1439721Y907963D02*
Y905854D01*
X1439720Y905853D01*
G01X1443421Y907963D02*
Y905854D01*
X1443420Y905853D01*
G01X1430470Y923985D02*
X1430471Y923984D01*
Y921875D01*
G01X1443421Y920780D02*
X1443420Y920779D01*
Y918670D01*
G01X1439721Y920780D02*
X1439720Y920779D01*
Y918670D01*
G01X1441570Y923985D02*
X1441571Y923984D01*
Y921875D01*
G01X1434170Y923985D02*
X1434171Y923984D01*
Y921875D01*
G01X1428621Y920780D02*
X1428620Y920779D01*
Y918670D01*
G01X1436021Y920780D02*
X1436020Y920779D01*
Y918670D01*
G01X1443854Y1039230D02*
X1443853Y1039231D01*
Y1041340D01*
G01X1429053Y1047749D02*
X1429054Y1045639D01*
G01X1436454D02*
X1436453Y1045640D01*
Y1047750D01*
G01X1443853D02*
Y1045640D01*
X1443854Y1045639D01*
G01X1430903Y1042434D02*
X1430904Y1042435D01*
Y1044544D01*
G01X1432754Y1039230D02*
X1432753Y1039231D01*
Y1041340D01*
G01X1440154Y1039230D02*
X1440153Y1039231D01*
Y1041340D01*
G01X1438303Y1042434D02*
X1438304Y1042435D01*
Y1044544D01*
G01X1434603Y1042434D02*
X1434604Y1042435D01*
Y1044544D01*
G01X1432754Y1058455D02*
Y1060564D01*
X1432753Y1060565D01*
G01X1438303Y1055251D02*
Y1057361D01*
G01Y1061660D02*
Y1063770D01*
G01X1442003Y1048842D02*
X1442002Y1048843D01*
Y1050952D01*
G01X1440153Y1054157D02*
Y1052048D01*
X1440154Y1052047D01*
G01X1436454D02*
Y1054157D01*
G01X1434603Y1055251D02*
X1434604Y1055252D01*
Y1057361D01*
G01X1429054Y1052047D02*
X1429053Y1054157D01*
G01X1440154Y1058455D02*
Y1060565D01*
G01X1430903Y1050952D02*
Y1048842D01*
G01X1434603Y1050952D02*
Y1048842D01*
G01X1436453Y1060565D02*
Y1058456D01*
X1436454Y1058455D01*
G01X1430904Y1057361D02*
Y1055252D01*
X1430903Y1055251D01*
G01X1429054Y1071273D02*
Y1073382D01*
X1429053Y1073383D01*
G01X1436454Y1071273D02*
Y1073382D01*
X1436453Y1073383D01*
G01X1434603Y1068068D02*
X1434602Y1068069D01*
Y1070178D01*
G01X1436454Y1064864D02*
X1436453Y1064865D01*
Y1066974D01*
G01X1440154Y1064864D02*
Y1066973D01*
X1440153Y1066974D01*
G01X1442003Y1068068D02*
Y1070177D01*
X1442002Y1070178D01*
G01X1440154Y1079791D02*
Y1077681D01*
G01X1436454D02*
X1436453Y1077682D01*
Y1079790D01*
X1436454Y1079791D01*
G01X1438303Y1074477D02*
X1438304Y1074478D01*
Y1076587D01*
G01X1442003Y1074477D02*
Y1076586D01*
X1442004Y1076587D01*
G01X1440154Y1071273D02*
X1440153Y1073383D01*
G01X1434603Y1074477D02*
X1434604D01*
Y1076587D01*
G01X1438303Y1095812D02*
Y1093703D01*
G01X1434603Y1095812D02*
Y1093703D01*
G01X1442003Y1089403D02*
Y1087294D01*
G01X1432754Y1092607D02*
Y1090498D01*
G01X1430903Y1089403D02*
Y1087294D01*
G01X1436454Y1086199D02*
Y1084090D01*
G01X1430903Y1080885D02*
Y1082994D01*
X1430902Y1082995D01*
G01X1442003Y1095812D02*
Y1093703D01*
G01X1440154Y1092607D02*
Y1090498D01*
G01X1430903Y1095812D02*
Y1093703D01*
G01X1434603Y1089403D02*
Y1087294D01*
G01X1438303Y1089403D02*
Y1087294D01*
G01X1436454Y1099016D02*
Y1096907D01*
G01X1444997Y1392885D02*
X1443037D01*
X1441881Y1394041D01*
Y1396269D01*
G01X1437666Y1421828D02*
Y1413102D01*
X1443231Y1407537D01*
X1444720D01*
G01X1447222Y1432624D02*
X1443676D01*
G01X1443482Y1423962D02*
X1439800D01*
X1437666Y1421828D01*
G01X1440273Y1521535D02*
Y1524094D01*
G01D02*
X1445530D01*
G01X1440513Y1537355D02*
Y1539914D01*
G01D02*
X1445970D01*
G01X1440663Y1548575D02*
Y1551134D01*
G01D02*
X1446210D01*
G01X1455483Y1560037D02*
Y1557685D01*
X1454600Y1556802D01*
X1451130D01*
X1448940Y1558992D01*
X1437690D01*
X1436000Y1560682D01*
Y1566962D01*
X1437089Y1568051D01*
X1440112D01*
G01X1447408Y1564037D02*
X1445954Y1565491D01*
X1440112D01*
G01X1435420Y1585323D02*
X1442499D01*
G01D02*
X1449116D01*
X1450055Y1586262D01*
G01X1434220Y1595900D02*
Y1609920D01*
X1449100Y1624800D01*
X1464613D01*
X1467840Y1628027D01*
G01X1443975Y1598400D02*
Y1602600D01*
G01Y1598400D02*
X1446700D01*
G01X1450060Y1602441D02*
X1444134D01*
X1443975Y1602600D01*
G01Y1611000D02*
Y1606800D01*
G01X1450060Y1605000D02*
X1447900D01*
X1446100Y1606800D01*
X1443975D01*
G01X1480800Y1663600D02*
Y1624800D01*
X1477500Y1621500D01*
X1466100D01*
X1465200Y1622400D01*
X1450400D01*
X1443975Y1615975D01*
Y1611000D01*
G01X1436225Y1628700D02*
Y1632900D01*
G01Y1628700D02*
X1433200D01*
X1431600Y1630300D01*
G01X1436225Y1624500D02*
Y1620300D01*
G01X1431600Y1625300D02*
X1432250Y1625950D01*
X1434775D01*
X1436225Y1624500D01*
G01X1448507Y1643900D02*
X1448497Y1643890D01*
X1443617D01*
G01X1438547Y1643910D02*
X1443597D01*
X1443617Y1643890D01*
G01X1428425Y1637362D02*
X1428500Y1637437D01*
Y1642362D01*
G01X1446380Y1660462D02*
X1444308Y1662534D01*
Y1665495D01*
G01X1442573Y1652394D02*
Y1649862D01*
G01X1442587Y1659242D02*
Y1662900D01*
X1441158Y1664329D01*
Y1665495D01*
G01X1442573Y1655544D02*
X1442587Y1655558D01*
Y1659242D01*
G01X1448507Y1643900D02*
Y1652875D01*
X1445838Y1655544D01*
X1442573D01*
G01X1438320Y1668292D02*
X1439657Y1669629D01*
X1441072D01*
G01X1444222D02*
X1447987D01*
X1448920Y1670562D01*
Y1675062D01*
G01X1441068Y1673955D02*
X1438220D01*
G01X1446715Y1679957D02*
X1444218Y1677460D01*
Y1673955D01*
G01X1450377Y67802D02*
X1446000D01*
G01X1466356Y64062D02*
X1460023D01*
G01X1444925Y215862D02*
Y218787D01*
X1452500Y226362D01*
Y236862D01*
X1451000Y238362D01*
X1444580D01*
X1444570Y238372D01*
G01X1448075Y211862D02*
Y215862D01*
G01Y211862D02*
X1453630D01*
X1456150Y214382D01*
G01X1471308Y233448D02*
X1469652D01*
X1469211Y233007D01*
X1459383D01*
G01Y230448D02*
X1463833D01*
G01X1459383Y225330D02*
X1466383D01*
G01X1459383Y235566D02*
X1455501D01*
X1454883Y234948D01*
Y228448D01*
X1455442Y227889D01*
X1459383D01*
G01X1466383Y220108D02*
X1463720Y222771D01*
X1459383D01*
G01Y235566D02*
X1463833D01*
G01X1471510Y255378D02*
X1463586D01*
X1462032Y253824D01*
X1458880D01*
G01X1471510Y263378D02*
X1467086D01*
X1465209Y261501D01*
X1458880D01*
G01X1463950Y258172D02*
X1462161Y256383D01*
X1458880D01*
G01Y264060D02*
X1463330D01*
G01X1449930Y281190D02*
Y283670D01*
X1447200Y286400D01*
G01D02*
Y289601D01*
X1447800Y290201D01*
Y291125D01*
G01X1451700Y294275D02*
Y298567D01*
X1451200Y299067D01*
X1449700D01*
G01D02*
X1448300D01*
X1447800Y298567D01*
Y294275D01*
G01X1453900Y286400D02*
X1454890D01*
X1455700Y287210D01*
Y291025D01*
X1455600Y291125D01*
G01X1451700D02*
Y287300D01*
X1452600Y286400D01*
X1453900D01*
G01X1456770Y342942D02*
X1453777Y345935D01*
Y364421D01*
G01X1458300Y367537D02*
X1459900Y369137D01*
Y370823D01*
G01D02*
X1460718Y371641D01*
Y378996D01*
G01X1458159D02*
Y376180D01*
X1455920Y373941D01*
G01D02*
Y372682D01*
X1453777Y370539D01*
Y367571D01*
G01X1445777D02*
X1449777D01*
G01D02*
Y371039D01*
G01D02*
X1455600Y376862D01*
Y378996D01*
G01X1449600Y396737D02*
X1459035D01*
X1460718Y398420D01*
Y401996D01*
G01X1455642Y409646D02*
X1458159Y407129D01*
Y401996D01*
G01X1456777Y418596D02*
Y420996D01*
G01Y424146D02*
Y426546D01*
G01X1450821Y895146D02*
X1450820Y895145D01*
Y893036D01*
G01X1448970Y898350D02*
X1448971Y898349D01*
Y896240D01*
G01X1454521Y901555D02*
X1454520Y901554D01*
Y899445D01*
G01X1452670Y898350D02*
X1452671Y898349D01*
Y896240D01*
G01X1447121Y901555D02*
X1447120Y901554D01*
Y899445D01*
G01X1456370Y904759D02*
X1456371Y904758D01*
Y902649D01*
G01X1445270Y904759D02*
X1445271Y904758D01*
Y902649D01*
G01X1447121Y914372D02*
Y912263D01*
X1447122Y912262D01*
G01X1452670Y917576D02*
Y915467D01*
X1452671Y915466D01*
G01X1454521Y914372D02*
Y912263D01*
X1454522Y912262D01*
G01X1448970Y904759D02*
X1448971Y904758D01*
Y902649D01*
G01X1456370Y911167D02*
Y909057D01*
G01X1452670Y904759D02*
X1452671Y904758D01*
Y902649D01*
G01X1445270Y917576D02*
Y915467D01*
X1445271Y915466D01*
G01X1448970D02*
Y917576D01*
G01X1447121Y907963D02*
Y905854D01*
X1447120Y905853D01*
G01X1454521Y907963D02*
X1454520Y907962D01*
Y905853D01*
G01X1448970Y911167D02*
Y909058D01*
X1448971Y909057D01*
G01X1445270Y911167D02*
Y909058D01*
X1445271Y909057D01*
G01X1452670Y911167D02*
Y909058D01*
X1452671Y909057D01*
G01X1454521Y918670D02*
Y920780D01*
G01X1448970Y923985D02*
X1448971Y923984D01*
Y921875D01*
G01X1447121Y920780D02*
X1447120Y920779D01*
Y918670D01*
G01X1445270Y923985D02*
X1445271Y923984D01*
Y921875D01*
G01X1454521Y965640D02*
Y963531D01*
X1454520Y963530D01*
G01X1458221Y965640D02*
X1458219Y963530D01*
X1458220Y963529D01*
G01X1456370Y968845D02*
Y966736D01*
X1456371Y966735D01*
G01X1454521Y972049D02*
Y969939D01*
G01X1456370Y981662D02*
Y979553D01*
X1456371Y979552D01*
G01X1456370Y975253D02*
Y973144D01*
X1456371Y973143D01*
G01X1454521Y978457D02*
Y976348D01*
X1454520Y976347D01*
G01X1454521Y984866D02*
X1454520Y984865D01*
Y982756D01*
G01X1458654Y1013595D02*
X1458653Y1015705D01*
G01X1456803Y1029617D02*
X1456804Y1029618D01*
Y1031727D01*
G01X1456803Y1023208D02*
Y1025317D01*
X1456804Y1025318D01*
G01X1447553Y1041340D02*
Y1039231D01*
X1447554Y1039230D01*
G01X1451254Y1045639D02*
X1451253D01*
Y1047749D01*
G01X1445704Y1044544D02*
Y1042435D01*
X1445703Y1042434D01*
G01X1454954Y1032821D02*
X1454953Y1032822D01*
Y1034931D01*
G01X1456803Y1036026D02*
Y1038135D01*
X1456804Y1038136D01*
G01X1454954Y1039230D02*
X1454953Y1039231D01*
Y1041340D01*
G01X1456803Y1042434D02*
X1456804Y1042435D01*
Y1044544D01*
G01X1449403Y1042434D02*
X1449404Y1042435D01*
Y1044544D01*
G01X1454954Y1064864D02*
Y1066973D01*
X1454953Y1066974D01*
G01X1445703Y1068068D02*
Y1070177D01*
X1445702Y1070178D01*
G01X1447554Y1064864D02*
X1447553Y1064865D01*
Y1066974D01*
G01X1453103Y1074477D02*
X1453104Y1074478D01*
Y1076587D01*
G01X1456803Y1074477D02*
X1456804D01*
Y1076587D01*
G01X1456803Y1068068D02*
X1456804Y1070178D01*
G01X1453103Y1068068D02*
X1453104Y1070178D01*
G01X1447554Y1071273D02*
X1447553Y1073383D01*
G01X1449403Y1074477D02*
X1449404Y1074478D01*
Y1076587D01*
G01X1445703Y1074477D02*
X1445704Y1074478D01*
Y1076587D01*
G01X1447554Y1077681D02*
Y1079790D01*
X1447553Y1079791D01*
G01X1451254Y1071273D02*
X1451253Y1071274D01*
Y1073383D01*
G01X1458654Y1071273D02*
X1458653Y1073383D01*
G01X1454954Y1092607D02*
Y1090498D01*
G01X1451254Y1092607D02*
Y1090498D01*
G01X1449403Y1089403D02*
Y1087294D01*
G01X1447554Y1086199D02*
Y1084090D01*
G01X1453103Y1082994D02*
Y1080885D01*
G01X1458654Y1092607D02*
Y1090498D01*
G01X1453103Y1095812D02*
Y1093703D01*
G01X1447554Y1092607D02*
Y1090498D01*
G01X1451254Y1086199D02*
Y1084090D01*
G01X1454954Y1086199D02*
Y1084090D01*
G01X1447747Y1334095D02*
X1448648Y1333194D01*
Y1328321D01*
X1449889Y1327080D01*
X1450115Y1326535D01*
Y1325260D01*
G01X1465570Y1406538D02*
X1464121D01*
X1461182Y1403599D01*
X1459968Y1402765D01*
G01X1444997Y1400204D02*
Y1396303D01*
X1445031Y1396269D01*
G01X1457182Y1400385D02*
X1457682Y1399885D01*
X1462194D01*
G01X1457182Y1400385D02*
X1453749Y1396952D01*
X1452754D01*
X1450717Y1394915D01*
X1446385D01*
X1445031Y1396269D01*
G01X1465570Y1409687D02*
X1462366D01*
X1461975Y1409296D01*
G01X1445020Y1412672D02*
X1445231D01*
X1448842Y1409061D01*
G01X1445530Y1524094D02*
X1449097D01*
X1451692Y1526689D01*
G01X1445970Y1539914D02*
X1449337D01*
X1451932Y1542509D01*
G01X1446210Y1551134D02*
X1449487D01*
X1452082Y1553729D01*
G01X1455483Y1565037D02*
X1458200D01*
G01Y1560037D02*
X1457635Y1559472D01*
X1456048D01*
X1455483Y1560037D01*
G01X1447408Y1569037D02*
X1451408Y1565037D01*
X1452333D01*
G01X1462333D02*
X1459268Y1568102D01*
X1455398D01*
X1452333Y1565037D01*
G01X1462333Y1560037D02*
X1459998Y1562372D01*
X1454668D01*
X1452333Y1560037D01*
G01X1447408Y1564037D02*
X1448333D01*
X1452333Y1560037D01*
G01X1450085Y1590302D02*
Y1586292D01*
X1450055Y1586262D01*
G01X1453205D02*
X1456120D01*
G01X1457540Y1607559D02*
Y1605000D01*
G01Y1612800D02*
X1461800D01*
X1462421Y1612179D01*
Y1609800D01*
G01D02*
Y1607921D01*
X1462059Y1607559D01*
X1457540D01*
G01X1459127Y1643990D02*
X1456510Y1641373D01*
Y1632162D01*
X1457552Y1631120D01*
X1459117D01*
G01X1454167Y1643990D02*
X1451300Y1641123D01*
Y1631962D01*
X1452122Y1631140D01*
X1454207D01*
G01X1459127Y1643990D02*
Y1648705D01*
X1458890Y1648942D01*
G01D02*
X1457757Y1650075D01*
Y1655836D01*
G01X1454167Y1643990D02*
X1452757Y1645400D01*
Y1649112D01*
G01X1457757Y1676702D02*
Y1669350D01*
X1448869Y1660462D01*
X1446380D01*
G01X1452757Y1649112D02*
Y1655836D01*
G01X1448920Y1675062D02*
Y1678562D01*
X1451020Y1680662D01*
X1460301D01*
X1462757Y1678206D01*
Y1676702D01*
G01X1467757D02*
Y1678006D01*
X1463101Y1682662D01*
X1449420D01*
X1446715Y1679957D01*
G01X1474142Y61767D02*
Y64355D01*
G01X1470992D02*
X1469366D01*
X1469073Y64062D01*
X1466356D01*
G01X1462561Y205982D02*
Y201590D01*
X1464580Y199571D01*
Y160517D01*
X1463000Y158937D01*
G01X1467761Y205982D02*
Y212223D01*
X1484808Y229270D01*
Y233448D01*
G01X1471308Y230640D02*
Y233448D01*
G01X1517063Y268214D02*
X1511290D01*
X1489458Y246382D01*
X1476300D01*
X1472150Y242232D01*
Y234290D01*
X1471308Y233448D01*
G01X1474458D02*
X1484808D01*
G01X1466383Y225330D02*
X1469534D01*
X1469652Y225448D01*
X1471308D01*
G01X1474660Y255378D02*
X1484510D01*
G01X1474660D02*
Y252878D01*
G01X1473820Y265962D02*
X1474120D01*
X1474660Y265422D01*
Y263378D01*
G01X1471510Y255378D02*
Y252878D01*
G01X1471690Y259862D02*
X1471680Y259872D01*
Y263208D01*
X1471510Y263378D01*
G01X1462790Y359042D02*
X1466777Y363029D01*
Y364421D01*
G01X1462870Y355012D02*
X1465830D01*
X1470777Y359959D01*
Y364421D01*
G01X1466777Y367571D02*
Y370030D01*
X1467700Y370953D01*
G01D02*
X1465836Y372817D01*
Y378996D01*
G01X1470777Y367571D02*
Y368836D01*
X1472758Y370817D01*
G01D02*
X1471546D01*
X1468395Y373968D01*
Y378996D01*
G01X1462777Y367571D02*
X1463600Y368394D01*
Y374462D01*
G01D02*
X1463277Y374785D01*
Y378996D01*
G01X1465836Y408668D02*
Y401996D01*
G01X1468395D02*
Y407171D01*
X1470942Y409718D01*
G01D02*
X1469777Y410883D01*
Y418396D01*
G01X1475250Y401812D02*
X1473730Y403332D01*
Y415321D01*
X1475272Y416863D01*
X1477384D01*
G01X1465570Y1404569D02*
X1464596D01*
X1462194Y1402167D01*
Y1399885D01*
G01X1482830Y1525162D02*
X1481120D01*
X1468170Y1538112D01*
Y1559200D01*
X1462333Y1565037D01*
G01X1478320Y1522962D02*
X1475160Y1526122D01*
X1474438D01*
X1471720Y1523404D01*
X1470998D01*
X1469874Y1524528D01*
Y1525250D01*
X1472592Y1527968D01*
Y1528690D01*
X1471468Y1529814D01*
X1470746D01*
X1468028Y1527096D01*
X1467306D01*
X1466182Y1528220D01*
Y1528942D01*
X1468900Y1531660D01*
Y1532382D01*
X1465483Y1535799D01*
Y1541896D01*
X1464973Y1542406D01*
X1463870D01*
X1463360Y1542916D01*
Y1544506D01*
X1463870Y1545016D01*
X1464973D01*
X1465483Y1545526D01*
Y1547116D01*
X1464973Y1547626D01*
X1463870D01*
X1463360Y1548136D01*
Y1549726D01*
X1463870Y1550236D01*
X1464973D01*
X1465483Y1550746D01*
Y1556887D01*
X1462333Y1560037D01*
G01X1467840Y1631177D02*
X1472565D01*
G01X1478061Y1633864D02*
X1475374Y1631177D01*
X1472565D01*
G01X1463767Y1643990D02*
X1461570Y1641793D01*
Y1631862D01*
X1462312Y1631120D01*
X1463747D01*
G01X1463767Y1643990D02*
X1464880Y1645103D01*
Y1649112D01*
G01D02*
Y1651742D01*
X1462757Y1653865D01*
Y1655836D01*
G01X1481484Y361688D02*
Y364213D01*
G01Y367363D02*
X1481766Y367645D01*
Y372288D01*
G01D02*
Y378788D01*
G01X1489564Y364123D02*
X1493874D01*
G01X1489564Y367273D02*
Y372167D01*
X1489443Y372288D01*
G01D02*
Y378788D01*
G01X1494784Y374188D02*
X1493324D01*
X1492002Y375510D01*
Y378788D01*
G01X1486040Y368392D02*
Y370945D01*
X1484325Y372660D01*
Y378788D01*
G01X1477384Y413713D02*
Y410620D01*
X1481766Y406238D01*
G01D02*
Y401788D01*
G01X1489443D02*
Y406351D01*
X1490384Y407292D01*
G01D02*
X1490891Y407799D01*
Y411322D01*
X1489384Y412829D01*
Y413713D01*
G01X1493384Y411313D02*
Y406064D01*
X1492002Y404682D01*
Y401788D01*
G01X1484325D02*
Y407838D01*
X1482650Y409513D01*
Y411190D01*
G01D02*
X1482617D01*
X1481384Y412423D01*
Y413713D01*
G01X1486884Y401788D02*
Y408998D01*
X1486644Y410206D01*
X1485301Y413451D01*
X1483480Y415272D01*
Y418603D01*
X1484490Y419613D01*
Y421097D01*
X1485375Y421982D01*
G01X1489384Y416863D02*
X1486880D01*
G01X1485375Y421982D02*
X1488825D01*
G01X1487955Y431972D02*
X1488600D01*
X1489310Y431262D01*
Y426822D01*
G01D02*
Y422467D01*
X1488825Y421982D01*
G01X1479003Y1108629D02*
Y1106520D01*
G01X1477154Y1105426D02*
Y1103316D01*
G01X1488254Y1105426D02*
Y1103316D01*
G01X1484554Y1111833D02*
Y1109724D01*
G01X1482703Y1102220D02*
Y1100111D01*
G01X1480854Y1111833D02*
Y1109724D01*
G01X1477154Y1111833D02*
Y1109724D01*
G01X1480854Y1105426D02*
Y1103316D01*
G01X1486403Y1108630D02*
Y1106520D01*
G01X1488254Y1111833D02*
Y1109724D01*
G01X1484554Y1105426D02*
Y1103316D01*
G01X1482703Y1115038D02*
Y1112929D01*
G01X1479875Y1347521D02*
X1480776Y1346620D01*
Y1341747D01*
X1482017Y1340506D01*
X1482243Y1339961D01*
Y1338686D01*
G01X1543444Y221456D02*
X1538148D01*
X1537590Y220898D01*
X1534646D01*
X1534136Y221408D01*
Y222553D01*
X1533626Y223063D01*
X1532136D01*
X1531626Y222553D01*
Y221408D01*
X1531116Y220898D01*
X1529626D01*
X1529116Y221408D01*
Y222553D01*
X1528606Y223063D01*
X1527116D01*
X1526606Y222553D01*
Y221408D01*
X1526096Y220898D01*
X1515242D01*
X1512001Y217657D01*
X1508307D01*
X1507797Y218167D01*
Y219629D01*
X1507287Y220139D01*
X1505797D01*
X1505287Y219629D01*
Y218167D01*
X1504777Y217657D01*
X1501616D01*
X1499922Y215963D01*
Y211240D01*
G01X1504484Y234562D02*
X1507340D01*
X1513180Y228722D01*
X1521585D01*
X1528099Y235236D01*
X1543444D01*
G01X1508410Y230842D02*
X1511940Y227312D01*
X1522170D01*
X1528125Y233267D01*
X1543444D01*
G01X1516993Y243362D02*
X1509040D01*
G01X1504890Y249862D02*
X1509644Y254616D01*
X1516993D01*
G01X1506600Y239092D02*
X1508649Y241141D01*
X1525750D01*
X1526941Y242332D01*
X1533409D01*
X1534600Y241141D01*
X1543444D01*
G01X1504360Y244592D02*
X1506140Y246372D01*
X1510550D01*
X1511560Y245362D01*
X1514420D01*
X1516170Y247112D01*
X1533750D01*
X1535784Y245078D01*
X1543444D01*
G01X1504650Y254392D02*
X1506500Y256242D01*
X1510421D01*
X1512795Y258616D01*
G01X1498184Y361723D02*
Y364123D01*
G01D02*
X1493874D01*
G01X1498184Y367273D02*
Y369798D01*
G01X1493384Y413713D02*
Y411313D01*
G01X1494561Y401788D02*
Y405249D01*
X1495527Y406215D01*
G01D02*
X1497384Y408072D01*
Y413713D01*
G01X1506321Y895146D02*
Y893037D01*
X1506320Y893036D01*
G01X1508603Y1121446D02*
Y1119337D01*
G01Y1127855D02*
Y1125746D01*
G01X1577365Y1417315D02*
X1571808Y1422872D01*
X1510430D01*
X1509257Y1424045D01*
X1507617D01*
G01X1511200Y131862D02*
X1513460Y129602D01*
X1516776D01*
G01X1515425Y136162D02*
Y136087D01*
X1511200Y131862D01*
G01X1518575Y136162D02*
Y138662D01*
G01X1517263Y193262D02*
X1521115D01*
G01X1517263Y196412D02*
X1524591Y203740D01*
X1526930D01*
G01X1543444Y215551D02*
X1524539D01*
G01X1522009Y210825D02*
Y213109D01*
X1522482Y213582D01*
X1543444D01*
G01X1516993Y231116D02*
X1514520D01*
G01X1520143D02*
Y235116D01*
G01X1543444Y231299D02*
X1529337D01*
X1523554Y225516D01*
X1510017D01*
G01X1516993Y239116D02*
X1512420D01*
G01X1528860Y239792D02*
X1528241Y239173D01*
X1520200D01*
X1520143Y239116D01*
G01X1543444Y247047D02*
X1535964D01*
X1534149Y248862D01*
X1520979D01*
X1520143Y249698D01*
G01X1510810Y249742D02*
Y250162D01*
X1513010Y252362D01*
X1517479D01*
X1520143Y249698D01*
G01X1543444Y243110D02*
X1535382D01*
X1533650Y244842D01*
X1524840D01*
G01D02*
X1523108Y243110D01*
X1520395D01*
X1520143Y243362D01*
G01X1543444Y237204D02*
X1526681D01*
X1524853Y235376D01*
G01D02*
X1524593Y235116D01*
X1520143D01*
G01X1512795Y258616D02*
X1516993D01*
G01X1543444Y250984D02*
X1538828D01*
X1535160Y254652D01*
X1524810D01*
G01D02*
X1524107D01*
X1520143Y258616D01*
G01X1529150Y251402D02*
X1523357D01*
X1520143Y254616D01*
G01X1520213Y268214D02*
X1522928D01*
X1526280Y264862D01*
X1531110D01*
G01X1520075Y272362D02*
X1533920D01*
X1539150Y267132D01*
G01X1519833Y280956D02*
Y277297D01*
G01Y284956D02*
Y280956D01*
G01X1516683Y288956D02*
Y284956D01*
G01Y288956D02*
X1517669Y289942D01*
Y291516D01*
G01D02*
X1516181Y293004D01*
Y294071D01*
G01X1512244Y311522D02*
Y305489D01*
G01X1519703Y1121446D02*
Y1119337D01*
G01X1516003Y1127855D02*
Y1125746D01*
G01X1510453Y1124650D02*
Y1122541D01*
G01X1512303Y1127855D02*
Y1125746D01*
G01Y1121446D02*
Y1119337D01*
G01X1516003Y1121446D02*
Y1119337D01*
G01X1517853Y1124650D02*
Y1122541D01*
G01X1519703Y1127855D02*
Y1125746D01*
G01X1514154Y1131059D02*
Y1128950D01*
G01X1514371Y1361484D02*
Y1362759D01*
X1514145Y1363304D01*
X1512904Y1364545D01*
Y1365814D01*
G01D02*
Y1369818D01*
X1512803Y1369919D01*
G01X1586647Y1433669D02*
X1584884Y1435432D01*
X1530930D01*
X1523293Y1427795D01*
X1512177D01*
G01X1516137Y1432135D02*
X1531155Y1447153D01*
X1597341D01*
G01X1510027Y1425825D02*
X1591685D01*
X1597341Y1420169D01*
G01X1576407Y1438525D02*
X1575770Y1439162D01*
X1528770D01*
X1519593Y1429985D01*
X1513657D01*
G01X1540342Y32756D02*
Y28550D01*
X1541340Y27552D01*
X1544010D01*
G01X1540342Y44370D02*
Y46240D01*
X1539090Y47492D01*
X1536310D01*
G01X1545066Y44370D02*
Y46984D01*
X1541468Y50582D01*
X1536900D01*
X1533270Y54212D01*
Y56692D01*
X1533630Y57052D01*
G01X1530910Y64900D02*
X1530400Y64390D01*
Y55032D01*
X1535970Y49462D01*
X1539960D01*
X1542704Y46718D01*
Y44370D01*
G01X1533520Y110662D02*
X1535657Y108525D01*
Y106732D01*
G01X1525940Y108192D02*
X1531110D01*
X1531917Y107385D01*
Y106732D01*
G01X1539397Y116180D02*
X1545610D01*
G01X1535575Y121362D02*
Y118862D01*
G01X1526224Y125862D02*
X1529500D01*
G01X1534155Y136146D02*
Y132017D01*
X1532500Y130362D01*
G01D02*
X1535575Y127287D01*
Y125362D01*
G01X1532425D02*
Y121362D01*
G01X1526224Y122122D02*
X1529500D01*
G01D02*
X1531665D01*
X1532425Y121362D01*
G01X1603580Y206902D02*
X1606356Y204126D01*
Y189270D01*
X1596208Y179122D01*
X1559310D01*
X1535450Y155262D01*
G01X1543444Y199803D02*
X1534720D01*
G01X1528720Y199862D02*
X1530629Y201771D01*
X1543444D01*
G01X1533385Y193108D02*
Y194425D01*
X1534826Y195866D01*
X1543444D01*
G01X1526930Y203740D02*
X1543444D01*
G01Y211614D02*
X1533148D01*
G01X1526998Y209645D02*
X1543444D01*
G01X1531824Y207677D02*
X1543444D01*
G01X1534194Y217519D02*
X1543444D01*
G01X1526152Y225114D02*
X1530368Y229330D01*
X1543444D01*
G01X1529670Y225522D02*
X1531510Y227362D01*
X1543444D01*
G01Y225393D02*
X1535561D01*
G01X1527732Y219488D02*
X1543444D01*
G01Y239173D02*
X1529479D01*
X1528860Y239792D01*
G01X1543444Y249015D02*
X1536037D01*
X1533650Y251402D01*
X1529150D01*
G01X1531110Y264862D02*
X1553800D01*
X1558480Y260182D01*
Y252222D01*
X1559718Y250984D01*
X1566004D01*
G01X1539150Y267132D02*
X1553930D01*
X1559900Y261162D01*
Y253622D01*
X1560570Y252952D01*
X1566004D01*
G01X1539720Y589862D02*
Y587437D01*
G01D02*
X1543720D01*
G01X1539720Y584287D02*
Y581862D01*
G01X1545989Y601238D02*
Y598441D01*
X1541568Y594020D01*
G01D02*
Y592376D01*
X1543720Y590224D01*
Y587437D01*
G01X1535007Y608685D02*
X1540107D01*
X1540989Y607803D01*
Y601238D01*
G01X1545610Y116180D02*
X1543820Y117970D01*
Y121162D01*
X1543779Y121203D01*
G01X1547697D02*
X1543779D01*
G01X1552960Y124359D02*
X1552954Y124353D01*
X1547697D01*
G01X1546813Y127781D02*
Y132712D01*
G01D02*
X1546141Y133384D01*
Y138263D01*
G01X1549963Y127781D02*
X1553189D01*
G01X1549881Y147711D02*
X1556049D01*
G01X1542401Y138263D02*
Y141561D01*
G01X1595750Y159305D02*
X1545763D01*
G01X1543444Y205708D02*
X1548874D01*
X1551160Y203422D01*
Y189342D01*
G01X1557760Y214792D02*
X1558970Y213582D01*
X1566004D01*
G01X1550353Y217352D02*
Y221248D01*
X1548176Y223425D01*
X1543444D01*
G01X1557900Y220362D02*
Y218532D01*
X1560881Y215551D01*
X1566004D01*
G01X1552720Y589862D02*
Y587437D01*
G01D02*
X1548720D01*
G01X1548938Y593832D02*
X1548720Y593614D01*
Y587437D01*
G01X1552720Y584287D02*
Y581862D01*
G01X1550989Y601238D02*
Y595883D01*
X1548938Y593832D01*
G01X1550989Y622038D02*
Y626378D01*
X1549590Y627777D01*
Y629295D01*
G01X1545989Y622038D02*
Y625370D01*
X1543895Y627464D01*
Y629286D01*
G01X1550162Y637641D02*
Y634165D01*
G01X1549590Y629295D02*
Y631279D01*
X1550162Y631851D01*
Y634165D01*
G01X1546312Y637641D02*
Y634165D01*
G01X1543895Y629286D02*
Y630794D01*
X1546312Y633211D01*
Y634165D01*
G01X1550917Y704332D02*
Y700785D01*
X1547807Y697675D01*
Y645515D01*
X1550162Y643160D01*
Y640791D01*
G01X1550390Y709885D02*
X1548918D01*
X1545583Y706550D01*
Y699461D01*
X1545437Y699315D01*
Y643785D01*
X1546312Y642910D01*
Y640791D01*
G01X1588550Y185702D02*
X1587380D01*
X1573279Y199803D01*
X1566004D01*
G01X1589003Y219526D02*
Y217534D01*
X1586291Y214822D01*
X1574097D01*
X1571400Y217519D01*
X1566004D01*
G01X1595730Y205662D02*
X1589778Y211614D01*
X1566004D01*
G01X1588100Y205442D02*
X1583897Y209645D01*
X1566004D01*
G01X1588720Y193962D02*
X1582960D01*
X1575151Y201771D01*
X1566004D01*
G01X1603530Y202402D02*
X1584451D01*
X1579176Y207677D01*
X1566004D01*
G01Y205708D02*
X1577243D01*
X1582340Y200611D01*
G01X1559400Y229832D02*
Y221942D01*
X1561854Y219488D01*
X1566004D01*
G01X1596830Y232482D02*
X1595540Y233772D01*
X1595120D01*
X1590850Y238042D01*
X1578430D01*
X1573655Y233267D01*
X1566004D01*
G01X1591830Y232482D02*
X1587920Y236392D01*
X1579190D01*
X1574097Y231299D01*
X1566004D01*
G01X1586830Y232482D02*
X1584470Y234842D01*
X1579900D01*
X1574388Y229330D01*
X1566004D01*
G01X1581830Y232482D02*
X1576710Y227362D01*
X1566004D01*
G01X1581830Y227482D02*
X1579741Y225393D01*
X1566004D01*
G01X1581830Y222482D02*
X1580887Y223425D01*
X1566004D01*
G01X1581830Y217482D02*
X1577856Y221456D01*
X1566004D01*
G01X1588784Y243890D02*
X1587596Y245078D01*
X1573560D01*
G01D02*
X1566004D01*
G01X1574760Y251032D02*
X1572743Y249015D01*
X1566004D01*
G01X1580240Y242232D02*
X1576970D01*
X1571942Y237204D01*
X1566004D01*
G01X1596830Y237482D02*
X1594650Y239662D01*
X1577950D01*
X1573524Y235236D01*
X1566004D01*
G01Y247047D02*
X1580955D01*
X1581810Y247902D01*
G01X1582340Y200611D02*
X1583589Y199362D01*
X1588925D01*
G01X1589003Y227526D02*
Y219526D01*
G01X1604240Y227892D02*
X1602600Y229532D01*
X1591009D01*
X1589003Y227526D01*
G01X1581810Y247902D02*
X1581916Y248008D01*
X1588764D01*
G01Y256244D02*
Y252146D01*
X1588744Y252126D01*
G01D02*
X1587650Y251032D01*
X1574760D01*
G01X1597341Y1415669D02*
X1579011D01*
X1577365Y1417315D01*
G01X1597341Y1433669D02*
X1586647D01*
G01X1597341Y1442669D02*
X1580551D01*
X1576407Y1438525D01*
G01X1595750Y128005D02*
Y159305D01*
G01X1603747Y192951D02*
X1594111D01*
X1592075Y194987D01*
Y199362D01*
G01X1603920Y222922D02*
X1599540Y227302D01*
X1592377D01*
X1592153Y227526D01*
G01X1604240Y238242D02*
Y239362D01*
X1599712Y243890D01*
X1591934D01*
G01X1605800Y766478D02*
X1605480Y766798D01*
X1601391D01*
G01X1631091Y1252034D02*
X1626583D01*
X1624907Y1250358D01*
X1620759D01*
G01X1614299D02*
X1613687D01*
X1613570Y1250475D01*
X1612010D01*
X1610097Y1248562D01*
X1608400D01*
X1604928Y1252034D01*
X1601391D01*
G01X1609056Y1250602D02*
Y1253344D01*
X1607019Y1255381D01*
X1601391D01*
G01X1608000Y1261662D02*
X1607588Y1262074D01*
X1601391D01*
G01X1597341Y1420169D02*
Y1424669D01*
G01Y1415669D02*
Y1411169D01*
G01Y1433669D02*
Y1429169D01*
G01Y1452071D02*
Y1447153D01*
G01Y1442669D02*
Y1438169D01*
G01X1623452Y32756D02*
Y27494D01*
X1621920Y25962D01*
G01X1623452Y44370D02*
Y48630D01*
X1622220Y49862D01*
G01X1613466Y128005D02*
Y114472D01*
G01D02*
X1613478Y114484D01*
X1619515D01*
G01X1613466Y159305D02*
Y128005D01*
G01X1617533Y957546D02*
X1613083D01*
G01X1617533Y954200D02*
X1613083D01*
G01X1620399Y1000325D02*
Y997223D01*
X1617533Y994357D01*
G01X1647233Y1057940D02*
X1641136D01*
X1640176Y1058900D01*
Y1060415D01*
X1639726Y1060865D01*
X1637827D01*
X1636575Y1059613D01*
X1635009D01*
G01X1626939D02*
X1626156D01*
X1624483Y1057940D01*
X1617533D01*
G01X1611475Y1259227D02*
X1613088Y1257614D01*
Y1256169D01*
X1613876Y1255381D01*
X1617533D01*
G01Y1252034D02*
X1613183D01*
G01X1613027Y1248805D02*
X1617416D01*
X1617533Y1248688D01*
G01Y1258727D02*
X1621983D01*
G01X1679646Y115669D02*
X1679579Y115602D01*
X1675540D01*
X1674277Y116865D01*
X1637248D01*
X1636607Y116224D01*
X1634339D01*
G01D02*
X1631011D01*
X1629608Y117627D01*
G01X1679646Y125669D02*
X1675842Y121865D01*
X1637367D01*
X1636726Y121224D01*
X1634339D01*
G01D02*
X1630011D01*
X1629608Y121627D01*
G01X1679646Y135669D02*
X1675842Y131865D01*
X1637381D01*
X1636740Y131224D01*
X1634339D01*
G01D02*
X1632742Y129627D01*
X1629608D01*
G01X1632342Y216015D02*
X1632467Y215890D01*
X1645300D01*
X1648400Y212790D01*
Y205805D01*
G01X1631091Y766798D02*
X1626741D01*
G01X1660791Y1252034D02*
X1652588D01*
X1650917Y1253705D01*
X1650279D01*
G01X1643999D02*
X1643976Y1253728D01*
X1640762D01*
X1639062Y1252028D01*
X1631097D01*
X1631091Y1252034D01*
G01X1623930Y1252242D02*
Y1253242D01*
X1626069Y1255381D01*
X1631091D01*
G01X1624600Y1262074D02*
X1631091D01*
G01X1631768Y1445794D02*
X1632669Y1444893D01*
Y1440192D01*
X1634136Y1438725D01*
Y1436959D01*
G01X1666690Y193290D02*
X1652190D01*
X1649292Y196188D01*
X1648770D01*
G01X1648400Y202655D02*
X1648485Y202570D01*
X1651170D01*
X1652430Y201310D01*
Y196770D01*
X1653265Y195935D01*
X1654900D01*
G01D02*
X1660370D01*
G01X1644360Y202665D02*
X1648390D01*
X1648400Y202655D01*
G01X1652610Y400277D02*
Y403002D01*
X1654610Y405002D01*
G01D02*
X1655610Y406002D01*
Y410265D01*
G01X1653642Y418139D02*
Y419170D01*
X1652110Y420702D01*
X1649010D01*
X1646010Y423702D01*
G01D02*
Y427527D01*
X1647110Y428627D01*
G01X1655610Y418139D02*
Y419703D01*
X1653610Y421703D01*
Y423702D01*
G01D02*
Y428127D01*
X1654110Y428627D01*
G01Y431777D02*
Y434177D01*
G01D02*
Y438382D01*
X1659640Y443912D01*
X1765044D01*
X1765670Y444538D01*
G01X1658085Y645186D02*
X1657184Y644285D01*
X1653854D01*
G01D02*
X1652311D01*
X1651070Y643044D01*
X1650525Y642818D01*
X1649250D01*
G01Y676818D02*
X1650525D01*
X1651620Y677272D01*
X1652633Y678285D01*
X1657184D01*
X1658085Y679186D01*
G01Y713186D02*
X1657184Y712285D01*
X1652311D01*
X1651070Y711044D01*
X1650525Y710818D01*
X1649250D01*
G01X1647233Y957546D02*
X1642783D01*
G01X1647233Y954200D02*
X1642783D01*
G01X1648205Y998632D02*
X1647233Y997660D01*
Y994357D01*
G01X1676933Y1057940D02*
X1674753D01*
X1673928Y1057115D01*
X1669473D01*
X1666975Y1059613D01*
X1664769D01*
G01X1656889D02*
X1655180D01*
X1653507Y1057940D01*
X1647233D01*
G01Y1255381D02*
X1642883D01*
G01X1647233Y1252034D02*
X1642883D01*
G01X1651679Y1248885D02*
X1651482Y1248688D01*
X1647233D01*
G01X1653140Y1257862D02*
X1655621Y1255381D01*
X1660791D01*
G01X1647233Y1258727D02*
X1642883D01*
G01X1654600Y1262742D02*
X1656100D01*
X1656768Y1262074D01*
X1660791D01*
G01X1660370Y195935D02*
Y198252D01*
X1656982Y201640D01*
G01X1659610Y400277D02*
X1663610D01*
G01D02*
Y403202D01*
X1661610Y405202D01*
G01D02*
X1657578Y409234D01*
Y410265D01*
G01X1661110Y428627D02*
X1661210Y428527D01*
Y423702D01*
G01D02*
X1657578Y420070D01*
Y418139D01*
G01X1672040Y564077D02*
Y557206D01*
X1672401Y556845D01*
G01X1668975Y559364D02*
Y557905D01*
X1672353Y552848D01*
X1672532Y552417D01*
Y548123D01*
X1672067Y547658D01*
Y546514D01*
G01X1669563Y552923D02*
X1671422Y551064D01*
Y548784D01*
X1670492Y547854D01*
Y546514D01*
G01X1669563Y552923D02*
Y553365D01*
X1668268Y556490D01*
X1666657Y558101D01*
Y560116D01*
X1664040Y562733D01*
Y564077D01*
G01X1668040D02*
Y560299D01*
X1668975Y559364D01*
G01X1660660Y602273D02*
X1659904D01*
X1659674Y602043D01*
X1657107D01*
G01X1656441Y766798D02*
X1660791D01*
G01X1690491Y1252034D02*
X1685959D01*
X1684283Y1250358D01*
X1680289D01*
G01X1672829D02*
X1669475D01*
X1667799Y1252034D01*
X1660791D01*
G01X1672279Y1436959D02*
Y1438783D01*
X1670812Y1440250D01*
Y1444893D01*
X1669911Y1445794D01*
G01X1671673Y1493362D02*
Y1497362D01*
G01X1679508Y1498303D02*
X1672614D01*
X1671673Y1497362D01*
G01Y1505362D02*
Y1501362D01*
G01X1678340Y1500862D02*
X1672173D01*
X1671673Y1501362D01*
G01Y1516862D02*
Y1512862D01*
G01X1679508Y1517803D02*
X1672614D01*
X1671673Y1516862D01*
G01Y1533862D02*
Y1537862D01*
G01Y1520862D02*
Y1524862D01*
G01X1677930Y1520362D02*
X1672173D01*
X1671673Y1520862D01*
G01X1679508Y1538803D02*
X1672614D01*
X1671673Y1537862D01*
G01Y1541862D02*
Y1545862D01*
G01X1678340Y1541362D02*
X1672173D01*
X1671673Y1541862D01*
G01Y1553557D02*
Y1550815D01*
G01Y1553557D02*
Y1557557D01*
G01X1682008Y1558262D02*
X1679803Y1556057D01*
X1673173D01*
X1671673Y1557557D01*
G01X1671748Y1561557D02*
X1676453D01*
G01X1671748D02*
Y1565557D01*
G01X1671660Y1569412D02*
X1671748Y1569324D01*
Y1565557D01*
G01Y1585321D02*
Y1581321D01*
G01D02*
X1682008D01*
G01X1671748Y1585321D02*
X1674220D01*
G01X1679646Y145669D02*
X1680342D01*
X1684999Y141012D01*
X1695064D01*
X1705798Y151746D01*
Y154052D01*
G01X1679646Y155669D02*
Y155375D01*
X1684220Y150801D01*
X1693575D01*
X1702586Y159812D01*
X1705920D01*
G01X1704625Y165909D02*
X1699583Y160867D01*
X1684442D01*
X1679646Y165663D01*
Y165669D01*
G01Y175669D02*
X1683659Y171656D01*
X1704600D01*
G01X1687058Y424694D02*
X1687079Y424715D01*
Y427685D01*
X1686154Y428610D01*
G01X1694050Y416643D02*
X1691329D01*
X1687079Y420893D01*
Y424673D01*
X1687058Y424694D01*
G01X1674630Y521222D02*
X1673642Y522210D01*
Y527616D01*
G01X1688768Y518107D02*
Y520648D01*
X1683091Y526325D01*
Y527616D01*
G01X1690999Y513107D02*
X1689851D01*
X1686406Y516552D01*
Y520046D01*
X1681516Y524936D01*
Y527616D01*
G01X1691104Y530503D02*
X1689816D01*
X1687191Y533128D01*
X1685453D01*
G01X1689769Y537339D02*
X1689256Y537852D01*
X1685453D01*
G01X1690999Y525507D02*
Y527401D01*
X1686847Y531553D01*
X1685453D01*
G01X1689544Y543874D02*
X1688522D01*
X1687225Y542577D01*
X1685453D01*
G01Y539427D02*
X1688306D01*
X1688761Y539882D01*
X1689506D01*
G01X1689755Y541673D02*
X1688116D01*
X1687445Y541002D01*
X1685453D01*
G01Y534703D02*
X1687272D01*
X1688950Y533025D01*
X1693219D01*
X1693701Y533507D01*
G01X1681910Y559380D02*
Y559360D01*
X1681165Y558615D01*
X1678103D01*
X1677001Y557513D01*
X1676240Y555678D01*
Y548321D01*
X1676791Y547770D01*
Y546514D01*
G01X1675706Y559419D02*
X1674752Y557115D01*
Y548179D01*
X1675217Y547714D01*
Y546514D01*
G01X1672401Y556845D02*
Y556024D01*
X1673642Y553026D01*
Y546514D01*
G01X1685453Y544152D02*
X1686994D01*
X1688431Y545589D01*
G01X1680040Y564077D02*
X1681090Y563027D01*
Y562082D01*
X1681910Y561262D01*
Y559380D01*
G01X1676040Y564077D02*
Y559753D01*
X1675706Y559419D01*
G01X1686041Y766798D02*
X1690491D01*
G01X1672583Y957546D02*
X1676933D01*
G01X1672583Y954200D02*
X1676933D01*
G01Y994357D02*
X1672583D01*
G01X1676933Y1057940D02*
X1678905D01*
X1679850Y1056995D01*
X1682909D01*
X1685527Y1059613D01*
X1686839D01*
G01X1694189D02*
X1695591D01*
X1696691Y1060713D01*
X1698873D01*
X1699578Y1060008D01*
Y1058444D01*
X1700082Y1057940D01*
X1702283D01*
G01X1676933Y1255381D02*
X1672583D01*
G01X1676933Y1252034D02*
X1681179D01*
G01X1676933Y1248688D02*
X1672583D01*
G01X1683578Y1253780D02*
X1685179Y1255381D01*
X1690491D01*
G01X1676933Y1258727D02*
X1672583D01*
G01X1683500Y1264312D02*
X1685738Y1262074D01*
X1690491D01*
G01X1682008Y1498303D02*
X1679508D01*
G01X1682008Y1500862D02*
X1678340D01*
G01X1682008Y1517803D02*
X1679508D01*
G01X1682008Y1520362D02*
X1677930D01*
G01X1682008Y1538803D02*
X1679508D01*
G01X1682008Y1541362D02*
X1678340D01*
G01X1689488Y1560821D02*
X1688248D01*
X1687538Y1561531D01*
Y1562761D01*
X1688157Y1563380D01*
X1689488D01*
G01X1676453Y1561557D02*
X1679163D01*
X1679899Y1560821D01*
X1682008D01*
G01X1678230Y1590542D02*
X1693452D01*
X1700114Y1583880D01*
G01X1711705Y165909D02*
X1704625D01*
G01X1711642Y174970D02*
X1709986D01*
X1708776Y176180D01*
X1693963D01*
X1693452Y175669D01*
X1689646D01*
G01X1704600Y171656D02*
X1705715D01*
X1707045Y170326D01*
X1711705D01*
G01X1703067Y410738D02*
X1707780D01*
G01X1697161Y408769D02*
Y406602D01*
G01D02*
X1696682Y407081D01*
X1690950D01*
X1688504Y404635D01*
G01X1692429Y403985D02*
Y401485D01*
G01D02*
X1688504D01*
G01X1701124Y428100D02*
Y423802D01*
G01D02*
Y420607D01*
X1701098Y420581D01*
G01X1697161Y416643D02*
X1694050D01*
G01X1697161Y420581D02*
X1695455Y422287D01*
G01D02*
X1694314Y423428D01*
Y428580D01*
G01X1703067Y420581D02*
X1704624Y422138D01*
Y428100D01*
G01X1690208Y424694D02*
Y428556D01*
X1690154Y428610D01*
G01X1690208Y424694D02*
Y421855D01*
G01D02*
X1693451Y418612D01*
X1697161D01*
G01X1707568Y420370D02*
X1705810Y418612D01*
X1703067D01*
G01X1727804Y480669D02*
Y461462D01*
X1720993Y454651D01*
X1706912D01*
X1702701Y458862D01*
X1696720D01*
X1693720Y455862D01*
G01X1703547Y493656D02*
Y494589D01*
X1703720Y494762D01*
Y497661D01*
X1702700Y498681D01*
G01X1701635Y497177D02*
X1701973Y496839D01*
Y493656D01*
G01X1699300Y498632D02*
Y496282D01*
X1700398Y495184D01*
Y493656D01*
G01X1697210Y500802D02*
Y496672D01*
X1698823Y495059D01*
Y493656D01*
G01X1694050Y501422D02*
X1695485Y499987D01*
X1696000Y498743D01*
Y495972D01*
X1697248Y494724D01*
Y493656D01*
G01X1693711Y498527D02*
X1694030Y498208D01*
Y496122D01*
X1695673Y494479D01*
Y493656D01*
G01X1703720Y503787D02*
Y503227D01*
X1701811Y501318D01*
G01D02*
X1704830Y498299D01*
Y494852D01*
X1705122Y494560D01*
Y493656D01*
G01X1702700Y498681D02*
X1702027Y499354D01*
X1701073D01*
X1699495Y500932D01*
X1698720Y502802D01*
Y503787D01*
G01X1693701Y525507D02*
X1690999D01*
G01X1693701Y518107D02*
X1688768D01*
G01X1693701Y513107D02*
X1690999D01*
G01X1701726Y518107D02*
X1696851D01*
G01X1699553Y513107D02*
X1696851D01*
G01X1693701Y529507D02*
X1692100D01*
X1691104Y530503D01*
G01X1696851Y537507D02*
Y538673D01*
X1697725Y539547D01*
X1702320D01*
G01X1709356Y541144D02*
X1707759Y539547D01*
X1702320D01*
G01X1689506Y539882D02*
X1689946D01*
X1692321Y537507D01*
X1693701D01*
G01X1703960Y543928D02*
X1701960D01*
X1701526Y543494D01*
X1697656D01*
X1696851Y542689D01*
Y541507D01*
G01X1693701D02*
X1693535Y541673D01*
X1689755D01*
G01X1707716Y513562D02*
Y524176D01*
X1700500Y531392D01*
X1694958D01*
X1693701Y532649D01*
Y533507D01*
G01X1704460Y531613D02*
X1703904D01*
X1699965Y535552D01*
X1698140D01*
X1696851Y534263D01*
Y533507D01*
G01X1699107Y555783D02*
X1696851Y553527D01*
G01X1703306Y550064D02*
X1698749Y545507D01*
X1696851D01*
G01X1693701D02*
X1692068Y543874D01*
X1689544D01*
G01X1709680Y545432D02*
X1708176Y543928D01*
X1703960D01*
G01X1698048Y705662D02*
Y707285D01*
X1699631Y708868D01*
X1700357D01*
X1700657Y708568D01*
G01X1701051Y710537D02*
X1697406D01*
X1696402Y709533D01*
G01D02*
X1695446Y708577D01*
Y707093D01*
G01X1706633Y957546D02*
X1702183D01*
G01X1706633Y954200D02*
X1702183D01*
G01X1706633Y994357D02*
X1702183D01*
G01X1702283Y1057940D02*
X1706633D01*
G01X1720191Y1252034D02*
X1713417D01*
X1711741Y1250358D01*
X1709889D01*
G01X1703399D02*
X1699116D01*
X1697440Y1252034D01*
X1690491D01*
G01X1699089Y1258842D02*
X1702550Y1255381D01*
X1706633D01*
G01X1699030Y1263912D02*
Y1261980D01*
X1702283Y1258727D01*
X1706633D01*
G01Y1248688D02*
X1702283D01*
G01X1689488Y1503421D02*
Y1500862D01*
G01D02*
X1694248D01*
G01D02*
X1699173D01*
G01X1689488Y1522921D02*
Y1520362D01*
G01D02*
X1694248D01*
G01D02*
X1699173D01*
G01X1689488Y1543921D02*
Y1541362D01*
G01D02*
X1694248D01*
G01D02*
X1699173D01*
G01X1689488Y1560821D02*
X1694453D01*
G01D02*
X1696217D01*
X1699453Y1564057D01*
G01X1689488Y1583880D02*
X1700114D01*
G01D02*
X1700173Y1583821D01*
G01X1707744Y32756D02*
Y28373D01*
X1707089Y27718D01*
Y15793D01*
X1707220Y15662D01*
G01X1712468Y32756D02*
Y28097D01*
X1712089Y27718D01*
Y20693D01*
X1714500Y18282D01*
X1715210D01*
G01X1714830Y32756D02*
Y27959D01*
X1714589Y27718D01*
Y21562D01*
G01X1710106Y32756D02*
Y28235D01*
X1709589Y27718D01*
Y26062D01*
G01X1719555Y32756D02*
Y25896D01*
X1719589Y25862D01*
G01X1717192Y32756D02*
Y27821D01*
X1717089Y27718D01*
Y25862D01*
G01X1707744Y44370D02*
Y51828D01*
X1706100Y53472D01*
Y57052D01*
G01X1719555Y44370D02*
Y48397D01*
X1726600Y55442D01*
Y57232D01*
G01X1717192Y44370D02*
Y48634D01*
X1721240Y52682D01*
Y57422D01*
G01X1714830Y44370D02*
Y49672D01*
X1716230Y51072D01*
Y57202D01*
G01X1712468Y44370D02*
Y50144D01*
X1711140Y51472D01*
Y57202D01*
G01X1711832Y65308D02*
Y75646D01*
G01X1706100Y57052D02*
X1706726D01*
X1711832Y62158D01*
G01X1721240Y57422D02*
Y57652D01*
X1723320Y59732D01*
Y68362D01*
X1717320Y74362D01*
Y75279D01*
X1716965Y75634D01*
G01X1716230Y57202D02*
X1720895Y61867D01*
Y62394D01*
G01Y65544D02*
Y68062D01*
G01X1716875Y65544D02*
Y68062D01*
G01X1711140Y57202D02*
X1716332Y62394D01*
X1716875D01*
G01X1712520Y117862D02*
X1710820Y116162D01*
Y88762D01*
X1714320Y85262D01*
Y76462D01*
X1713504Y75646D01*
X1711832D01*
G01X1712720Y111862D02*
Y89162D01*
X1716965Y84917D01*
Y78784D01*
G01X1718608Y108959D02*
X1722608D01*
G01X1716600Y113622D02*
Y110967D01*
X1718608Y108959D01*
G01X1713418Y130862D02*
Y128242D01*
G01X1705798Y154052D02*
X1709638Y157892D01*
X1711754D01*
G01X1705920Y159812D02*
X1708008Y161900D01*
X1711754D01*
G01X1710959Y210080D02*
X1707159D01*
G01X1715044Y410120D02*
X1711044D01*
X1710426Y410738D01*
G01X1715044Y410120D02*
X1715052Y410112D01*
X1718931D01*
G01X1707780Y410738D02*
X1710426D01*
G01X1710408Y420370D02*
X1713266D01*
X1713296Y420340D01*
X1714952D01*
G01X1710408Y420370D02*
X1707568D01*
G01X1713977Y465229D02*
Y457137D01*
G01X1708977Y465229D02*
Y458542D01*
G01X1719854Y474859D02*
X1718102D01*
X1717642Y474399D01*
X1715711D01*
G01D02*
X1714232Y475878D01*
Y477801D01*
X1713338Y478695D01*
X1712209D01*
G01X1713977Y468379D02*
Y470804D01*
G01D02*
X1712696D01*
X1710004Y473496D01*
Y474601D01*
X1709847Y474758D01*
G01X1708977Y468379D02*
Y470804D01*
G01D02*
X1708272Y471509D01*
Y474758D01*
G01X1716134Y478443D02*
X1714307Y480270D01*
X1712209D01*
G01X1716087Y495665D02*
X1714995D01*
X1714237Y494907D01*
Y490672D01*
X1713284Y489719D01*
X1712209D01*
G01X1719854Y486869D02*
X1716972D01*
X1716156Y487685D01*
G01X1712209Y486569D02*
X1713804D01*
X1714920Y487685D01*
X1716156D01*
G01X1716278Y491676D02*
Y490887D01*
X1713535Y488144D01*
X1712209D01*
G01X1719854Y490869D02*
X1717085D01*
X1716278Y491676D01*
G01X1712209Y481845D02*
X1714877D01*
X1717342Y480824D01*
X1719297Y478869D01*
X1719854D01*
G01X1716087Y495665D02*
X1716487Y496065D01*
X1718658D01*
X1719854Y494869D01*
G01X1713920Y700962D02*
Y702346D01*
X1710720Y705546D01*
Y708715D01*
X1710335Y709645D01*
X1709143Y710837D01*
X1708043D01*
X1707743Y710537D01*
G01X1720191Y766798D02*
X1715841D01*
G01X1749891Y1252034D02*
X1745451D01*
X1743775Y1250358D01*
X1739599D01*
G01X1733099D02*
X1729676D01*
X1728000Y1252034D01*
X1720191D01*
G01X1706633D02*
X1711109D01*
G01X1714440Y1255381D02*
X1720191D01*
G01X1713930Y1262074D02*
X1720191D01*
G01X1726600Y57232D02*
X1725520Y58312D01*
Y62287D01*
G01X1725320Y67962D02*
X1725520Y67762D01*
Y65437D01*
G01X1732099Y108959D02*
X1726608D01*
G01D02*
X1722608D01*
G01X1732099Y112895D02*
X1728999D01*
G01D02*
X1728971Y112867D01*
X1725493D01*
G01X1739720Y120892D02*
X1739580Y121032D01*
Y121930D01*
X1736418Y125092D01*
G01X1730765Y151362D02*
Y152904D01*
X1737458Y159597D01*
X1744422D01*
G01X1737470Y177147D02*
X1729515D01*
X1729440Y177072D01*
G01Y173072D02*
X1730955Y174587D01*
X1742907D01*
G01X1728320Y169862D02*
X1729440Y170982D01*
Y173072D01*
G01X1725344Y359334D02*
X1731406Y353272D01*
X1771518D01*
X1783690Y365444D01*
Y391570D01*
X1787330Y395210D01*
X1807700D01*
X1809550Y393360D01*
Y382130D01*
X1812128Y379552D01*
X1823094D01*
G01X1731470Y358022D02*
X1734008Y360560D01*
Y364872D01*
G01X1738480Y358082D02*
X1735976Y360586D01*
Y364872D01*
G01X1742770Y387112D02*
X1735976Y380318D01*
Y375896D01*
G01X1735870Y387082D02*
X1734008Y385220D01*
Y375896D01*
G01X1728860Y387032D02*
X1732039Y383853D01*
Y375896D01*
G01X1729810Y393195D02*
Y390620D01*
G01X1729954Y402130D02*
Y396489D01*
X1729810Y396345D01*
G01X1733780D02*
Y402044D01*
X1733694Y402130D01*
G01X1733780Y396345D02*
X1737660D01*
G01X1731150Y427410D02*
X1726920D01*
X1725130Y425620D01*
Y403550D01*
X1726550Y402130D01*
X1729954D01*
G01X1733694D02*
Y404934D01*
X1733985Y405225D01*
X1739865D01*
X1740910Y404180D01*
Y400960D01*
X1741410Y400460D01*
X1743170D01*
G01X1734290Y420415D02*
Y423820D01*
G01X1738290Y420415D02*
Y426220D01*
X1737100Y427410D01*
X1731150D01*
G01X1734290Y417265D02*
X1738290D01*
G01X1734420Y475672D02*
Y482562D01*
X1733420Y483562D01*
X1731111D01*
X1727804Y486869D01*
G01Y480669D02*
X1726004Y478869D01*
X1723004D01*
G01Y486869D02*
X1727804D01*
G01Y490869D02*
Y492596D01*
X1731120Y495912D01*
G01X1723004Y490869D02*
X1727804D01*
G01X1723004Y494869D02*
X1728313Y500178D01*
X1735010D01*
G01X1731983Y957546D02*
X1736333D01*
G01X1731983Y954200D02*
X1736333D01*
G01Y994357D02*
X1731983D01*
G01X1766033Y1057940D02*
X1756754D01*
X1755081Y1059613D01*
X1753809D01*
G01X1745839D02*
X1744968D01*
X1742430Y1057075D01*
X1739266D01*
X1738401Y1057940D01*
X1736333D01*
G01D02*
X1731683D01*
G01X1736333Y1255381D02*
X1731983D01*
G01X1736333Y1252034D02*
X1731983D01*
G01X1736333Y1248688D02*
X1731983D01*
G01X1736333Y1258727D02*
X1731983D01*
G01X1751031Y32756D02*
Y26991D01*
X1757320Y20702D01*
Y15872D01*
G01X1751065Y39017D02*
X1751031Y39051D01*
Y44370D01*
G01X1741548Y116439D02*
Y118531D01*
X1741740Y118723D01*
Y123582D01*
X1741886Y123728D01*
G01X1739580Y116439D02*
Y120752D01*
X1739720Y120892D01*
G01X1743516Y116439D02*
Y121458D01*
X1745010Y122952D01*
G01X1749422Y116340D02*
Y118574D01*
G01D02*
X1750820Y119972D01*
G01D02*
X1750918Y120070D01*
Y125092D01*
G01Y128242D02*
X1758300D01*
G01X1741886Y123728D02*
X1743418Y125260D01*
Y128592D01*
G01X1745010Y122952D02*
X1746918Y124860D01*
Y125092D01*
G01X1738520Y151362D02*
Y155122D01*
X1740240Y156842D01*
X1744422D01*
G01X1751220Y147562D02*
Y149992D01*
X1752755Y151527D01*
X1758398D01*
G01X1748465Y147562D02*
Y151134D01*
X1751613Y154282D01*
X1758398D01*
G01X1754120Y171562D02*
X1753420Y170862D01*
Y158262D01*
X1754840Y156842D01*
X1758398D01*
G01X1750920Y171662D02*
Y164462D01*
X1749120Y162662D01*
Y155962D01*
X1747440Y154282D01*
X1744422D01*
G01X1742907Y177147D02*
X1737470D01*
G01X1746484Y279682D02*
X1746366Y279800D01*
Y283457D01*
G01X1756177Y288494D02*
X1753378D01*
X1750847Y285963D01*
G01D02*
X1748341Y283457D01*
X1746366D01*
G01X1752000Y306562D02*
X1754100Y301492D01*
Y295553D01*
X1755253Y294400D01*
X1756177D01*
G01X1740504Y367431D02*
X1741440D01*
X1742290Y366581D01*
Y364206D01*
X1743384Y363112D01*
X1745910D01*
G01D02*
X1750076D01*
X1751012Y364048D01*
G01X1745490Y357002D02*
X1737945Y364547D01*
Y364872D01*
G01X1764852Y368148D02*
X1763048Y369952D01*
X1752916D01*
X1751012Y368048D01*
G01X1740504Y369400D02*
X1742282D01*
X1743550Y368132D01*
X1746120D01*
G01D02*
X1746204Y368048D01*
X1751012D01*
G01X1764852Y364148D02*
X1763088Y365912D01*
X1752320D01*
X1751012Y364604D01*
Y364048D01*
G01X1764645Y372452D02*
X1764221D01*
X1761721Y374952D01*
X1752220D01*
X1751145Y373877D01*
Y372452D01*
G01X1740504Y371368D02*
X1742086D01*
X1744240Y373522D01*
X1745910D01*
G01D02*
X1746980Y372452D01*
X1751145D01*
G01X1737945Y375896D02*
Y377407D01*
X1743430Y382892D01*
X1744380D01*
G01X1751145Y377452D02*
X1744510D01*
G01D02*
X1742220Y375162D01*
Y373962D01*
X1741595Y373337D01*
X1740504D01*
G01X1744380Y382892D02*
X1751085D01*
X1751145Y382952D01*
G01X1737660Y393195D02*
Y390620D01*
G01X1738290Y417265D02*
Y415356D01*
X1737434Y414500D01*
Y411578D01*
G01D02*
X1740298D01*
X1742245Y413525D01*
X1742745D01*
X1742947Y413323D01*
G01D02*
X1743170Y413100D01*
Y408375D01*
G01Y400460D02*
Y405225D01*
G01X1745541Y766798D02*
X1749891D01*
G01X1779591Y1252034D02*
X1774873D01*
X1773197Y1250358D01*
X1769329D01*
G01X1762799D02*
X1757776D01*
X1756100Y1252034D01*
X1749891D01*
G01X1742337Y1252300D02*
Y1253139D01*
X1744579Y1255381D01*
X1749891D01*
G01X1743710Y1262074D02*
X1749891D01*
G01X1745111Y1467176D02*
Y1463262D01*
G01X1762842Y32756D02*
Y29150D01*
X1762876Y29116D01*
Y28064D01*
X1762420Y27608D01*
Y21562D01*
G01X1765204Y32756D02*
X1765238Y32722D01*
Y22062D01*
G01X1779377Y32756D02*
Y29090D01*
X1778659Y28372D01*
Y25979D01*
X1777347Y24667D01*
X1774461D01*
X1773756Y23962D01*
X1771246Y17905D01*
X1769669Y16328D01*
Y15244D01*
G01X1774653Y32756D02*
X1774687Y32722D01*
Y30010D01*
X1772934Y28257D01*
Y26189D01*
X1769881Y18817D01*
X1766251Y15187D01*
X1761998D01*
G01X1765260Y18262D02*
X1767370D01*
X1768298Y19190D01*
X1771140Y26051D01*
Y28713D01*
X1772291Y29864D01*
Y32756D01*
G01X1767220Y26962D02*
X1767566Y27308D01*
Y32756D01*
G01X1768026Y24165D02*
X1769660Y25799D01*
Y28802D01*
X1769929Y29071D01*
Y32756D01*
G01X1762842Y44370D02*
Y53158D01*
X1762738Y53262D01*
G01X1765204Y44370D02*
Y51326D01*
X1767220Y53342D01*
G01X1767566Y44370D02*
Y48436D01*
X1767185Y48817D01*
G01X1769929Y44370D02*
Y48231D01*
X1769274Y48886D01*
Y50742D01*
G01X1763613Y68637D02*
X1763895D01*
X1764820Y69562D01*
X1765777D01*
X1765798Y69541D01*
X1767638D01*
G01D02*
X1771791D01*
X1775580Y73330D01*
G01X1764123Y83607D02*
X1767170D01*
G01D02*
X1771616D01*
X1771642Y83581D01*
G01X1763643Y76797D02*
X1767990D01*
G01D02*
X1768795D01*
X1771642Y79644D01*
G01X1760478Y90027D02*
X1763122D01*
X1764123Y89026D01*
Y87107D01*
G01X1771642Y85550D02*
X1770085Y87107D01*
X1764123D01*
G01X1767638Y72691D02*
X1770368D01*
G01X1763613Y72637D02*
X1767584D01*
X1767638Y72691D01*
G01X1760033Y171733D02*
X1762138D01*
X1764749Y169122D01*
X1766490D01*
G01D02*
X1771019D01*
X1771800Y169903D01*
G01Y178403D02*
X1770544Y177147D01*
X1760033D01*
G01X1765820Y182282D02*
X1769699Y178403D01*
X1771800D01*
G01X1760033Y174587D02*
X1767300D01*
G01D02*
X1771116D01*
X1771800Y173903D01*
G01X1754295Y372452D02*
X1756933D01*
G01X1754295Y377452D02*
X1759220D01*
G01D02*
X1764645D01*
G01X1767795D02*
X1770220D01*
G01X1754295Y382952D02*
X1759220D01*
G01D02*
X1770220D01*
G01X1760216Y433221D02*
Y436838D01*
X1761720Y438342D01*
G01X1769520Y433793D02*
Y433794D01*
G01D02*
X1769410Y433904D01*
Y453986D01*
G01X1761720Y438342D02*
X1763530D01*
X1768078Y433794D01*
X1769520D01*
G01X1773126Y461393D02*
X1770887Y463632D01*
X1763980D01*
X1763316Y462968D01*
Y461393D01*
G01X1773126Y465893D02*
X1770967Y468052D01*
X1764450D01*
X1763426Y467028D01*
Y465893D01*
G01X1761683Y957546D02*
X1766033D01*
G01X1761683Y954200D02*
X1766033D01*
G01Y994357D02*
X1761683D01*
G01X1795733Y1057940D02*
X1792433D01*
X1791756Y1057263D01*
X1788125D01*
X1785775Y1059613D01*
X1783509D01*
G01X1775599D02*
X1772316D01*
X1770643Y1057940D01*
X1766033D01*
G01Y1255381D02*
X1761683D01*
G01X1766033Y1252034D02*
X1770299D01*
G01X1766033Y1248688D02*
X1761683D01*
G01X1766033Y1258727D02*
X1761683D01*
G01X1775556Y21471D02*
X1779011D01*
X1781740Y24200D01*
Y32756D01*
G01X1777015D02*
Y29150D01*
X1777049Y29116D01*
Y27741D01*
X1775830Y26522D01*
G01X1781740Y44370D02*
Y52672D01*
X1781774Y52706D01*
Y54462D01*
G01X1774653Y44370D02*
Y48507D01*
X1774274Y48886D01*
Y50742D01*
G01X1772291Y44370D02*
Y48369D01*
X1771774Y48886D01*
Y53682D01*
G01X1777015Y44370D02*
Y48645D01*
X1776774Y48886D01*
Y53498D01*
X1776710Y53562D01*
G01X1779377Y44370D02*
Y50658D01*
X1779411Y50692D01*
G01X1783454Y81613D02*
X1784271D01*
X1787790Y85132D01*
G01X1781485Y85550D02*
Y88192D01*
G01X1775580Y73330D02*
Y79644D01*
G01X1783454D02*
X1785142Y77956D01*
Y76032D01*
G01D02*
Y73433D01*
X1787588Y70987D01*
G01X1770368Y72691D02*
X1773611Y75934D01*
Y79644D01*
G01Y85550D02*
Y88293D01*
G01X1782103Y96927D02*
X1782061Y96969D01*
Y100939D01*
G01X1782103Y92927D02*
Y96927D01*
G01X1781485Y88192D02*
Y92309D01*
X1782103Y92927D01*
G01X1771853Y92891D02*
X1771891Y92929D01*
Y97245D01*
G01X1773611Y88293D02*
X1771853Y90051D01*
Y92891D01*
G01X1774950Y169903D02*
Y167392D01*
G01X1799690Y165565D02*
X1782456D01*
X1778118Y169903D01*
X1774950D01*
G01X1780320Y153162D02*
X1789187D01*
X1789328Y153303D01*
G01X1777354Y295489D02*
X1776265Y294400D01*
X1774681D01*
G01X1790546Y448785D02*
X1787183D01*
X1784920Y446522D01*
Y442672D01*
X1782720Y440472D01*
X1772680D01*
X1771720Y439512D01*
Y437692D01*
X1773530Y435882D01*
Y431533D01*
X1775010Y430053D01*
X1778182D01*
G01X1818874Y427932D02*
Y429137D01*
X1817049Y430962D01*
X1810720D01*
X1809811Y430053D01*
X1778182D01*
G01X1779740Y459942D02*
X1775286D01*
X1773647Y461581D01*
X1773314D01*
X1773126Y461393D01*
G01X1790546Y461581D02*
X1786701D01*
X1785062Y459942D01*
X1779740D01*
G01X1790546Y453904D02*
X1784010D01*
G01X1778810Y455215D02*
X1782699D01*
X1784010Y453904D01*
G01X1778810Y455215D02*
Y456290D01*
X1777830Y457270D01*
X1774130D01*
X1773150Y456290D01*
Y453986D01*
G01X1778430Y466699D02*
X1776620D01*
X1773126Y470193D01*
G01X1790546Y467092D02*
X1790153Y466699D01*
X1778430D01*
G01X1783608Y464140D02*
X1774879D01*
X1773126Y465893D01*
G01X1790546Y464140D02*
X1783608D01*
G01X1773559Y767345D02*
X1774106Y766798D01*
X1779591D01*
G01X1809291Y1252034D02*
X1803757D01*
X1802081Y1250358D01*
X1798919D01*
G01X1792499D02*
X1787136D01*
X1785460Y1252034D01*
X1779591D01*
G01X1773480Y1253692D02*
Y1254582D01*
X1774279Y1255381D01*
X1779591D01*
G01X1773390Y1262074D02*
X1779591D01*
G01X1790738Y74912D02*
Y70987D01*
G01X1787790Y85132D02*
X1788100Y85442D01*
X1790738D01*
G01X1788238Y74912D02*
X1790738D01*
G01X1806920Y150862D02*
X1806802Y150744D01*
X1796768D01*
G01X1819461Y150726D02*
X1817156D01*
X1816220Y151662D01*
Y167562D01*
X1815220Y168562D01*
X1802687D01*
X1799690Y165565D01*
G01X1800160Y362542D02*
X1800180Y362562D01*
Y367112D01*
X1801680Y368612D01*
X1805069D01*
G01X1792196Y367866D02*
Y385834D01*
X1791494Y386536D01*
G01X1795346Y372732D02*
Y367866D01*
G01Y372732D02*
X1796696Y374082D01*
X1800570D01*
X1803481Y371171D01*
X1805069D01*
G01X1800340Y387062D02*
X1801040Y387762D01*
X1805539D01*
X1805629Y387852D01*
G01X1791494Y390252D02*
Y386536D01*
G01X1805629Y390411D02*
X1800030D01*
G01D02*
X1796459D01*
X1796300Y390252D01*
X1794644D01*
G01X1798179Y410615D02*
X1792450D01*
G01D02*
X1788057D01*
X1787874Y410432D01*
G01Y403932D02*
X1792507D01*
G01D02*
X1796614D01*
X1798179Y405497D01*
G01X1787874Y425432D02*
X1792220D01*
G01D02*
X1796629D01*
X1798168Y423893D01*
G01Y418775D02*
X1792335D01*
G01D02*
X1788031D01*
X1787874Y418932D01*
G01X1790546Y446226D02*
X1796006D01*
X1806460Y435772D01*
Y433002D01*
G01X1790546Y443667D02*
X1793744D01*
X1800980Y436431D01*
Y433132D01*
G01X1790546Y441108D02*
X1793784D01*
X1795060Y439832D01*
Y433182D01*
G01X1790546Y451344D02*
X1790562D01*
X1790744Y451162D01*
X1796020D01*
G01X1790546Y459022D02*
X1794211D01*
X1795161Y459972D01*
Y472622D01*
G01X1790546Y456463D02*
X1795271D01*
X1797720Y458912D01*
Y477852D01*
G01X1791383Y957546D02*
X1795733D01*
G01X1791383Y954200D02*
X1795733D01*
G01Y994357D02*
X1791383D01*
G01X1825433Y1057940D02*
X1816365D01*
X1814692Y1059613D01*
X1813239D01*
G01X1805369D02*
X1804317D01*
X1801649Y1056945D01*
X1800196D01*
X1799201Y1057940D01*
X1795733D01*
G01X1788219Y1259312D02*
Y1258012D01*
X1790850Y1255381D01*
X1795733D01*
G01X1788360Y1264522D02*
Y1262132D01*
X1791765Y1258727D01*
X1795733D01*
G01Y1252034D02*
X1800019D01*
G01X1795733Y1248688D02*
X1791383D01*
G01X1808910Y143902D02*
X1809867Y142945D01*
X1813955D01*
G01X1819450Y145070D02*
X1818425Y146095D01*
X1813955D01*
G01X1813335Y161427D02*
X1808110D01*
G01D02*
X1802912D01*
X1802874Y161465D01*
G01X1802840Y165565D02*
X1802874Y165551D01*
Y161465D01*
G01X1813335Y155435D02*
Y158868D01*
G01X1813325Y179897D02*
X1813420Y179802D01*
X1823085D01*
G01X1813325Y177257D02*
Y179897D01*
G01X1823476Y363731D02*
X1819712D01*
X1818274Y362293D01*
G01D02*
X1813658D01*
X1812549Y363402D01*
Y366053D01*
G01X1813109Y385293D02*
X1818274D01*
G01D02*
X1821753D01*
X1823094Y383952D01*
G01X1816224Y403225D02*
X1811404D01*
G01X1805659Y410615D02*
Y412221D01*
X1805648Y412232D01*
Y418775D01*
G01X1805659Y410615D02*
X1804151D01*
X1802904Y409368D01*
Y406368D01*
X1803775Y405497D01*
X1805659D01*
G01X1811404Y403225D02*
X1807931D01*
X1805659Y405497D01*
G01X1805648Y418775D02*
X1803497D01*
X1802904Y419368D01*
Y422868D01*
X1803929Y423893D01*
X1805648D01*
G01X1815724Y427932D02*
X1809687D01*
X1807383Y425628D01*
Y425278D01*
X1805998Y423893D01*
X1805648D01*
G01X1818874Y417432D02*
X1820640D01*
X1821140Y417932D01*
Y425440D01*
X1820640Y425940D01*
X1815990D01*
X1815724Y426206D01*
Y427932D01*
G01Y417432D02*
Y413432D01*
G01Y417432D02*
X1810792D01*
G01X1818700Y433182D02*
Y436962D01*
X1817506Y438156D01*
X1813578D01*
G01Y441108D02*
X1819144D01*
X1820790Y439462D01*
G01X1813578Y443667D02*
X1822555D01*
X1826525Y439697D01*
G01X1813578Y459022D02*
X1823660D01*
X1826200Y456482D01*
G01X1813578Y446226D02*
X1820650D01*
G01X1813578Y448785D02*
X1823527D01*
X1826340Y445972D01*
G01X1813578Y451344D02*
X1820790D01*
G01X1813578Y453904D02*
X1823908D01*
X1826520Y451292D01*
G01X1813578Y456463D02*
X1820840D01*
G01X1813578Y461581D02*
X1827430D01*
G01X1813578Y464140D02*
X1821580D01*
G01X1809291Y766798D02*
X1804841D01*
G01X1830379Y1250358D02*
X1828619D01*
G01X1822199D02*
X1815548D01*
X1813872Y1252034D01*
X1809291D01*
G01X1813814Y1254693D02*
X1813126Y1255381D01*
X1809291D01*
G01X1803100Y1262074D02*
X1809291D01*
G01X1811494Y1505349D02*
X1813106Y1503737D01*
X1813700Y1502303D01*
Y1500362D01*
G01X1818289Y1504241D02*
Y1501591D01*
G01X1815139Y1504241D02*
Y1506746D01*
X1813994Y1507891D01*
G01X1809243Y1510568D02*
Y1508772D01*
X1809794Y1508221D01*
X1812259D01*
X1812589Y1507891D01*
X1813994D01*
G01X1819450Y145070D02*
X1820610Y146230D01*
X1826100D01*
X1831272Y151402D01*
X1831277D01*
G01Y153961D02*
X1825210D01*
G01D02*
X1821302D01*
X1821217Y153876D01*
X1819461D01*
G01X1826080Y163660D02*
X1825950Y163530D01*
X1821271D01*
X1820815Y163986D01*
G01X1826080Y163660D02*
Y164459D01*
X1822703Y167836D01*
Y170071D01*
X1822612Y170162D01*
G01X1820815Y161427D02*
X1819103D01*
X1818660Y161870D01*
Y163610D01*
X1819036Y163986D01*
X1820815D01*
G01X1830565Y177243D02*
X1836657D01*
G01X1823085Y182361D02*
X1823959D01*
X1830080Y188482D01*
G01D02*
X1834276Y192678D01*
X1835730D01*
G01X1823476Y363731D02*
Y367701D01*
G01X1826626Y363731D02*
X1829189D01*
G01X1826244Y379552D02*
Y383952D01*
G01X1826308Y374586D02*
X1826244Y374650D01*
Y379552D01*
G01X1836750Y379558D02*
X1835488D01*
X1830516Y374586D01*
X1826308D01*
G01X1819374Y403225D02*
X1824404D01*
G01X1829434Y406348D02*
X1829304Y406218D01*
Y399185D01*
G01X1824404Y403225D02*
X1828444Y399185D01*
X1829304D01*
G01X1823904Y427432D02*
Y434062D01*
X1823764Y434202D01*
G01X1818874Y427932D02*
X1820531D01*
X1821031Y427432D01*
X1823904D01*
G01X1832376Y453921D02*
Y459111D01*
X1832366Y459121D01*
G01X1826200Y456482D02*
X1829727D01*
X1832366Y459121D01*
G01X1827430Y461581D02*
X1830754D01*
X1832366Y463193D01*
G01X1821580Y464140D02*
X1829185D01*
X1832366Y467321D01*
G01X1820983Y957546D02*
X1825433D01*
G01X1820983Y954200D02*
X1825433D01*
G01Y994357D02*
X1820983D01*
G01X1829920Y1258322D02*
Y1257132D01*
X1828169Y1255381D01*
X1825433D01*
G01X1829940Y1263662D02*
Y1261232D01*
X1827435Y1258727D01*
X1825433D01*
G01Y1252034D02*
X1821083D01*
G01X1821139Y1248155D02*
X1822536D01*
X1823069Y1248688D01*
X1825433D01*
G01X1838757Y156520D02*
X1838687Y156450D01*
X1837290D01*
X1836977Y156137D01*
Y154323D01*
X1837339Y153961D01*
X1838757D01*
G01X1843830Y159800D02*
X1845895Y161865D01*
X1847656D01*
X1849091Y163300D01*
X1849191D01*
G01X1838757Y156520D02*
X1840550D01*
X1843830Y159800D01*
G01X1842885Y172187D02*
X1842880Y172192D01*
Y176722D01*
G01X1836657Y177243D02*
X1842359D01*
X1842880Y176722D01*
G01X1846030D02*
Y180337D01*
X1844157Y182210D01*
G01X1836294Y383592D02*
X1836750Y383136D01*
Y379558D01*
G01X1897682Y1364479D02*
Y1659057D01*
X1898686Y1660061D01*
X1906738D01*
X1907682Y1659117D01*
Y1364479D01*
G54D325*
G01X33020Y382822D02*
X34440D01*
X36595Y384977D01*
G01X43020Y382942D02*
X44473Y384395D01*
X45876D01*
G01X41933Y395652D02*
X43347Y394238D01*
X45876D01*
G01X53406Y399799D02*
Y402862D01*
G01X56777Y1314165D02*
Y1317079D01*
X58286Y1318588D01*
X59272D01*
G01X68020Y395222D02*
X67035Y396207D01*
X64872D01*
G01Y394238D02*
X67036D01*
X68020Y395222D01*
G01X84430Y1311831D02*
Y1321093D01*
X83878Y1321645D01*
X72565D01*
X69508Y1318588D01*
G01D02*
X65600D01*
G01X84430Y1333091D02*
Y1323829D01*
X83746Y1323145D01*
X73157D01*
X70234Y1326068D01*
X69508D01*
G01D02*
X65240D01*
G01X78524Y1531756D02*
X77250Y1530482D01*
X76680D01*
G01X72774Y1549669D02*
X73413Y1549030D01*
X74635D01*
X75274Y1549669D01*
G01X86302Y637030D02*
X81929D01*
X81899Y637060D01*
G01X86302Y640180D02*
X90518D01*
G01X95250Y637848D02*
X92918Y640180D01*
X90518D01*
G01X98600Y636262D02*
X97648Y635310D01*
X93952D01*
X92232Y637030D01*
X90518D01*
G01X89859Y628246D02*
X88940Y629165D01*
Y635452D01*
X90518Y637030D01*
G01X81899Y631160D02*
X86540D01*
X87000Y630700D01*
Y628787D01*
X86459Y628246D01*
G01X93547Y692260D02*
Y688720D01*
G01X86433Y690644D02*
Y688160D01*
G01D02*
Y687467D01*
X86444Y687456D01*
Y685488D01*
G01X89594D02*
X93465D01*
X93547Y685570D01*
G01X97549Y685490D02*
X97469Y685570D01*
X93547D01*
G01X89594Y685488D02*
X89583Y685499D01*
Y690644D01*
G01X88583Y694209D02*
X88979Y694605D01*
X92096D01*
G01D02*
X92725D01*
X93547Y693783D01*
Y692260D01*
G01X85433Y694209D02*
Y693037D01*
X86433Y692037D01*
Y690644D01*
G01X85433Y694209D02*
Y695555D01*
X86195Y696317D01*
Y700856D01*
X88009Y702670D01*
X89981D01*
G01X100931Y702202D02*
X100679D01*
X98920Y703961D01*
Y706062D01*
X96603Y708379D01*
X94311D01*
G01X94074Y1531869D02*
X96774Y1529169D01*
G01X110757Y392071D02*
X108691D01*
X107200Y393562D01*
G01X110757Y388071D02*
X107301D01*
G01X108025Y497374D02*
Y493608D01*
G01D02*
X107995Y493578D01*
G01X110689Y498271D02*
Y496272D01*
X108025Y493608D01*
G01X109607Y507792D02*
X108025Y509374D01*
G01Y497374D02*
Y501374D01*
G01D02*
X108720Y502069D01*
X110220D01*
G01X108025Y505374D02*
X110464D01*
G01D02*
X111467D01*
G01X108025Y513374D02*
Y513738D01*
X106157Y515606D01*
X99773D01*
G01D02*
Y513554D01*
X99089Y512870D01*
G01X108025Y517925D02*
X110600D01*
X110607Y517932D01*
G01X108643Y526892D02*
X108613Y526922D01*
Y531500D01*
G01X108643Y523742D02*
X108686Y523785D01*
X112739D01*
G01X97216Y638478D02*
X96586Y637848D01*
X95250D01*
G01X105760Y660632D02*
X107045Y661917D01*
G01X97549Y688640D02*
X98600D01*
X102060Y692100D01*
G01X110170Y685490D02*
X142439D01*
X143470Y686521D01*
Y688207D01*
G01X97549Y685490D02*
X97559Y685500D01*
X102310D01*
G01D02*
X107010D01*
X107020Y685490D01*
G01X100931Y705352D02*
X100914Y705369D01*
Y709172D01*
G01X119920Y379362D02*
X126320D01*
X130557Y383599D01*
Y384071D01*
G01X112483Y510637D02*
X113255D01*
X114311Y509581D01*
G01X118652Y528860D02*
Y521491D01*
X119138Y521005D01*
G01X114472Y518928D02*
Y519742D01*
X112831Y521383D01*
Y523693D01*
X112739Y523785D01*
G01X116776Y517455D02*
Y520616D01*
X115798Y521594D01*
Y523694D01*
X115889Y523785D01*
G01D02*
X115798Y523876D01*
Y525769D01*
X115793Y525774D01*
Y528188D01*
G01X112393D02*
Y529380D01*
X114513Y531500D01*
G01X124163Y636153D02*
Y632522D01*
X125620Y631065D01*
G01X125890Y644163D02*
X128046D01*
X128606Y643603D01*
G01X122280Y651934D02*
X123674D01*
X124343Y652603D01*
X125163D01*
G01X238297Y123968D02*
X233814D01*
X232260Y125522D01*
Y128862D01*
X231180Y129942D01*
X228616D01*
X139010Y219548D01*
Y304342D01*
X156670Y322002D01*
Y344542D01*
G01X235147Y127118D02*
Y129715D01*
X232750Y132112D01*
X229515D01*
X141180Y220447D01*
Y303443D01*
X159170Y321433D01*
Y344542D01*
G01X161670D02*
Y321118D01*
X143170Y302618D01*
Y221272D01*
X230340Y134102D01*
X239740D01*
G01X128015Y421490D02*
X131062D01*
X132490Y420062D01*
G01D02*
X137490Y415062D01*
X143821D01*
G01X143922Y522810D02*
X139837Y518725D01*
G01X138489Y525374D02*
X134525D01*
G01D02*
Y522996D01*
X133312Y521783D01*
G01X132600Y537072D02*
X133550Y538022D01*
X134897D01*
X135795Y537124D01*
Y530346D01*
X131375Y525926D01*
Y525374D01*
G01X131737Y522181D02*
Y525012D01*
X131375Y525374D01*
G01X138489Y528524D02*
Y533983D01*
X138469Y534003D01*
G01X132600Y540472D02*
X133169Y539903D01*
X138469D01*
G01X130057Y636103D02*
X127363D01*
X127313Y636153D01*
G01X131740Y640103D02*
X127313D01*
G01X246297Y132012D02*
X241447Y136862D01*
X231001D01*
X147170Y220693D01*
Y300961D01*
X164830Y318621D01*
Y344542D01*
G01X158376Y430883D02*
Y432295D01*
X159196Y433115D01*
X166580D01*
G01X143922Y531783D02*
Y526830D01*
G01D02*
Y522810D01*
G01X155858Y1406669D02*
X157579Y1404948D01*
Y1403338D01*
G01X152806Y1408384D02*
Y1406706D01*
X155807Y1403705D01*
Y1403338D01*
G01X155858Y1409390D02*
X155362D01*
X154356Y1408384D01*
X152806D01*
G01X149843Y1545985D02*
X147067D01*
G01X172507Y417205D02*
X168064Y412762D01*
X162075D01*
X161475Y413362D01*
G01X172321Y430883D02*
Y431661D01*
X173819Y433159D01*
X180411D01*
X181821Y431749D01*
Y430883D01*
G01X172321D02*
X171119D01*
X168887Y433115D01*
X166580D01*
G01X193941Y1409750D02*
X193483D01*
X192117Y1408384D01*
X190949D01*
G01X201392Y574271D02*
X201686D01*
X203407Y575992D01*
X204723D01*
G01Y574220D02*
X204314D01*
X200995Y570901D01*
X199676D01*
G01X198336Y574271D02*
X199676Y572931D01*
Y570901D01*
G01X200654Y578271D02*
Y578331D01*
X200655Y578332D01*
X203561Y579535D01*
X204723D01*
G01Y609992D02*
X203407D01*
X201686Y608271D01*
X201392D01*
G01X204723Y608220D02*
X204314D01*
X200995Y604901D01*
X199676D01*
G01X198336Y608271D02*
X199676Y606931D01*
Y604901D01*
G01X204723Y613535D02*
X203561D01*
X200655Y612332D01*
X200654Y612331D01*
Y612271D01*
G01X204723Y642220D02*
X204314D01*
X200995Y638901D01*
X199676D01*
G01X198336Y642271D02*
X199676Y640931D01*
Y638901D01*
G01X204723Y643992D02*
X203407D01*
X201686Y642271D01*
X201392D01*
G01X204723Y647535D02*
X203561D01*
X200655Y646332D01*
X200654Y646331D01*
Y646271D01*
G01X206027Y678369D02*
Y676988D01*
X202176Y673137D01*
X201220D01*
G01X205320D02*
X205096D01*
X202037Y670078D01*
X201311D01*
X201220Y669987D01*
G01X205320Y673137D02*
Y673973D01*
X207996Y676649D01*
Y678369D01*
G01X198495Y669487D02*
X198995Y669987D01*
X199145D01*
X199236Y670078D01*
X201129D01*
X201220Y669987D01*
G01X194858Y684348D02*
X194997Y684209D01*
X197932D01*
X198293Y684570D01*
X199866D01*
G01X196049Y678195D02*
Y678422D01*
X198260Y680633D01*
X199866D01*
G01X200018Y677492D02*
X201213D01*
X202090Y678369D01*
G01X193332Y678195D02*
Y678593D01*
X195126Y680387D01*
Y681291D01*
G01D02*
X196437Y682602D01*
X199866D01*
G01X194217Y689683D02*
X195366D01*
X196159Y690476D01*
X199866D01*
G01X196745Y675092D02*
X197015Y675362D01*
X202120D01*
X204059Y677301D01*
Y678369D01*
G01X197086Y686326D02*
X197299Y686539D01*
X199866D01*
G01X194217Y693623D02*
X197518D01*
X198697Y692444D01*
X199866D01*
G01X212891Y566632D02*
X214240Y567981D01*
X215316D01*
G01X212891Y601981D02*
X215316D01*
G01X212891Y635981D02*
X215316D01*
G01X211466Y673737D02*
X209964Y675239D01*
Y678369D01*
G01X261179Y84303D02*
X244067D01*
X240067Y88303D01*
Y101265D01*
X243487Y104685D01*
G01X239740Y134102D02*
X242297Y131545D01*
Y127118D01*
G01X302805Y1379941D02*
X303750Y1378996D01*
X305797D01*
X307676Y1377117D01*
Y1374460D01*
X305711Y1372495D01*
X280908D01*
X232522Y1324109D01*
X227038D01*
X225788Y1322859D01*
G01X302805Y1376541D02*
X303760Y1377496D01*
X305175D01*
X306176Y1376495D01*
Y1375082D01*
X305089Y1373995D01*
X280286D01*
X231900Y1325609D01*
X227038D01*
X225788Y1326859D01*
G01X242297Y123968D02*
Y122562D01*
X241360Y121625D01*
Y120142D01*
X242200Y119302D01*
G01D02*
X244940D01*
X246297Y120659D01*
Y123968D01*
G01X250297D02*
X254297D01*
G01X246297D02*
X250297D01*
G01X254297D02*
X260521Y117744D01*
Y115315D01*
G01X246297Y127118D02*
Y132012D01*
G01X257997Y127453D02*
Y123243D01*
X262490Y118750D01*
Y115315D01*
G01X268940Y217982D02*
X269772Y218814D01*
Y220845D01*
G01X290685Y165447D02*
X289206Y163968D01*
Y160315D01*
G01X295685Y165447D02*
X293600Y163362D01*
Y158654D01*
X292702Y157756D01*
X291765D01*
G01X293805Y569397D02*
X293654Y569548D01*
X290095D01*
G01X293805Y565997D02*
X293780Y566022D01*
X290095D01*
G01X296405Y630732D02*
X295455Y631682D01*
X293620D01*
X292695Y630757D01*
G01X296405Y634132D02*
X295455Y633182D01*
X293796D01*
X292695Y634283D01*
G01X294679Y688446D02*
X293729Y687496D01*
X292070D01*
X290969Y688597D01*
G01X294679Y685046D02*
X293729Y685996D01*
X291894D01*
X290969Y685071D01*
G01X303573Y1361428D02*
X303863D01*
X305157Y1360134D01*
G01X315105Y1361484D02*
Y1362646D01*
X313902Y1365552D01*
X313901Y1365553D01*
X313841D01*
G01X311562Y1361484D02*
Y1362800D01*
X309841Y1364521D01*
Y1364815D01*
G01X308176Y1359024D02*
Y1360088D01*
X306667Y1361597D01*
G01X309841Y1367871D02*
X309422Y1367452D01*
Y1367382D01*
X308502Y1366462D01*
X307019D01*
G01X309790Y1361484D02*
Y1361861D01*
X307019Y1364632D01*
Y1366462D01*
G01X334079Y882329D02*
Y880219D01*
G01X335928Y879124D02*
Y877014D01*
G01X334079Y940006D02*
X332229Y941100D01*
G01X335928Y936801D02*
Y934692D01*
G01Y956027D02*
Y953917D01*
G01X334079Y952823D02*
X332228Y953917D01*
G01X334512Y1007187D02*
X332661Y1006093D01*
G01X336361Y1003983D02*
X338211Y1002888D01*
G01Y1013595D02*
Y1015705D01*
G01X334512Y1026413D02*
X332661Y1025318D01*
G01X334512Y1020004D02*
X332661Y1018910D01*
G01X336361Y1023208D02*
X338211Y1022114D01*
G01X334512Y1045639D02*
X332661Y1044544D01*
G01X336361Y1042434D02*
X338211Y1041340D01*
G01X334512Y1039230D02*
X334511Y1041340D01*
G01X340061Y1061660D02*
X338211Y1060565D01*
G01Y1118243D02*
Y1116133D01*
G01Y1131060D02*
Y1128950D01*
G01X354428Y853490D02*
X354429Y851380D01*
G01X347029Y866307D02*
Y864197D01*
G01X354428Y866307D02*
X354429Y866306D01*
Y864197D01*
G01X350728Y866307D02*
X350729Y866306D01*
Y864197D01*
G01X339629Y866307D02*
X341479Y867401D01*
G01X348879Y863103D02*
Y860993D01*
G01X347029Y872716D02*
Y870606D01*
G01X354428Y879124D02*
Y877015D01*
X354429Y877014D01*
G01X345179Y882329D02*
Y880219D01*
G01Y875920D02*
Y873810D01*
G01X352579Y880219D02*
Y882329D01*
G01X350728Y879124D02*
Y877015D01*
X350729Y877014D01*
G01X339629Y885533D02*
Y883423D01*
G01X347029Y885533D02*
Y883423D01*
G01X350728Y885533D02*
Y883424D01*
X350729Y883423D01*
G01X348879Y875920D02*
Y873810D01*
G01X347029Y891942D02*
Y889832D01*
G01X345179Y895146D02*
Y893036D01*
G01X343328Y898350D02*
Y896240D01*
G01X345179Y901555D02*
Y899445D01*
G01X347029Y909057D02*
Y911167D01*
G01X345179Y914372D02*
Y912262D01*
G01X343328Y917576D02*
Y915467D01*
X343329Y915466D01*
G01X347029Y930393D02*
Y928283D01*
G01Y923985D02*
Y921875D01*
G01X345179Y920780D02*
Y918670D01*
G01Y933598D02*
Y931488D01*
G01X352579Y933598D02*
X352578Y933597D01*
Y931488D01*
G01X339629Y949619D02*
X341479Y950713D01*
G01X339629Y943210D02*
X341478Y944304D01*
G01X347029Y941100D02*
Y943210D01*
G01Y947509D02*
Y949619D01*
G01X352579Y940006D02*
X352578Y940005D01*
Y937896D01*
G01X339629Y934692D02*
Y936801D01*
G01X345179Y940006D02*
Y937896D01*
G01X343328Y934692D02*
Y936801D01*
G01X339629Y962436D02*
X343328Y960326D01*
G01X341479Y965640D02*
X343329Y966735D01*
G01X343328Y956027D02*
Y953917D01*
G01X345179Y952823D02*
Y950713D01*
G01X340061Y1010391D02*
X341911Y1009297D01*
G01X340061Y1003983D02*
X341911Y1002888D01*
G01X345611Y1007187D02*
Y1009297D01*
G01X343761Y1003983D02*
Y1006093D01*
G01X345611Y1000778D02*
Y1002888D01*
G01X341912Y1013595D02*
X345611Y1015705D01*
G01X340061Y1023208D02*
X341911Y1022114D01*
G01X340061Y1016800D02*
X341911Y1015705D01*
G01X345611Y1026413D02*
Y1028523D01*
G01Y1020004D02*
X343761Y1018910D01*
G01Y1023208D02*
X345611Y1022114D01*
G01X340061Y1029617D02*
X343761Y1031727D01*
G01X353011Y1045639D02*
Y1047749D01*
G01X340061Y1042434D02*
X341911Y1041340D01*
G01X340061Y1036026D02*
X343761Y1038136D01*
G01X347461Y1036026D02*
Y1038136D01*
G01X345611Y1039230D02*
Y1041340D01*
G01Y1045639D02*
Y1047749D01*
G01Y1058455D02*
Y1060565D01*
G01X343761Y1061660D02*
Y1063770D01*
G01X345611Y1064864D02*
Y1066974D01*
G01X351161Y1093703D02*
X349310Y1092609D01*
G01X349312Y1090498D02*
X347461Y1089404D01*
G01Y1087294D02*
X345610Y1086200D01*
G01X345611Y1084090D02*
X343760Y1082996D01*
Y1082995D01*
G01X341912Y1090498D02*
X343707Y1091513D01*
G01X341912Y1096907D02*
X340061Y1095813D01*
G01X347461Y1106520D02*
Y1108630D01*
G01X349312Y1103316D02*
Y1105425D01*
X349311Y1105426D01*
G01X349312Y1116133D02*
Y1118243D01*
G01X345611Y1116133D02*
Y1118243D01*
G01X353011Y1116133D02*
Y1118243D01*
G01X351161Y1125746D02*
Y1127855D01*
X351162Y1127856D01*
G01X349312Y1128950D02*
Y1131059D01*
X349311Y1131060D01*
G01X353011Y1135359D02*
Y1137469D01*
G01Y1128950D02*
Y1131060D01*
G01X345969Y1342755D02*
X346029D01*
X346030Y1342754D01*
X347233Y1339848D01*
Y1338686D01*
G01X341969Y1342017D02*
Y1341723D01*
X343690Y1340002D01*
Y1338686D01*
G01X338795Y1338799D02*
X340304Y1337290D01*
Y1336226D01*
G01X341918Y1338686D02*
Y1339063D01*
X338917Y1342064D01*
Y1343732D01*
G01X341969Y1345073D02*
X340628Y1343732D01*
X338917D01*
G01X359979Y843877D02*
Y841467D01*
G01X367379Y843877D02*
Y841467D01*
G01X365528Y853490D02*
Y851381D01*
X365529Y851380D01*
G01X361828Y853490D02*
Y851381D01*
X361829Y851380D01*
G01X358128Y853490D02*
Y851381D01*
X358129Y851380D01*
G01X369228Y853490D02*
Y851381D01*
X369229Y851380D01*
G01X363679Y850286D02*
Y848178D01*
X363678Y848177D01*
Y848176D01*
G01X356279Y850286D02*
Y848178D01*
X356278Y848177D01*
Y848176D01*
G01X371079Y850286D02*
Y848178D01*
X371078Y848177D01*
Y848176D01*
G01X365528Y866307D02*
X365529Y866306D01*
Y864197D01*
G01X361828Y866307D02*
X361829Y866306D01*
Y864197D01*
G01X358128Y866307D02*
X358129Y866306D01*
Y864197D01*
G01X369228Y866307D02*
X369229Y866306D01*
Y864197D01*
G01X363679Y863103D02*
Y860994D01*
X363678Y860993D01*
G01X356279Y863103D02*
Y860994D01*
X356278Y860993D01*
G01X371079Y863103D02*
Y860994D01*
X371078Y860993D01*
G01X365528Y879124D02*
Y877015D01*
X365529Y877014D01*
G01X361828Y879124D02*
Y877015D01*
X361829Y877014D01*
G01X358128Y879124D02*
Y877015D01*
X358129Y877014D01*
G01X369228Y879124D02*
Y877015D01*
X369229Y877014D01*
G01X363679Y875920D02*
Y873811D01*
X363678Y873810D01*
G01X356279Y875920D02*
Y873811D01*
X356278Y873810D01*
G01X371079Y875920D02*
Y873811D01*
X371078Y873810D01*
G01X365528Y891942D02*
Y889833D01*
X365529Y889832D01*
G01X361828Y891942D02*
Y889833D01*
X361829Y889832D01*
G01X358128Y891942D02*
Y889832D01*
G01X369228Y891942D02*
Y889833D01*
X369229Y889832D01*
G01X371079Y888737D02*
Y886628D01*
X371078Y886627D01*
G01X356279Y907963D02*
Y905854D01*
X356278Y905853D01*
G01X365528Y917576D02*
X365529Y917575D01*
Y915466D01*
G01X369228Y917576D02*
X369229Y917575D01*
Y915466D01*
G01X365528Y923985D02*
Y921876D01*
X365529Y921875D01*
G01X358128Y923985D02*
X358129Y923984D01*
Y921875D01*
G01X365528Y936801D02*
X365529D01*
Y934691D01*
G01X361828Y936801D02*
Y934691D01*
G01X369228Y936801D02*
X369229D01*
Y934691D01*
G01X360411Y1047749D02*
Y1045639D01*
X360412D01*
G01X365961Y1100111D02*
Y1102220D01*
X365962Y1102221D01*
G01X362261Y1100111D02*
Y1102220D01*
X362262Y1102221D01*
G01X356712Y1103316D02*
Y1105425D01*
X356711Y1105426D01*
G01X364112Y1109724D02*
X364113Y1109725D01*
X364112Y1111834D01*
G01X356712Y1109724D02*
X356713Y1109725D01*
X356712Y1111834D01*
G01X369661Y1100111D02*
Y1102221D01*
G01X367812Y1103316D02*
Y1105425D01*
X367811Y1105426D01*
G01X360412Y1103316D02*
X360413Y1103317D01*
Y1105425D01*
X360412Y1105426D01*
G01X358561Y1100111D02*
Y1102220D01*
X358562Y1102221D01*
G01X364112Y1116133D02*
Y1118242D01*
X364111Y1118243D01*
G01X360412Y1116133D02*
X360411Y1116134D01*
Y1118243D01*
G01X356712Y1116133D02*
X356711Y1116134D01*
Y1118243D01*
G01X367812Y1116133D02*
Y1118242D01*
X367811Y1118243D01*
G01X362261Y1119337D02*
Y1121447D01*
G01X354861Y1119337D02*
Y1121447D01*
G01X369661Y1119337D02*
Y1121446D01*
X369662Y1121447D01*
G01X364112Y1128950D02*
Y1131060D01*
G01X360412Y1128950D02*
Y1131060D01*
G01X356712Y1128950D02*
Y1131060D01*
G01X367812Y1128950D02*
Y1131059D01*
X367811Y1131060D01*
G01X354861Y1132154D02*
Y1134264D01*
G01X369661Y1132154D02*
Y1134263D01*
X369662Y1134264D01*
G01X362261Y1132154D02*
Y1134263D01*
X362262Y1134264D01*
G01X369413Y1323910D02*
X368156Y1325167D01*
X367807D01*
G01X370923Y1325373D02*
X372432Y1323864D01*
Y1322800D01*
G01X374046Y1325260D02*
Y1325637D01*
X370874Y1328809D01*
Y1330308D01*
G01X374097Y1331647D02*
X372758Y1330308D01*
X370874D01*
G01X382179Y843877D02*
Y841467D01*
G01X374779Y843877D02*
Y841467D01*
G01X380328Y853490D02*
Y851381D01*
X380329Y851380D01*
G01X376628Y853490D02*
Y851381D01*
X376629Y851380D01*
G01X372928Y853490D02*
X372929Y853489D01*
Y851380D01*
G01X384028Y853490D02*
Y851381D01*
X384029Y851380D01*
G01X385879Y850286D02*
Y848178D01*
X385878Y848177D01*
Y848176D01*
G01X378479Y850286D02*
Y848178D01*
X378478Y848177D01*
Y848176D01*
G01X380328Y866307D02*
X380329Y866306D01*
Y864197D01*
G01X376628Y866307D02*
X376629Y866306D01*
Y864197D01*
G01X372928Y866307D02*
X372929Y866306D01*
Y864197D01*
G01X384028Y866307D02*
X384029Y866306D01*
Y864197D01*
G01X385879Y863103D02*
Y860994D01*
X385878Y860993D01*
G01X378479Y863103D02*
Y860994D01*
X378478Y860993D01*
G01X380328Y879124D02*
Y877015D01*
X380329Y877014D01*
G01X376628Y879124D02*
Y877015D01*
X376629Y877014D01*
G01X372928Y879124D02*
Y877015D01*
X372929Y877014D01*
G01X384028Y879124D02*
Y877015D01*
X384029Y877014D01*
G01X385879Y875920D02*
Y873811D01*
X385878Y873810D01*
G01X378479Y875920D02*
Y873811D01*
X378478Y873810D01*
G01X380328Y891942D02*
Y889833D01*
X380329Y889832D01*
G01X376628Y891942D02*
Y889833D01*
X376629Y889832D01*
G01X372928Y891942D02*
Y889833D01*
X372929Y889832D01*
G01X384028Y891942D02*
Y889833D01*
X384029Y889832D01*
G01X385879Y888737D02*
Y886628D01*
X385878Y886627D01*
G01X378479Y888737D02*
Y886628D01*
X378478Y886627D01*
G01X384028Y923985D02*
X384029Y923984D01*
Y921875D01*
G01X371512Y1039230D02*
Y1041339D01*
X371511Y1041340D01*
G01Y1047749D02*
Y1045639D01*
X371512D01*
G01X378912Y1039230D02*
X378911Y1039231D01*
Y1041340D01*
G01Y1047749D02*
Y1045639D01*
X378912D01*
G01X386311Y1047749D02*
Y1045639D01*
X386312D01*
G01X384461Y1093703D02*
Y1095812D01*
X384462Y1095813D01*
G01X380761Y1093703D02*
Y1095812D01*
X380762Y1095813D01*
G01X371512Y1103316D02*
Y1105426D01*
G01Y1096907D02*
Y1099017D01*
G01Y1109724D02*
Y1111834D01*
G01X380761Y1106520D02*
Y1108629D01*
X380762Y1108630D01*
G01X378912Y1096907D02*
Y1099016D01*
X378911Y1099017D01*
G01X377061Y1100111D02*
Y1102220D01*
X377062Y1102221D01*
G01X373361Y1106520D02*
Y1108630D01*
G01Y1100111D02*
Y1102221D01*
G01X386312Y1096907D02*
Y1099017D01*
G01X384461Y1100111D02*
Y1102220D01*
X384462Y1102221D01*
G01X382612Y1096907D02*
Y1099016D01*
X382611Y1099017D01*
G01X371512Y1116133D02*
Y1118242D01*
X371511Y1118243D01*
G01X382612Y1116133D02*
Y1118242D01*
X382611Y1118243D01*
G01X378912Y1116133D02*
Y1118242D01*
X378911Y1118243D01*
G01X375212Y1116133D02*
Y1118242D01*
X375211Y1118243D01*
G01X386312Y1116133D02*
Y1118242D01*
X386311Y1118243D01*
G01X384461Y1119337D02*
Y1121446D01*
X384462Y1121447D01*
G01X377061Y1119337D02*
Y1121446D01*
X377062Y1121447D01*
G01X371512Y1128950D02*
Y1131059D01*
X371511Y1131060D01*
G01X382612Y1128950D02*
Y1131059D01*
X382611Y1131060D01*
G01X378912Y1128950D02*
Y1131059D01*
X378911Y1131060D01*
G01X375212Y1128950D02*
Y1131059D01*
X375211Y1131060D01*
G01X386312Y1128950D02*
Y1131059D01*
X386311Y1131060D01*
G01X384461Y1132154D02*
Y1134263D01*
X384462Y1134264D01*
G01X377061Y1132154D02*
Y1134263D01*
X377062Y1134264D01*
G01X378097Y1329329D02*
X378157D01*
X378158Y1329328D01*
X379361Y1326422D01*
Y1325260D01*
G01X374097Y1328591D02*
Y1328297D01*
X375818Y1326576D01*
Y1325260D01*
G01X387728Y853490D02*
Y851381D01*
X387729Y851380D01*
G01X396979Y843877D02*
Y841467D01*
G01X389579Y843877D02*
Y841467D01*
G01X398828Y853490D02*
Y851381D01*
X398829Y851380D01*
G01X395128Y853490D02*
Y851381D01*
X395129Y851380D01*
G01X391428Y853490D02*
Y851381D01*
X391429Y851380D01*
G01X402528Y853490D02*
Y851381D01*
X402529Y851380D01*
G01X400679Y850286D02*
Y848178D01*
X400678Y848177D01*
Y848176D01*
G01X387728Y866307D02*
X387729Y866306D01*
Y864197D01*
G01X398828Y866307D02*
X398829Y866306D01*
Y864197D01*
G01X395128Y866307D02*
X395129Y866306D01*
Y864197D01*
G01X391428Y866307D02*
X391429Y866306D01*
Y864197D01*
G01X402528Y866307D02*
X402529Y866306D01*
Y864197D01*
G01X400679Y863103D02*
Y860994D01*
X400678Y860993D01*
G01X393279Y863103D02*
Y860994D01*
X393278Y860993D01*
G01X387728Y879124D02*
Y877015D01*
X387729Y877014D01*
G01X398828Y879124D02*
Y877015D01*
X398829Y877014D01*
G01X395128Y879124D02*
Y877015D01*
X395129Y877014D01*
G01X391428Y879124D02*
Y877015D01*
X391429Y877014D01*
G01X402528Y879124D02*
Y877015D01*
X402529Y877014D01*
G01X393279Y875920D02*
Y873811D01*
X393278Y873810D01*
G01X387728Y891942D02*
Y889833D01*
X387729Y889832D01*
G01X398828Y891942D02*
Y889833D01*
X398829Y889832D01*
G01X395128Y891942D02*
Y889833D01*
X395129Y889832D01*
G01X391428Y891942D02*
Y889833D01*
X391429Y889832D01*
G01X402528Y891942D02*
Y889833D01*
X402529Y889832D01*
G01X400679Y888737D02*
Y886628D01*
X400678Y886627D01*
G01X393279Y888737D02*
Y886628D01*
X393278Y886627D01*
G01X395128Y917576D02*
Y915467D01*
X395129Y915466D01*
G01X391428Y917576D02*
X391429Y917575D01*
Y915466D01*
G01X391428Y923985D02*
Y921876D01*
X391429Y921875D01*
G01X387728Y936801D02*
Y934691D01*
G01X395128Y936801D02*
X395129D01*
Y934691D01*
G01X391428Y936801D02*
X391429D01*
Y934691D01*
G01X398828Y949619D02*
X398829Y949618D01*
Y947509D01*
G01X402528Y949619D02*
X402529Y949618D01*
Y947509D01*
G01X396979Y959232D02*
X396978Y959231D01*
Y957122D01*
G01X396979Y952823D02*
Y950713D01*
G01X395128Y956027D02*
Y953918D01*
X395129Y953917D01*
G01X400679Y959232D02*
X400678Y959231D01*
Y957122D01*
G01X402528Y956027D02*
X402529D01*
Y953917D01*
G01X400679Y952823D02*
X400680Y952822D01*
Y950713D01*
G01X398828Y956027D02*
X398829D01*
Y953917D01*
G01X399261Y1016800D02*
Y1018910D01*
G01X397412Y1026413D02*
Y1028522D01*
X397411Y1028523D01*
G01X397412Y1020004D02*
G03X397411Y1022114I-2226050J0D01*
G01X395561Y1023208D02*
Y1025317D01*
X395562Y1025318D01*
G01X399261Y1029617D02*
Y1031726D01*
X399262Y1031727D01*
G01X391861Y1029617D02*
Y1031726D01*
X391862Y1031727D01*
G01X402961Y1023208D02*
G02X402962Y1025318I2226050J0D01*
G01X399261Y1023208D02*
G02X399262Y1025318I2226050J0D01*
G01X402961Y1016800D02*
Y1018909D01*
X402960Y1018910D01*
G01X401112Y1020004D02*
Y1022113D01*
X401111Y1022114D01*
G01X399261Y1036026D02*
Y1038136D01*
G01X397412Y1039230D02*
Y1041339D01*
X397411Y1041340D01*
G01X395561Y1042434D02*
Y1044543D01*
X395562Y1044544D01*
G01X397411Y1047749D02*
Y1045639D01*
X397412D01*
G01X402961Y1042434D02*
Y1044543D01*
X402962Y1044544D01*
G01X401112Y1039230D02*
Y1041339D01*
X401111Y1041340D01*
G01X399261Y1042434D02*
Y1044543D01*
X399262Y1044544D01*
G01X399261Y1048842D02*
G02X399262Y1050952I2226050J0D01*
G01X397412Y1077681D02*
G03X397411Y1079791I-2226050J0D01*
G01X401112Y1077681D02*
Y1079790D01*
X401111Y1079791D01*
G01X399261Y1087294D02*
Y1089403D01*
X399262Y1089404D01*
G01X397412Y1084090D02*
Y1086200D01*
G01X395561Y1080885D02*
G02X395562Y1082995I2226050J0D01*
G01X401112Y1090498D02*
Y1092608D01*
G01Y1084090D02*
G03X401111Y1086200I-2226050J0D01*
G01X402961Y1093703D02*
Y1095812D01*
X402962Y1095813D01*
G01X399261Y1080885D02*
G02X399262Y1082995I2226050J0D01*
G01X395561Y1100111D02*
Y1102220D01*
X395562Y1102221D01*
G01X390012Y1103316D02*
X390011Y1105426D01*
G01X388161Y1106520D02*
Y1108629D01*
X388162Y1108630D01*
G01X388161Y1100111D02*
Y1102220D01*
X388162Y1102221D01*
G01X391861Y1100111D02*
X391862Y1102221D01*
G01X393712Y1103316D02*
Y1105425D01*
X393711Y1105426D01*
G01X397412Y1116133D02*
Y1118242D01*
X397411Y1118243D01*
G01X395561Y1112929D02*
Y1115039D01*
G01X393712Y1116133D02*
Y1118242D01*
X393711Y1118243D01*
G01X390012Y1116133D02*
Y1118242D01*
X390011Y1118243D01*
G01X401112Y1116133D02*
Y1118242D01*
X401111Y1118243D01*
G01X391861Y1119337D02*
Y1121446D01*
X391862Y1121447D01*
G01X399261Y1119337D02*
Y1121446D01*
X399262Y1121447D01*
G01X397412Y1128950D02*
Y1131059D01*
X397411Y1131060D01*
G01X393712Y1128950D02*
Y1131059D01*
X393711Y1131060D01*
G01X390012Y1128950D02*
Y1131059D01*
X390011Y1131060D01*
G01X401112Y1128950D02*
Y1131059D01*
X401111Y1131060D01*
G01X399261Y1132154D02*
Y1134263D01*
X399262Y1134264D01*
G01X391861Y1132154D02*
Y1134263D01*
X391862Y1134264D01*
G01X403051Y1325373D02*
X404560Y1323864D01*
Y1322800D01*
G01X406225Y1331647D02*
X405806Y1331228D01*
Y1331198D01*
X404886Y1330278D01*
X402973D01*
G01X406174Y1325260D02*
Y1325599D01*
X402973Y1328800D01*
Y1330278D01*
G01X401849Y1385910D02*
Y1389731D01*
X403260Y1391142D01*
G01D02*
X404077Y1390325D01*
X408740D01*
G01X419179Y843877D02*
Y841467D01*
G01X404379Y843877D02*
Y841467D01*
G01X411779Y843877D02*
Y841467D01*
G01X413628Y853490D02*
Y851381D01*
X413629Y851380D01*
G01X409928Y853490D02*
Y851381D01*
X409929Y851380D01*
G01X406228Y853490D02*
Y851381D01*
X406229Y851380D01*
G01X417328Y853490D02*
Y851381D01*
X417329Y851380D01*
G01X415479Y850286D02*
Y848177D01*
X415478Y848176D01*
G01X408079Y850286D02*
Y848178D01*
X408078Y848177D01*
Y848176D01*
G01X413628Y866307D02*
X413629Y866306D01*
Y864197D01*
G01X409928Y866307D02*
X409929Y866306D01*
Y864197D01*
G01X406228Y866307D02*
X406229Y866306D01*
Y864197D01*
G01X417328Y866307D02*
X417329Y866306D01*
Y864197D01*
G01X415479Y863103D02*
Y860994D01*
X415478Y860993D01*
G01X408079Y863103D02*
Y860994D01*
X408078Y860993D01*
G01X413628Y879124D02*
Y877015D01*
X413629Y877014D01*
G01X409928Y879124D02*
Y877015D01*
X409929Y877014D01*
G01X406228Y879124D02*
Y877015D01*
X406229Y877014D01*
G01X417328Y879124D02*
Y877015D01*
X417329Y877014D01*
G01X415479Y875920D02*
Y873811D01*
X415478Y873810D01*
G01X413628Y891942D02*
Y889833D01*
X413629Y889832D01*
G01X411779Y895146D02*
Y893036D01*
G01X409928Y891942D02*
Y889833D01*
X409929Y889832D01*
G01X408079Y895146D02*
Y893036D01*
G01X406228Y891942D02*
Y889833D01*
X406229Y889832D01*
G01X417328Y891942D02*
Y889833D01*
X417329Y889832D01*
G01X415479Y888737D02*
Y886628D01*
X415478Y886627D01*
G01X408079Y888737D02*
Y886628D01*
X408078Y886627D01*
G01X406228Y898350D02*
Y896241D01*
X406229Y896240D01*
G01X415479Y901555D02*
Y899446D01*
X415478Y899445D01*
G01X408079Y901555D02*
Y899446D01*
X408078Y899445D01*
G01X404379Y914372D02*
Y912263D01*
X404378Y912262D01*
G01X419179Y914372D02*
X419178Y914371D01*
Y912262D01*
G01X409928Y917576D02*
X409929Y917575D01*
Y915466D01*
G01X409928Y923985D02*
X409929Y923984D01*
Y921875D01*
G01X414616Y939223D02*
X414093Y939746D01*
Y942098D01*
G01X408512Y1039230D02*
Y1041339D01*
X408511Y1041340D01*
G01X417761Y1042434D02*
G02X417762Y1044544I2226050J0D01*
G01X412211Y1047749D02*
Y1045639D01*
G01X404811Y1047749D02*
Y1045639D01*
G01X404812Y1039230D02*
Y1041339D01*
X404811Y1041340D01*
G01X415912Y1058455D02*
X415911Y1058456D01*
Y1060565D01*
G01X415912Y1052047D02*
X415911Y1052048D01*
Y1054157D01*
G01X412212Y1058455D02*
X412211Y1058456D01*
Y1060565D01*
G01X410361Y1048842D02*
Y1050952D01*
G01X408512Y1052047D02*
X408511Y1052048D01*
Y1054157D01*
G01X417761Y1048842D02*
Y1050952D01*
G01X415912Y1064864D02*
X415911Y1064865D01*
Y1066974D01*
G01X415912Y1077681D02*
Y1079790D01*
X415911Y1079791D01*
G01X417761Y1080885D02*
Y1082995D01*
G01X406661Y1093703D02*
Y1095812D01*
X406662Y1095813D01*
G01X404812Y1090498D02*
Y1092606D01*
X404811Y1092607D01*
Y1092608D01*
G01X417761Y1093703D02*
Y1095812D01*
X417762Y1095813D01*
G01X415912Y1096907D02*
Y1099017D01*
G01X417761Y1100111D02*
Y1102220D01*
X417762Y1102221D01*
G01X415912Y1116133D02*
Y1118242D01*
X415911Y1118243D01*
G01X414061Y1119337D02*
Y1121447D01*
G01X412212Y1122541D02*
Y1124650D01*
X412211Y1124651D01*
G01X412212Y1116133D02*
Y1118242D01*
X412211Y1118243D01*
G01X408512Y1116133D02*
Y1118242D01*
X408511Y1118243D01*
G01X404812Y1116133D02*
Y1118242D01*
X404811Y1118243D01*
G01X417761Y1112929D02*
Y1115039D01*
G01X410361Y1125746D02*
Y1127856D01*
G01X419612Y1116133D02*
Y1118243D01*
G01X406661Y1119337D02*
Y1121447D01*
G01X414061Y1132154D02*
X414062Y1134264D01*
G01X412212Y1128950D02*
Y1131060D01*
G01X410361Y1138563D02*
Y1140973D01*
G01X408512Y1128950D02*
Y1131059D01*
X408511Y1131060D01*
G01X404812Y1128950D02*
Y1131059D01*
X404811Y1131060D01*
G01X406661Y1132154D02*
Y1134263D01*
X406662Y1134264D01*
G01X410225Y1329329D02*
X410285D01*
X410286Y1329328D01*
X411489Y1326422D01*
Y1325260D01*
G01X406225Y1328591D02*
Y1328297D01*
X407946Y1326576D01*
Y1325260D01*
G01X414333Y1385292D02*
Y1386087D01*
X415731Y1387485D01*
X416976D01*
X418552Y1389061D01*
Y1390306D01*
G01X410933Y1384648D02*
X409671Y1385910D01*
X407749D01*
G01X411890Y1390325D02*
X415383D01*
X415402Y1390306D01*
G01X417920Y1395170D02*
Y1393138D01*
X415402Y1390620D01*
Y1390306D01*
G01X432128Y847081D02*
Y844671D01*
G01X426579Y843877D02*
Y841467D01*
G01X432128Y853490D02*
Y851381D01*
X432129Y851380D01*
G01X428428Y853490D02*
Y851381D01*
X428429Y851380D01*
G01X424728Y853490D02*
Y851381D01*
X424729Y851380D01*
G01X421028Y853490D02*
Y851381D01*
X421029Y851380D01*
G01X435829Y853490D02*
Y851380D01*
G01X422879Y850286D02*
Y848178D01*
X422878Y848177D01*
Y848176D01*
G01X432128Y866307D02*
X432129Y866306D01*
Y864197D01*
G01X428428Y866307D02*
X428429Y866306D01*
Y864197D01*
G01X424728Y866307D02*
X424729Y866306D01*
Y864197D01*
G01X421028Y866307D02*
X421029Y866306D01*
Y864197D01*
G01X435829Y866307D02*
Y864197D01*
G01X422879Y863103D02*
Y860994D01*
X422878Y860993D01*
G01X432128Y879124D02*
Y877015D01*
X432129Y877014D01*
G01X428428Y879124D02*
Y877015D01*
X428429Y877014D01*
G01X424728Y879124D02*
Y877015D01*
X424729Y877014D01*
G01X421028Y879124D02*
Y877015D01*
X421029Y877014D01*
G01X435829Y879124D02*
Y877014D01*
G01X422879Y875920D02*
Y873811D01*
X422878Y873810D01*
G01X430279Y875920D02*
Y873811D01*
X430278Y873810D01*
G01X432128Y891942D02*
Y889833D01*
X432129Y889832D01*
G01X428428Y891942D02*
Y889833D01*
X428429Y889832D01*
G01X424728Y891942D02*
Y889833D01*
X424729Y889832D01*
G01X421028Y891942D02*
Y889833D01*
X421029Y889832D01*
G01X435829D02*
Y891942D01*
G01X430279Y888737D02*
Y886628D01*
X430278Y886627D01*
G01X422879Y888737D02*
Y886628D01*
X422878Y886627D01*
G01X430279Y901555D02*
Y899446D01*
X430278Y899445D01*
G01X428428Y917576D02*
Y915467D01*
X428429Y915466D01*
G01X433979Y927189D02*
Y925080D01*
X433980Y925079D01*
G01X433979Y933598D02*
Y931488D01*
X433980Y931487D01*
G01X428428Y923985D02*
X428429Y923984D01*
Y921875D01*
G01X430279Y937897D02*
Y940006D01*
G01X433979D02*
Y937897D01*
G01Y946414D02*
Y944306D01*
X433980Y944305D01*
G01X432128Y943210D02*
Y941103D01*
X432130Y941101D01*
G01X433979Y959232D02*
Y957124D01*
X433980Y957123D01*
G01X433979Y952823D02*
Y950715D01*
X433980Y950714D01*
G01X433979Y965640D02*
Y963532D01*
X433980Y963531D01*
G01X433979Y978457D02*
X433980Y978456D01*
Y976348D01*
G01X433979Y972049D02*
Y969941D01*
X433980Y969940D01*
G01X433979Y984866D02*
X433980Y984865D01*
Y982757D01*
G01X434412Y1007187D02*
Y1009297D01*
X434411Y1009298D01*
G01X434412Y1000778D02*
Y1002889D01*
G01Y1013595D02*
Y1015706D01*
G01Y1026413D02*
Y1028523D01*
X434411Y1028524D01*
G01X434412Y1020004D02*
Y1022114D01*
X434411Y1022115D01*
G01X428861Y1042434D02*
G02X428862Y1044544I2226050J0D01*
G01X434412Y1032821D02*
Y1034932D01*
G01X430711Y1045639D02*
Y1047748D01*
X430712Y1047749D01*
G01X423312Y1045639D02*
Y1047748D01*
X423311Y1047749D01*
G01X425161Y1042434D02*
Y1044543D01*
X425162Y1044544D01*
G01X434412Y1045638D02*
Y1045639D01*
G01D02*
Y1047749D01*
G01X425161Y1055251D02*
X425162Y1055252D01*
Y1057361D01*
G01X432561Y1048842D02*
Y1050952D01*
G01X434412Y1058455D02*
Y1060564D01*
X434411Y1060565D01*
G01X434412Y1052047D02*
Y1054156D01*
X434411Y1054157D01*
G01X421461Y1061660D02*
X421462Y1061661D01*
Y1063770D01*
G01X432561Y1074477D02*
Y1076587D01*
G01X434412Y1071273D02*
Y1073382D01*
X434411Y1073383D01*
G01X434412Y1064864D02*
Y1066973D01*
X434411Y1066974D01*
G01X434412Y1077681D02*
Y1079790D01*
X434411Y1079791D01*
G01X423312Y1077681D02*
Y1079790D01*
X423311Y1079791D01*
G01X428861Y1080885D02*
Y1082995D01*
G01X421461Y1080885D02*
Y1082994D01*
X421462Y1082995D01*
G01X432561Y1087294D02*
Y1089404D01*
G01Y1080885D02*
Y1082995D01*
G01X434412Y1090498D02*
Y1092607D01*
X434411Y1092608D01*
G01X434412Y1084090D02*
Y1086199D01*
X434411Y1086200D01*
G01X428861Y1093703D02*
Y1095813D01*
G01X421461Y1093703D02*
Y1095812D01*
X421462Y1095813D01*
G01X432561Y1093703D02*
Y1095813D01*
G01X427012Y1096907D02*
Y1099016D01*
X427011Y1099017D01*
G01X425161Y1100111D02*
Y1102221D01*
G01X423312Y1103316D02*
Y1105425D01*
X423311Y1105426D01*
G01X421461Y1106520D02*
Y1108629D01*
X421462Y1108630D01*
G01X434412Y1103316D02*
Y1105425D01*
X434411Y1105426D01*
G01X423312Y1109724D02*
Y1111833D01*
X423311Y1111834D01*
G01X434412Y1109724D02*
Y1111833D01*
X434411Y1111834D01*
G01X423312Y1096907D02*
Y1099016D01*
X423311Y1099017D01*
G01X421461Y1100111D02*
X421462Y1100112D01*
Y1102221D01*
G01X434412Y1096907D02*
Y1099017D01*
G01X423312Y1122541D02*
Y1124650D01*
X423311Y1124651D01*
G01X423312Y1116133D02*
Y1118242D01*
X423311Y1118243D01*
G01X421461Y1112929D02*
Y1115038D01*
X421462Y1115039D01*
G01X434412Y1122541D02*
Y1124650D01*
X434411Y1124651D01*
G01X434412Y1116133D02*
Y1118242D01*
X434411Y1118243D01*
G01X423312Y1135359D02*
Y1137469D01*
G01Y1128950D02*
Y1131059D01*
X423311Y1131060D01*
G01X434412Y1135359D02*
Y1137769D01*
G01Y1128950D02*
Y1131059D01*
X434411Y1131060D01*
G01X430711Y1135359D02*
Y1137769D01*
G01X433669Y1323910D02*
X432412Y1325167D01*
X432063D01*
G01X435179Y1325373D02*
X436688Y1323864D01*
Y1322800D01*
G01X438353Y1331647D02*
X437013Y1330307D01*
X434983D01*
G01D02*
Y1328889D01*
X438302Y1325570D01*
Y1325260D01*
G01X439528Y847081D02*
Y844672D01*
X439529Y844671D01*
G01X446928Y853490D02*
Y851381D01*
X446929Y851380D01*
G01X443228Y853490D02*
Y851380D01*
G01X439528Y853490D02*
Y851381D01*
X439529Y851380D01*
G01X450629Y853490D02*
Y851380D01*
G01X448779Y856694D02*
Y854584D01*
G01X446928Y866307D02*
X446929Y866306D01*
Y864197D01*
G01X443228Y866307D02*
X443229Y866306D01*
Y864197D01*
G01X439528Y866307D02*
Y864198D01*
X439529Y864197D01*
G01X450629Y866307D02*
Y864197D01*
G01X445079Y863103D02*
Y860994D01*
X445078Y860993D01*
G01X446928Y879124D02*
Y877015D01*
X446929Y877014D01*
G01X443228Y879124D02*
Y877015D01*
X443229Y877014D01*
G01X439528Y879124D02*
Y877015D01*
X439529Y877014D01*
G01X450629Y879124D02*
Y877014D01*
G01X437679Y875920D02*
Y873810D01*
G01X445079Y875920D02*
Y873811D01*
X445078Y873810D01*
G01X446928Y891942D02*
Y889833D01*
X446929Y889832D01*
G01X443228Y891942D02*
Y889833D01*
X443229Y889832D01*
G01X439528Y891942D02*
Y889833D01*
X439529Y889832D01*
G01X437679Y888737D02*
Y886628D01*
X437678Y886627D01*
G01X450629Y889832D02*
Y891942D01*
G01X452479Y888737D02*
Y886628D01*
X452478Y886627D01*
G01X445079Y888737D02*
Y886628D01*
X445078Y886627D01*
G01X437679Y914372D02*
X437678Y914371D01*
Y912262D01*
G01X446928Y917576D02*
Y915467D01*
X446929Y915466D01*
G01X452479Y901555D02*
X452478Y901554D01*
Y899445D01*
G01X446928Y930393D02*
Y928285D01*
X446930Y928283D01*
G01X441379Y927189D02*
Y925079D01*
G01Y933598D02*
Y931487D01*
G01X446928Y923985D02*
X446929Y923984D01*
Y921875D01*
G01X441379Y940006D02*
Y937897D01*
G01X445079Y940006D02*
Y937897D01*
G01X437679Y940006D02*
Y937897D01*
G01X448779Y940006D02*
Y937897D01*
G01X446928Y943210D02*
Y941102D01*
X446929Y941101D01*
G01X446928Y949619D02*
Y947512D01*
X446930Y947510D01*
G01X446928Y962436D02*
Y960329D01*
X446930Y960327D01*
G01X446928Y956027D02*
Y953920D01*
X446930Y953918D01*
G01X446928Y968845D02*
Y966738D01*
X446930Y966736D01*
G01X446928Y981662D02*
Y979555D01*
X446930Y979553D01*
G01X446928Y975253D02*
Y973146D01*
X446930Y973144D01*
G01X447361Y997574D02*
Y999684D01*
X447362Y999685D01*
G01X447361Y1003983D02*
Y1006093D01*
X447362Y1006094D01*
G01X447361Y1010391D02*
Y1012501D01*
X447362Y1012502D01*
G01X447361Y1023208D02*
Y1025318D01*
X447362Y1025319D01*
G01X447361Y1016800D02*
Y1018910D01*
X447362Y1018911D01*
G01X447361Y1029617D02*
X447362Y1029618D01*
Y1031728D01*
G01X447361Y1036026D02*
Y1038134D01*
X447360Y1038135D01*
Y1038136D01*
G01X451061Y1042434D02*
Y1044544D01*
G01X449212Y1045639D02*
Y1047748D01*
X449211Y1047749D01*
G01X447361Y1055251D02*
Y1057361D01*
G01Y1048842D02*
Y1050952D01*
G01Y1061660D02*
Y1063770D01*
G01X451061Y1061660D02*
Y1063770D01*
G01X447361Y1074477D02*
Y1076587D01*
G01Y1068068D02*
Y1070178D01*
G01X449212Y1077681D02*
X449211Y1079791D01*
G01X449212Y1064864D02*
Y1066973D01*
X449211Y1066974D01*
G01X447361Y1080885D02*
Y1082995D01*
G01X451061Y1087294D02*
Y1089403D01*
X451062Y1089404D01*
G01X449212Y1084090D02*
Y1086200D01*
G01X451061Y1093703D02*
Y1095812D01*
X451062Y1095813D01*
G01X447361Y1093703D02*
Y1095813D01*
G01Y1106520D02*
Y1108630D01*
G01Y1100111D02*
Y1102221D01*
G01Y1119337D02*
Y1121447D01*
G01Y1112929D02*
Y1115039D01*
G01Y1125746D02*
Y1127856D01*
G01Y1132154D02*
Y1134264D01*
G01X442353Y1329329D02*
X442413D01*
X442414Y1329328D01*
X443617Y1326422D01*
Y1325260D01*
G01X438353Y1328591D02*
Y1328297D01*
X440074Y1326576D01*
Y1325260D01*
G01X455434Y1404469D02*
X453748D01*
X451014Y1401735D01*
Y1400554D01*
G01Y1397404D02*
Y1393959D01*
G01Y1397404D02*
X448579D01*
X448114Y1396939D01*
G01D02*
Y1396812D01*
G01X448020Y1391862D02*
X448949D01*
X449012Y1391799D01*
X453044D01*
X454164Y1392919D01*
Y1393959D01*
G01X450026Y1413125D02*
X447400Y1415751D01*
X445339D01*
G01D02*
Y1415731D01*
G01X467736Y296973D02*
Y302358D01*
G01Y309838D02*
Y312938D01*
G01X458028Y853490D02*
Y851381D01*
X458029Y851380D01*
G01X461728Y853490D02*
Y851381D01*
X461729Y851380D01*
G01X454328Y853490D02*
Y851380D01*
G01X456179Y843877D02*
Y841467D01*
G01X463579Y843877D02*
Y841467D01*
G01X465428Y853490D02*
Y851381D01*
X465429Y851380D01*
G01X459879Y850286D02*
X459878Y850285D01*
Y848176D01*
G01X467279Y850286D02*
Y848178D01*
X467278Y848177D01*
Y848176D01*
G01X456179Y856694D02*
Y854584D01*
G01X463579Y856694D02*
Y854584D01*
G01X461728Y866307D02*
X461729Y866306D01*
Y864197D01*
G01X458028Y866307D02*
X458029Y866306D01*
Y864197D01*
G01X454328Y866307D02*
X454329Y866306D01*
Y864197D01*
G01X465428Y866307D02*
X465429Y866306D01*
Y864197D01*
G01X452479Y863103D02*
Y860993D01*
G01X459879Y863103D02*
Y860994D01*
X459878Y860993D01*
G01X467279Y863103D02*
Y860994D01*
X467278Y860993D01*
G01X461728Y879124D02*
Y877015D01*
X461729Y877014D01*
G01X458028Y879124D02*
Y877015D01*
X458029Y877014D01*
G01X454328Y879124D02*
Y877015D01*
X454329Y877014D01*
G01X465428Y879124D02*
Y877015D01*
X465429Y877014D01*
G01X459879Y875920D02*
Y873811D01*
X459878Y873810D01*
G01X467279Y875920D02*
Y873811D01*
X467278Y873810D01*
G01X452479Y875920D02*
Y873810D01*
G01X461728Y891942D02*
Y889833D01*
X461729Y889832D01*
G01X458028Y891942D02*
Y889833D01*
X458029Y889832D01*
G01X454328Y891942D02*
Y889833D01*
X454329Y889832D01*
G01X465428Y891942D02*
Y889833D01*
X465429Y889832D01*
G01X459879Y901555D02*
X459878Y901554D01*
Y899445D01*
G01X459879Y888737D02*
Y886628D01*
X459878Y886627D01*
G01X467279Y901555D02*
X467278Y901554D01*
Y899445D01*
G01X467279Y888737D02*
Y886628D01*
X467278Y886627D01*
G01X458028Y904759D02*
X458029Y904758D01*
Y902649D01*
G01X456179Y907963D02*
X456178Y907962D01*
Y905853D01*
G01X465428Y904759D02*
X465429Y904758D01*
Y902649D01*
G01X465428Y917576D02*
Y915467D01*
X465429Y915466D01*
G01X461728Y923985D02*
X461729Y923984D01*
Y921875D01*
G01X452912Y1039230D02*
Y1041338D01*
X452911Y1041339D01*
Y1041340D01*
G01X465861Y1042434D02*
Y1044544D01*
G01X456612Y1045639D02*
Y1047748D01*
X456611Y1047749D01*
G01X464012Y1045639D02*
Y1047748D01*
X464011Y1047749D01*
G01X465861Y1055251D02*
X465862Y1057361D01*
G01X465861Y1061660D02*
X465862Y1063653D01*
Y1063770D01*
G01X467712Y1052047D02*
Y1054157D01*
G01Y1058455D02*
Y1060565D01*
G01X454761Y1061660D02*
Y1063770D01*
G01X452912Y1077681D02*
X452911Y1079791D01*
G01X454761Y1074477D02*
Y1076587D01*
G01X467712Y1064864D02*
X467711Y1066974D01*
G01X456612Y1077681D02*
Y1079791D01*
G01X467712Y1077681D02*
X467711Y1079791D01*
G01X456612Y1064864D02*
Y1066973D01*
X456611Y1066974D01*
G01X452912Y1064864D02*
Y1066973D01*
X452911Y1066974D01*
G01X452912Y1090498D02*
Y1092607D01*
X452911Y1092608D01*
G01X458461Y1080885D02*
Y1082995D01*
G01X464012Y1084090D02*
X464011Y1086200D01*
G01X467712Y1084090D02*
Y1086200D01*
G01Y1090498D02*
Y1092608D01*
G01X452912Y1084090D02*
Y1086199D01*
X452911Y1086200D01*
G01X465861Y1080885D02*
X465862Y1080886D01*
Y1082995D01*
G01X462161Y1080885D02*
X462162Y1080886D01*
Y1082995D01*
G01X452912Y1096907D02*
Y1099016D01*
X452911Y1099017D01*
G01X460312Y1103316D02*
Y1105426D01*
G01X458461Y1100111D02*
Y1102220D01*
X458462Y1102221D01*
G01X456612Y1096907D02*
Y1099016D01*
X456611Y1099017D01*
G01X464012Y1103316D02*
Y1105426D01*
G01Y1096907D02*
Y1099017D01*
G01X462161Y1106520D02*
Y1108629D01*
X462162Y1108630D01*
G01X465861Y1106520D02*
Y1108630D01*
G01Y1100111D02*
Y1102221D01*
G01X464012Y1109724D02*
Y1111834D01*
G01X467712Y1103316D02*
Y1105425D01*
X467711Y1105426D01*
G01X467712Y1109724D02*
X467711Y1109725D01*
Y1111834D01*
G01X467712Y1096907D02*
X467711Y1099017D01*
G01X462161Y1100111D02*
X462162Y1102221D01*
G01X458461Y1119337D02*
Y1121446D01*
X458462Y1121447D01*
G01X458461Y1112929D02*
Y1115038D01*
X458462Y1115039D01*
G01X467712Y1122541D02*
Y1124651D01*
G01Y1116133D02*
Y1118242D01*
X467711Y1118243D01*
G01X465861Y1119337D02*
Y1121446D01*
X465862Y1121447D01*
G01X465861Y1112929D02*
Y1115038D01*
X465862Y1115039D01*
G01X458461Y1125746D02*
Y1127855D01*
X458462Y1127856D01*
G01X458461Y1132154D02*
Y1134263D01*
X458462Y1134264D01*
G01X465797Y1323910D02*
X464540Y1325167D01*
X464191D01*
G01X467307Y1325373D02*
X468816Y1323864D01*
Y1322800D01*
G01X470481Y1331647D02*
X469159Y1330325D01*
X467644D01*
G01D02*
Y1328423D01*
X470430Y1325637D01*
Y1325260D01*
G01X459321Y1393009D02*
X458371Y1393959D01*
X454164D01*
G01X459321Y1396409D02*
X458377Y1395465D01*
X456654D01*
X455434Y1396685D01*
Y1398569D01*
G01X468880Y1418400D02*
X469080D01*
X470430Y1419750D01*
Y1426212D01*
X469277Y1427365D01*
X464411D01*
X463410Y1428366D01*
Y1431504D01*
G01X482920Y398060D02*
X485673Y395307D01*
Y382405D01*
G01X478379Y843877D02*
Y841467D01*
G01X469128Y853490D02*
Y851381D01*
X469129Y851380D01*
G01X470979Y843877D02*
Y841467D01*
G01X476528Y853490D02*
Y851381D01*
X476529Y851380D01*
G01X480228Y853490D02*
Y851381D01*
X480229Y851380D01*
G01X472828Y853490D02*
Y851381D01*
X472829Y851380D01*
G01X483928Y853490D02*
Y851381D01*
X483929Y851380D01*
G01X482079Y850286D02*
Y848178D01*
X482078Y848177D01*
Y848176D01*
G01X474679Y850286D02*
Y848178D01*
X474678Y848177D01*
Y848176D01*
G01X469128Y866307D02*
X469129Y866306D01*
Y864197D01*
G01X480228Y866307D02*
X480229Y866306D01*
Y864197D01*
G01X478379Y856694D02*
Y854584D01*
G01X476528Y866307D02*
X476529Y866306D01*
Y864197D01*
G01X470979Y856694D02*
Y854584D01*
G01X472828Y866307D02*
X472829Y866306D01*
Y864197D01*
G01X483928Y866307D02*
X483929Y866306D01*
Y864197D01*
G01X482079Y863103D02*
Y860994D01*
X482078Y860993D01*
G01X474679Y863103D02*
Y860994D01*
X474678Y860993D01*
G01X469128Y879124D02*
Y877015D01*
X469129Y877014D01*
G01X480228Y879124D02*
Y877015D01*
X480229Y877014D01*
G01X476528Y879124D02*
Y877015D01*
X476529Y877014D01*
G01X472828Y879124D02*
Y877015D01*
X472829Y877014D01*
G01X470979Y875920D02*
Y873810D01*
G01X483928Y879124D02*
Y877015D01*
X483929Y877014D01*
G01X482079Y875920D02*
Y873811D01*
X482078Y873810D01*
G01X474679Y875920D02*
Y873811D01*
X474678Y873810D01*
G01X469128Y898350D02*
X469129Y898349D01*
Y896240D01*
G01X469128Y891942D02*
Y889833D01*
X469129Y889832D01*
G01X480228Y891942D02*
Y889833D01*
X480229Y889832D01*
G01X476528Y891942D02*
Y889833D01*
X476529Y889832D01*
G01X472828Y891942D02*
Y889833D01*
X472829Y889832D01*
G01X483928Y891942D02*
Y889833D01*
X483929Y889832D01*
G01X474679Y901555D02*
X474678Y901554D01*
Y899445D01*
G01X482079Y901555D02*
X482078Y901554D01*
Y899445D01*
G01X482079Y888737D02*
Y886628D01*
X482078Y886627D01*
G01X474679Y888737D02*
Y886628D01*
X474678Y886627D01*
G01X474679Y907963D02*
X474678Y907962D01*
Y905853D01*
G01X483928Y911167D02*
X483929Y911166D01*
Y909057D01*
G01X482079Y914372D02*
Y912262D01*
G01X483928Y904759D02*
Y902649D01*
G01X482079Y907963D02*
X482078Y907962D01*
Y905853D01*
G01X480228Y923985D02*
X480229Y923984D01*
Y921875D01*
G01X476528Y923985D02*
Y921875D01*
G01X474679Y920780D02*
X474678Y920779D01*
Y918670D01*
G01X482079Y920780D02*
X482078Y920779D01*
Y918670D01*
G01X483928Y923985D02*
Y921875D01*
G01X480228Y936801D02*
Y934692D01*
X480229Y934691D01*
G01X482079Y946414D02*
Y944304D01*
G01X483928Y949619D02*
Y947509D01*
G01X480228Y949619D02*
Y947510D01*
X480229Y947509D01*
G01X482079Y959232D02*
X482078Y959231D01*
Y957122D01*
G01X482079Y952823D02*
Y950713D01*
G01X480228Y956027D02*
X480229Y956026D01*
Y953917D01*
G01X478379Y959232D02*
X478378Y959231D01*
Y957122D01*
G01X478379Y952823D02*
X478378Y952822D01*
Y950713D01*
G01X482512Y1000778D02*
Y1002887D01*
X482511Y1002888D01*
G01X478812Y1013595D02*
X478811Y1015705D01*
G01X482512Y1020004D02*
Y1020053D01*
X482511Y1022114D01*
G01X484361Y1016800D02*
Y1018910D01*
G01X480661Y1016800D02*
Y1018910D01*
G01X478812Y1026413D02*
Y1028521D01*
X478811Y1028522D01*
Y1028523D01*
G01X478812Y1020004D02*
Y1022113D01*
X478811Y1022114D01*
G01X471412Y1045639D02*
Y1047748D01*
X471411Y1047749D01*
G01X482512Y1045639D02*
Y1047748D01*
X482511Y1047749D01*
G01X478812Y1045639D02*
Y1047748D01*
X478811Y1047749D01*
G01X476961Y1042434D02*
Y1044543D01*
X476962Y1044544D01*
G01X480661Y1048842D02*
X480662Y1050952D01*
G01X475112Y1058455D02*
X475111Y1060565D01*
G01X471412Y1052047D02*
X471411Y1054157D01*
G01X484361Y1055251D02*
Y1057361D01*
G01X482512Y1058455D02*
X482511Y1060565D01*
G01X484361Y1048842D02*
X484362Y1050952D01*
G01X473261Y1055251D02*
Y1057361D01*
G01X471412Y1058455D02*
Y1060565D01*
G01X475112Y1052047D02*
Y1054157D01*
G01X469561Y1055251D02*
Y1057361D01*
G01Y1048842D02*
Y1050952D01*
G01X480661Y1055251D02*
Y1057361D01*
G01X478812Y1058455D02*
Y1060565D01*
G01Y1052047D02*
Y1054157D01*
G01X476961Y1048842D02*
Y1050952D01*
G01X480661Y1061660D02*
X480662Y1063653D01*
Y1063770D01*
G01X476961Y1061660D02*
X476962Y1063653D01*
Y1063770D01*
G01X476961Y1055251D02*
Y1057360D01*
X476962Y1057361D01*
G01X473261Y1061660D02*
X473262Y1063653D01*
Y1063770D01*
G01X469561Y1061660D02*
X469562Y1063653D01*
Y1063770D01*
G01X482512Y1052047D02*
X482511Y1052048D01*
Y1054157D01*
G01X473261Y1048842D02*
Y1050951D01*
X473262Y1050952D01*
G01X482512Y1064864D02*
Y1066974D01*
G01X473261Y1080885D02*
X473262Y1082995D01*
G01X482512Y1084090D02*
Y1086200D01*
G01X469561Y1093703D02*
X469562Y1095813D01*
G01X480661Y1087294D02*
X480662Y1089404D01*
G01X473261Y1093703D02*
Y1095812D01*
X473262Y1095813D01*
G01X469561Y1080885D02*
X469562Y1080886D01*
Y1082995D01*
G01X480661Y1106520D02*
X480662Y1108630D01*
G01X476961Y1100111D02*
X476962Y1102221D01*
G01X475112Y1096907D02*
Y1099017D01*
G01X471412Y1096907D02*
X471411Y1099017D01*
G01X469561Y1100111D02*
X469562Y1102221D01*
G01X482512Y1109724D02*
X482511Y1111834D01*
G01X484361Y1106520D02*
Y1108628D01*
X484362Y1108629D01*
Y1108630D01*
G01X475112Y1109724D02*
Y1111833D01*
X475111Y1111834D01*
G01X471412Y1109724D02*
Y1111833D01*
X471411Y1111834D01*
G01X478812Y1103316D02*
X478811Y1105426D01*
G01X469561Y1106520D02*
X469562Y1106521D01*
Y1108630D01*
G01X473261Y1100111D02*
Y1102220D01*
X473262Y1102221D01*
G01X482512Y1096907D02*
Y1099016D01*
X482511Y1099017D01*
G01X478812Y1109724D02*
Y1111833D01*
X478811Y1111834D01*
G01X476961Y1106520D02*
Y1108628D01*
X476962Y1108629D01*
Y1108630D01*
G01X471412Y1103316D02*
Y1105425D01*
X471411Y1105426D01*
G01X475112Y1103316D02*
Y1105425D01*
X475111Y1105426D01*
G01X484361Y1100111D02*
Y1102220D01*
X484362Y1102221D01*
G01X480661Y1100111D02*
Y1102220D01*
X480662Y1102221D01*
G01X480661Y1112929D02*
Y1115039D01*
G01X478812Y1116133D02*
Y1118242D01*
X478811Y1118243D01*
G01X476961Y1112929D02*
Y1115039D01*
G01X475112Y1116133D02*
Y1118242D01*
X475111Y1118243D01*
G01X471412Y1116133D02*
Y1118242D01*
X471411Y1118243D01*
G01X469561Y1112929D02*
Y1115039D01*
G01X482512Y1116133D02*
Y1118242D01*
X482511Y1118243D01*
G01X476961Y1125746D02*
Y1127856D01*
G01X469561Y1125746D02*
Y1127855D01*
X469562Y1127856D01*
G01X484361Y1112929D02*
X484362Y1112930D01*
Y1115039D01*
G01X473261Y1112929D02*
X473262Y1112930D01*
Y1115039D01*
G01X480661Y1119337D02*
X480662Y1121447D01*
G01X473261Y1119337D02*
X473262Y1121447D01*
G01X478812Y1128950D02*
Y1131059D01*
X478811Y1131060D01*
G01X475112Y1128950D02*
Y1131059D01*
X475111Y1131060D01*
G01X471412Y1135359D02*
Y1137469D01*
G01Y1128950D02*
Y1131060D01*
G01X469561Y1138563D02*
Y1140973D01*
G01X473261Y1132154D02*
Y1134264D01*
G01X482512Y1128950D02*
Y1131059D01*
X482511Y1131060D01*
G01X480661Y1132154D02*
Y1134263D01*
X480662Y1134264D01*
G01X474481Y1329329D02*
X474541D01*
X474542Y1329328D01*
X475745Y1326422D01*
Y1325260D01*
G01X470481Y1328591D02*
Y1328297D01*
X472202Y1326576D01*
Y1325260D01*
G01X480252Y1415918D02*
X480493Y1416159D01*
X482731D01*
X483551Y1415339D01*
X484294D01*
G01X471530Y1414650D02*
X473110Y1413070D01*
X473760D01*
X475686Y1411144D01*
X476496D01*
G01X476281Y1415918D02*
X472798D01*
X471530Y1414650D01*
G01X483821Y1411262D02*
X481448Y1413635D01*
X478745D01*
X476496Y1411386D01*
Y1411144D01*
G01X479646D02*
Y1409367D01*
X481468Y1407545D01*
G01X481997Y1409955D02*
Y1410144D01*
X480997Y1411144D01*
X479646D01*
G01X485834Y1409296D02*
X484083Y1407545D01*
X481468D01*
G01X477368D02*
X472701D01*
G01X470987Y1409965D02*
X472701Y1408251D01*
Y1407545D01*
G01X499073Y382512D02*
Y384563D01*
X502740Y388230D01*
G01D02*
Y392460D01*
X497568Y397632D01*
G01X493179Y843877D02*
Y841467D01*
G01X485779Y843877D02*
Y841467D01*
G01X500579Y843877D02*
Y841467D01*
G01X495028Y853490D02*
Y851381D01*
X495029Y851380D01*
G01X491328Y853490D02*
Y851381D01*
X491329Y851380D01*
G01X487628Y853490D02*
Y851381D01*
X487629Y851380D01*
G01X498728Y853490D02*
Y851381D01*
X498729Y851380D01*
G01X489479Y850286D02*
Y848178D01*
X489478Y848177D01*
Y848176D01*
G01X496879Y850286D02*
Y848178D01*
X496878Y848177D01*
Y848176D01*
G01X495028Y866307D02*
X495029Y866306D01*
Y864197D01*
G01X493179Y856694D02*
Y854584D01*
G01X491328Y866307D02*
X491329Y866306D01*
Y864197D01*
G01X487628Y866307D02*
X487629Y866306D01*
Y864197D01*
G01X485779Y856694D02*
Y854584D01*
G01X498728Y866307D02*
X498729Y866306D01*
Y864197D01*
G01X500579Y856694D02*
Y854584D01*
G01X489479Y863103D02*
Y860994D01*
X489478Y860993D01*
G01X496879Y863103D02*
Y860994D01*
X496878Y860993D01*
G01X495028Y879124D02*
Y877015D01*
X495029Y877014D01*
G01X491328Y879124D02*
Y877015D01*
X491329Y877014D01*
G01X487628Y879124D02*
Y877015D01*
X487629Y877014D01*
G01X498728Y879124D02*
Y877015D01*
X498729Y877014D01*
G01X489479Y875920D02*
Y873811D01*
X489478Y873810D01*
G01X496879Y875920D02*
Y873811D01*
X496878Y873810D01*
G01X495028Y891942D02*
Y889833D01*
X495029Y889832D01*
G01X491328Y891942D02*
Y889833D01*
X491329Y889832D01*
G01X487628Y891942D02*
Y889833D01*
X487629Y889832D01*
G01X498728Y891942D02*
Y889833D01*
X498729Y889832D01*
G01X489479Y901555D02*
X489478Y901554D01*
Y899445D01*
G01X489479Y888737D02*
Y886628D01*
X489478Y886627D01*
G01X496879Y888737D02*
Y886628D01*
X496878Y886627D01*
G01X489479Y914372D02*
X489478Y914371D01*
Y912262D01*
G01X485779Y907963D02*
Y905854D01*
X485778Y905853D01*
G01X489479Y920780D02*
X489478Y920779D01*
Y918670D01*
G01X496879Y933598D02*
X496878Y933597D01*
Y931488D01*
G01X489479Y933598D02*
X489478Y933597D01*
Y931488D01*
G01X498728Y936801D02*
Y934692D01*
X498729Y934691D01*
G01X497312Y1007187D02*
Y1009296D01*
X497311Y1009297D01*
G01X489912Y1007187D02*
Y1009296D01*
X489911Y1009297D01*
G01X489912Y1032821D02*
Y1034930D01*
X489911Y1034931D01*
G01X486212Y1032821D02*
Y1034930D01*
X486211Y1034931D01*
G01X489912Y1045639D02*
Y1047748D01*
X489911Y1047749D01*
G01X497312Y1045639D02*
Y1047748D01*
X497311Y1047749D01*
G01X489912Y1058455D02*
X489911Y1060565D01*
G01X486212Y1052047D02*
X486211Y1054157D01*
G01X489912Y1077681D02*
Y1079790D01*
X489911Y1079791D01*
G01X491761Y1093703D02*
Y1095812D01*
X491762Y1095813D01*
G01X488061Y1093703D02*
Y1095812D01*
X488062Y1095813D01*
G01X497312Y1109724D02*
Y1111834D01*
G01X489912Y1096907D02*
Y1099016D01*
X489911Y1099017D01*
G01X495461Y1100111D02*
X495462Y1102221D01*
G01X501012Y1096907D02*
Y1099016D01*
X501011Y1099017D01*
G01X493612Y1096907D02*
Y1099016D01*
X493611Y1099017D01*
G01X497312Y1096907D02*
Y1099016D01*
X497311Y1099017D01*
G01X495461Y1106520D02*
X495462Y1106521D01*
Y1108630D01*
G01X489912Y1103316D02*
X489911Y1105426D01*
G01X486212Y1109724D02*
Y1111833D01*
X486211Y1111834D01*
G01X493612Y1109724D02*
Y1111833D01*
X493611Y1111834D01*
G01X491761Y1106520D02*
Y1108628D01*
X491762Y1108629D01*
Y1108630D01*
G01X488061Y1106520D02*
Y1108628D01*
X488062Y1108629D01*
Y1108630D01*
G01X497312Y1116133D02*
Y1118242D01*
X497311Y1118243D01*
G01X495461Y1119337D02*
X495462Y1121447D01*
G01X493612Y1116133D02*
Y1118243D01*
G01X489912Y1116133D02*
Y1118242D01*
X489911Y1118243D01*
G01X486212Y1116133D02*
Y1118242D01*
X486211Y1118243D01*
G01X501012Y1116133D02*
Y1118242D01*
X501011Y1118243D01*
G01X499161Y1112929D02*
Y1115039D01*
G01X491761Y1125746D02*
Y1127856D01*
G01X499161Y1125746D02*
Y1127856D01*
G01X491761Y1112929D02*
X491762Y1112930D01*
Y1115039D01*
G01X495461Y1112929D02*
X495462Y1112930D01*
Y1115039D01*
G01X488061Y1119337D02*
X488062Y1121447D01*
G01X488061Y1112929D02*
X488062Y1115039D01*
G01X497312Y1128950D02*
Y1131059D01*
X497311Y1131060D01*
G01X493612Y1128950D02*
Y1131059D01*
X493611Y1131060D01*
G01X489912Y1128950D02*
Y1131059D01*
X489911Y1131060D01*
G01X486212Y1128950D02*
Y1131059D01*
X486211Y1131060D01*
G01X501012Y1128950D02*
Y1131059D01*
X501011Y1131060D01*
G01X495461Y1132154D02*
Y1134263D01*
X495462Y1134264D01*
G01X488061Y1132154D02*
Y1134263D01*
X488062Y1134264D01*
G01X497925Y1337336D02*
X496668Y1338593D01*
X496319D01*
G01X499435Y1338799D02*
X500944Y1337290D01*
Y1336226D01*
G01X502609Y1345073D02*
X501300Y1343764D01*
X499458D01*
G01X502558Y1338686D02*
Y1339063D01*
X499458Y1342163D01*
Y1343764D01*
G01X501136Y301658D02*
Y296273D01*
G01Y309138D02*
Y312238D01*
G01X502740Y388230D02*
X512028D01*
X515173Y385085D01*
Y382405D01*
G01X513173Y408740D02*
Y411905D01*
G01X507979Y843877D02*
Y841467D01*
G01X515379Y843877D02*
Y841467D01*
G01X506128Y853490D02*
Y851381D01*
X506129Y851380D01*
G01X502428Y853490D02*
Y851381D01*
X502429Y851380D01*
G01X513528Y853490D02*
Y851381D01*
X513529Y851380D01*
G01X509828Y853490D02*
Y851381D01*
X509829Y851380D01*
G01X517228Y853490D02*
Y851381D01*
X517229Y851380D01*
G01X511679Y850286D02*
Y848178D01*
X511678Y848177D01*
Y848176D01*
G01X504279Y850286D02*
Y848178D01*
X504278Y848177D01*
Y848176D01*
G01X513528Y866307D02*
Y864198D01*
X513529Y864197D01*
G01X509828Y866307D02*
X509829Y864197D01*
G01X506128Y866307D02*
X506129Y866306D01*
Y864197D01*
G01X502428Y866307D02*
X502429Y866306D01*
Y864197D01*
G01X507979Y856694D02*
Y854584D01*
G01X515379Y856694D02*
Y854584D01*
G01X517228Y866307D02*
Y864198D01*
X517229Y864197D01*
G01X511679Y863103D02*
Y860994D01*
X511678Y860993D01*
G01X504279Y863103D02*
Y860994D01*
X504278Y860993D01*
G01X509828Y879124D02*
Y877015D01*
X509829Y877014D01*
G01X502428Y879124D02*
Y877015D01*
X502429Y877014D01*
G01X513528Y879124D02*
Y877015D01*
X513529Y877014D01*
G01X506128Y879124D02*
Y877015D01*
X506129Y877014D01*
G01X517228Y879124D02*
Y877015D01*
X517229Y877014D01*
G01X511679Y875920D02*
Y873811D01*
X511678Y873810D01*
G01X504279Y875920D02*
Y873811D01*
X504278Y873810D01*
G01X506128Y891942D02*
Y889833D01*
X506129Y889832D01*
G01X502428Y891942D02*
Y889833D01*
X502429Y889832D01*
G01X513528Y891942D02*
Y889833D01*
X513529Y889832D01*
G01X509828Y891942D02*
Y889833D01*
X509829Y889832D01*
G01X517228Y891942D02*
Y889833D01*
X517229Y889832D01*
G01X511679Y888737D02*
Y886628D01*
X511678Y886627D01*
G01X504279Y888737D02*
Y886628D01*
X504278Y886627D01*
G01X502428Y917576D02*
Y915467D01*
X502429Y915466D01*
G01X506128Y917576D02*
Y915467D01*
X506129Y915466D01*
G01X515379Y933598D02*
X515378Y933597D01*
Y931488D01*
G01X506128Y936801D02*
X506129D01*
Y934691D01*
G01X502428Y936801D02*
Y934692D01*
X502429Y934691D01*
G01X508412Y1000778D02*
Y1002887D01*
X508411Y1002888D01*
G01X515812Y1007187D02*
Y1009296D01*
X515811Y1009297D01*
G01X515812Y1000778D02*
Y1002887D01*
X515811Y1002888D01*
G01X502861Y1023208D02*
Y1025317D01*
X502862Y1025318D01*
G01X510261Y1029617D02*
Y1031726D01*
X510262Y1031727D01*
G01X502861Y1029617D02*
Y1031726D01*
X502862Y1031727D01*
G01X508412Y1045639D02*
Y1047748D01*
X508411Y1047749D01*
G01X515812Y1045639D02*
Y1047748D01*
X515811Y1047749D01*
G01X512112Y1052047D02*
Y1054156D01*
X512111Y1054157D01*
G01X515812Y1052047D02*
Y1054156D01*
X515811Y1054157D01*
G01X513961Y1106520D02*
X513962Y1108630D01*
G01X513961Y1100111D02*
X513962Y1102221D01*
G01X512112Y1096907D02*
Y1099017D01*
G01X508412Y1096907D02*
X508411Y1099017D01*
G01X515812Y1103316D02*
X515811Y1105426D01*
G01X515812Y1109724D02*
X515811Y1111834D01*
G01X510261Y1100111D02*
Y1102220D01*
X510262Y1102221D01*
G01X512112Y1116133D02*
Y1118242D01*
X512111Y1118243D01*
G01X508412Y1116133D02*
Y1118242D01*
X508411Y1118243D01*
G01X504712Y1116133D02*
Y1118242D01*
X504711Y1118243D01*
G01X515812Y1116133D02*
Y1118242D01*
X515811Y1118243D01*
G01X502861Y1119337D02*
X502862Y1121447D01*
G01X510261Y1119337D02*
X510262Y1121447D01*
G01X502861Y1112929D02*
X502862Y1115039D01*
G01X512112Y1128950D02*
Y1131059D01*
X512111Y1131060D01*
G01X508412Y1128950D02*
Y1131059D01*
X508411Y1131060D01*
G01X504712Y1128950D02*
Y1131059D01*
X504711Y1131060D01*
G01X515812Y1128950D02*
Y1131059D01*
X515811Y1131060D01*
G01X510261Y1132154D02*
Y1134263D01*
X510262Y1134264D01*
G01X502861Y1132154D02*
Y1134263D01*
X502862Y1134264D01*
G01X506609Y1342755D02*
X506669D01*
X506670Y1342754D01*
X507873Y1339848D01*
Y1338686D01*
G01X502609Y1342017D02*
Y1341723D01*
X504330Y1340002D01*
Y1338686D01*
G01X532173Y382905D02*
X534573D01*
X535220Y383552D01*
G01X528145Y408705D02*
X529173Y409733D01*
Y411905D01*
G01X528329Y847081D02*
Y844671D01*
G01X522779Y843877D02*
Y841467D01*
G01X528329Y853490D02*
Y851380D01*
G01X524628Y853490D02*
Y851381D01*
X524629Y851380D01*
G01X520928Y853490D02*
Y851381D01*
X520929Y851380D01*
G01X532028Y853490D02*
Y851381D01*
X532029Y851380D01*
G01X528329Y866307D02*
Y864197D01*
G01X524628Y866307D02*
Y864198D01*
X524629Y864197D01*
G01X520928Y866307D02*
Y864198D01*
X520929Y864197D01*
G01X526479Y863103D02*
Y860993D01*
G01X519079Y863103D02*
Y860994D01*
X519078Y860993D01*
G01X528329Y879124D02*
Y877014D01*
G01X520928Y879124D02*
Y877015D01*
X520929Y877014D01*
G01X524628Y879124D02*
Y877015D01*
X524629Y877014D01*
G01X532028Y879124D02*
Y877015D01*
X532029Y877014D01*
G01X532028Y885533D02*
Y883423D01*
G01X526479Y875920D02*
Y873810D01*
G01X519079Y875920D02*
Y873811D01*
X519078Y873810D01*
G01X528329Y889832D02*
Y891942D01*
G01X524628D02*
Y889833D01*
X524629Y889832D01*
G01X520928Y891942D02*
Y889833D01*
X520929Y889832D01*
G01X532028Y891942D02*
Y889833D01*
X532029Y889832D01*
G01X526479Y888737D02*
Y886627D01*
G01X519079Y888737D02*
Y886628D01*
X519078Y886627D01*
G01X528329Y936801D02*
Y934691D01*
G01X524628Y936801D02*
Y934691D01*
G01X532028Y936801D02*
Y934692D01*
X532029Y934691D01*
G01X523212Y1007187D02*
Y1009296D01*
X523211Y1009297D01*
G01X532461Y1023208D02*
X532460Y1025317D01*
X532461Y1025318D01*
G01X523212Y1045639D02*
Y1047748D01*
X523211Y1047749D01*
G01X517661Y1106520D02*
Y1108628D01*
X517662Y1108629D01*
Y1108630D01*
G01X526912Y1103316D02*
X526911Y1105426D01*
G01X521361Y1100111D02*
Y1102221D01*
G01X519512Y1096907D02*
Y1099017D01*
G01X532461Y1106520D02*
Y1108630D01*
G01X530612Y1109724D02*
Y1111834D01*
G01X523212Y1109724D02*
X523211Y1111834D01*
G01X526912Y1096907D02*
X526911Y1099017D01*
G01X532461Y1100111D02*
Y1102220D01*
X532460Y1102221D01*
G01X521361Y1106520D02*
Y1108628D01*
X521362Y1108629D01*
Y1108630D01*
G01X525061Y1106520D02*
Y1108628D01*
X525062Y1108629D01*
Y1108630D01*
G01X523212Y1103316D02*
X523211Y1103317D01*
Y1105426D01*
G01X528761Y1106520D02*
Y1108628D01*
X528762Y1108629D01*
Y1108630D01*
G01X519512Y1109724D02*
Y1111833D01*
X519511Y1111834D01*
G01X526912Y1109724D02*
Y1111833D01*
X526911Y1111834D01*
G01X523212Y1096907D02*
Y1099017D01*
G01X525061Y1100111D02*
Y1102220D01*
X525062Y1102221D01*
G01X530612Y1103316D02*
Y1105425D01*
X530611Y1105426D01*
G01X528761Y1100111D02*
Y1102220D01*
X528762Y1102221D01*
G01X517661Y1112929D02*
X517662Y1112930D01*
Y1115039D01*
G01X530612Y1116133D02*
Y1118242D01*
X530611Y1118243D01*
G01X523212Y1116133D02*
Y1118242D01*
X523211Y1118243D01*
G01X521361Y1112929D02*
Y1115039D01*
G01X519512Y1116133D02*
Y1118242D01*
X519511Y1118243D01*
G01X532461Y1112929D02*
Y1115039D01*
G01X525061Y1112929D02*
X525062Y1112930D01*
Y1115039D01*
G01X528761Y1112929D02*
X528762Y1112930D01*
Y1115039D01*
G01X525061Y1119337D02*
X525062Y1121447D01*
G01X517661Y1119337D02*
X517662Y1121447D01*
G01X526912Y1116133D02*
Y1118242D01*
X526911Y1118243D01*
G01X530612Y1135359D02*
Y1137469D01*
G01Y1128950D02*
Y1131060D01*
G01X526912Y1128950D02*
Y1131060D01*
G01X523212Y1128950D02*
Y1131059D01*
X523211Y1131060D01*
G01X519512Y1128950D02*
Y1131059D01*
X519511Y1131060D01*
G01X528761Y1132154D02*
Y1134264D01*
G01X525061Y1132154D02*
Y1134263D01*
X525062Y1134264D01*
G01X517661Y1132154D02*
Y1134263D01*
X517662Y1134264D01*
G01X528447Y1350891D02*
Y1353316D01*
G01X530053Y1360134D02*
X528796Y1361391D01*
X528447D01*
G01X531563Y1361597D02*
X533072Y1360088D01*
Y1359024D01*
G01X534686Y1361484D02*
Y1361861D01*
X531586Y1364961D01*
Y1366550D01*
X531610Y1366574D01*
G01X534737Y1367871D02*
X533428Y1366562D01*
X531622D01*
X531610Y1366574D01*
G01X537579Y850286D02*
Y848177D01*
X537580Y848176D01*
G01X535729Y847081D02*
Y844671D01*
G01X544979Y863103D02*
Y860993D01*
G01Y869511D02*
Y867401D01*
G01X533879Y875920D02*
Y873810D01*
G01X546828Y872716D02*
X546829Y870606D01*
G01X535729Y885533D02*
Y883423D01*
G01X546828Y885533D02*
Y883424D01*
X546829Y883423D01*
G01X533879Y893036D02*
Y895146D01*
G01Y899445D02*
Y901555D01*
G01X541279Y895146D02*
X537579Y893036D01*
G01X541279Y888737D02*
Y886627D01*
G01X544979Y888737D02*
Y886627D01*
G01X537579Y888737D02*
Y886627D01*
G01X535729Y889832D02*
Y891942D01*
G01X546828D02*
X550529Y889832D01*
G01X541279Y901555D02*
X537579Y899445D01*
G01X533879Y888737D02*
Y886627D01*
G01Y912262D02*
Y914372D01*
G01X546828Y911167D02*
X548679Y912262D01*
G01X541279Y914372D02*
X537579Y912262D01*
G01X541279Y907963D02*
X539429Y909057D01*
G01X537579Y907963D02*
Y905853D01*
G01X535729Y911167D02*
Y909057D01*
G01X544979Y907963D02*
X543129Y909057D01*
G01X535729Y904759D02*
Y902649D01*
G01X546828Y904759D02*
X548679Y905853D01*
G01X533879Y933598D02*
X533878Y933597D01*
Y931488D01*
G01X544979Y927189D02*
X543129Y928283D01*
G01X541279Y927189D02*
X539429Y928283D01*
G01X541279Y920780D02*
X537579Y918670D01*
G01X535729Y930393D02*
Y928283D01*
G01X546828Y923985D02*
X548678Y925079D01*
G01X541279Y933598D02*
X537578Y931488D01*
G01X546828Y930393D02*
X548678Y931488D01*
G01X533879Y937896D02*
Y940006D01*
G01X541279D02*
X537579Y937896D01*
G01Y946414D02*
Y944305D01*
X537578Y944304D01*
G01X535729Y943210D02*
Y941100D01*
G01X546828Y943210D02*
X547584D01*
X548678Y944304D01*
G01X541279Y946414D02*
X539429Y947509D01*
G01X544979Y946414D02*
X541279D01*
G01X535729Y949619D02*
Y947509D01*
G01X546828Y949619D02*
X549278D01*
G01X533879Y957122D02*
Y959232D01*
G01Y950713D02*
Y952823D01*
G01X546828Y962436D02*
X549719D01*
G01X541279Y959232D02*
X537579Y957122D01*
G01X541279Y952823D02*
X537579Y950713D01*
G01X535729Y962436D02*
Y960326D01*
G01X537579Y965640D02*
X535729Y966735D01*
G01X541279Y965640D02*
X537579Y963530D01*
G01X533879Y978457D02*
Y976347D01*
G01X535729Y981662D02*
X533901Y980606D01*
G01X533879Y969939D02*
X535729Y968845D01*
G01X541279Y978457D02*
X539463Y979506D01*
X539459Y979522D01*
X539429Y979552D01*
G01X541279Y972049D02*
Y969939D01*
G01X533879Y972049D02*
X535729Y973143D01*
G01X537579Y984866D02*
Y982756D01*
G01X541279Y984866D02*
X543729D01*
G01X541711Y1007187D02*
X539862Y1006092D01*
G01X539861Y1003983D02*
X536161Y1006093D01*
G01X545412Y1007187D02*
X543563Y1006092D01*
G01X541711Y1013595D02*
Y1015704D01*
X541712Y1015705D01*
G01X545412Y1013595D02*
Y1015705D01*
G01X538012Y1013595D02*
Y1015705D01*
G01X541711Y1026413D02*
X540378Y1026103D01*
G01X541711Y1020004D02*
X539913Y1018942D01*
X539881Y1018910D01*
X539861D01*
G01X536161Y1016800D02*
Y1018910D01*
G01X547261Y1016800D02*
X548998Y1016010D01*
X549112Y1015705D01*
G01X536161Y1031727D02*
Y1029617D01*
G01X547261D02*
X550961Y1031727D01*
G01X534311Y1039230D02*
Y1041340D01*
G01Y1045639D02*
Y1047749D01*
G01X545412Y1032821D02*
Y1034931D01*
G01X539862Y1044544D02*
X541711Y1045639D01*
G01Y1039230D02*
X539974Y1038226D01*
X539884Y1038136D01*
X539861D01*
G01X541711Y1032821D02*
Y1034931D01*
G01X538012Y1032821D02*
X538011Y1034931D01*
G01X536161Y1038136D02*
Y1036026D01*
G01X547261D02*
X549112Y1034931D01*
G01X534311Y1060565D02*
Y1058455D01*
G01X541711Y1052047D02*
Y1054157D01*
G01X538012Y1052047D02*
Y1054156D01*
X538011Y1054157D01*
G01X536161Y1055251D02*
Y1057361D01*
G01X545412Y1052047D02*
X545411Y1054157D01*
G01X541711Y1058455D02*
X538011Y1060565D01*
G01X536161Y1048842D02*
Y1050952D01*
G01X543561Y1061660D02*
X546535D01*
X547445Y1062037D01*
X549422Y1064014D01*
Y1064850D01*
G01X534311Y1064864D02*
Y1066974D01*
G01Y1077681D02*
Y1079791D01*
G01X536161Y1068068D02*
X538011Y1066974D01*
G01X543561Y1074477D02*
X541711Y1073383D01*
G01X543561Y1068068D02*
X545411Y1066974D01*
G01X541711Y1077681D02*
X539974Y1076677D01*
X539884Y1076587D01*
X539861D01*
G01X538012Y1071273D02*
X536220Y1070213D01*
X536207Y1070214D01*
X536162Y1070178D01*
G01X536161Y1074477D02*
X538011Y1073383D01*
G01X545412Y1071273D02*
X547262Y1070178D01*
G01X534311Y1084090D02*
Y1086200D01*
G01X539861Y1080885D02*
X536162Y1082996D01*
G01X538012Y1090498D02*
Y1092607D01*
X538011Y1092608D01*
G01X536161Y1087294D02*
Y1089404D01*
G01X543561Y1093703D02*
X545411Y1092608D01*
G01X545412Y1084090D02*
X547262Y1082996D01*
G01X541711Y1096907D02*
X543561Y1095813D01*
G01X536161Y1093703D02*
Y1095813D01*
G01X545412Y1096907D02*
X547261Y1095813D01*
G01X534311Y1109724D02*
Y1111834D01*
G01Y1103316D02*
Y1105426D01*
G01X541711Y1103316D02*
Y1105426D01*
G01X539861Y1106520D02*
Y1108630D01*
G01X541711Y1109724D02*
Y1111834D01*
G01X545412Y1109724D02*
X545411Y1111834D01*
G01X538012Y1103316D02*
Y1105425D01*
X538011Y1105426D01*
G01X536161Y1106520D02*
Y1108630D01*
G01X538012Y1109724D02*
Y1111833D01*
X538011Y1111834D01*
G01X543561Y1112929D02*
Y1115036D01*
X543562Y1115037D01*
Y1115039D01*
G01X539861Y1112929D02*
Y1115036D01*
X539862Y1115037D01*
Y1115039D01*
G01X536161Y1112929D02*
Y1115039D01*
G01X534311Y1116133D02*
Y1118243D01*
G01X541711Y1116133D02*
Y1118243D01*
G01X536161Y1132154D02*
Y1134263D01*
X536162Y1134264D01*
G01X538737Y1365553D02*
X538797D01*
X538798Y1365552D01*
X540001Y1362646D01*
Y1361484D01*
G01X534737Y1364815D02*
Y1364521D01*
X536458Y1362800D01*
Y1361484D01*
G01X596287Y65158D02*
Y77490D01*
X598190Y79393D01*
Y83462D01*
G01D02*
X597220Y84432D01*
Y88287D01*
G01X603720Y98362D02*
Y97362D01*
X597795Y91437D01*
X597220D01*
G01X606040Y153432D02*
X606754Y152718D01*
X609146D01*
G01X606190Y144002D02*
X607317Y142875D01*
X609146D01*
G01X606668Y208931D02*
X607369D01*
X611159Y212721D01*
X612531D01*
G01D02*
X615280D01*
X619500Y208501D01*
X621536D01*
G01Y211651D02*
X618492D01*
X613886Y216257D01*
X608995D01*
G01D02*
X607595D01*
X604109Y212771D01*
Y211490D01*
G01X628142Y152718D02*
X630306D01*
X631290Y153702D01*
G01D02*
X630305Y154687D01*
X628142D01*
G01X625461Y208076D02*
X621961D01*
X621536Y208501D01*
G01X625461Y212076D02*
X624214D01*
X623540Y211402D01*
X621785D01*
X621536Y211651D01*
G01X663187Y1395170D02*
X661775D01*
X660645Y1396300D01*
X659311D01*
G01Y1392770D02*
X663187D01*
G01X659311Y1396300D02*
Y1392770D01*
G01X682774Y89362D02*
X680906D01*
X675587Y94681D01*
Y107754D01*
G01D02*
X676643Y108810D01*
G01X683453Y128093D02*
X681067D01*
X678520Y130640D01*
G01X669477Y1406694D02*
X671198Y1404973D01*
Y1403363D01*
G01X666425Y1408409D02*
Y1406689D01*
X669426Y1403688D01*
Y1403363D01*
G01X669477Y1409415D02*
X667425D01*
X666425Y1408415D01*
Y1408409D01*
G01X693193Y89362D02*
X692563Y88732D01*
X683404D01*
X682774Y89362D01*
G01X691153Y131578D02*
Y127368D01*
X695646Y122875D01*
Y119440D01*
G01X687453Y128093D02*
X688187D01*
X693677Y122603D01*
Y119440D01*
G01X683453Y128093D02*
X687453D01*
G01X709998Y103308D02*
X712433D01*
G01X697276Y166535D02*
X701926D01*
G01X697276Y178346D02*
X701926D01*
G01X697276Y184252D02*
X701926D01*
G01X697276Y172441D02*
X701926D01*
G01X697276Y190157D02*
X701926D01*
G01X697276Y196063D02*
X701926D01*
G01X697276Y201968D02*
X701926D01*
G01X697276Y207874D02*
X701926D01*
G01X697276Y213779D02*
X701926D01*
G01X697276Y219685D02*
X701926D01*
G01X707620Y1409660D02*
X707047D01*
X705796Y1408409D01*
X704568D01*
G01X704537Y1583683D02*
X702112D01*
G01X704537Y1587683D02*
X702112D01*
G01X704537Y1591683D02*
X702112D01*
G01X704537Y1595683D02*
Y1591683D01*
G01X707687Y1587683D02*
X710527Y1584843D01*
X712582D01*
G01X719199Y1584635D02*
X716612D01*
G01X719199Y1586407D02*
X718480D01*
X718094Y1586793D01*
X715722D01*
X713772Y1584843D01*
X712582D01*
G01X740840Y1655590D02*
X738882Y1653632D01*
X735588D01*
X734880Y1654340D01*
Y1657870D01*
X737560Y1660550D01*
Y1664390D01*
X735990Y1665960D01*
Y1672820D01*
X737500Y1674330D01*
X739538D01*
G01X745080Y1674362D02*
X739570D01*
X739538Y1674330D01*
G01X758360Y276122D02*
X759192Y275290D01*
X761223D01*
G01X765577Y1581893D02*
X763152D01*
G01X765577Y1577893D02*
X763152D01*
G01X765564Y1573793D02*
X763152D01*
G01X779270Y1584539D02*
X773373D01*
X772952Y1584118D01*
G01X769452Y1584393D02*
X769727Y1584118D01*
X772952D01*
G01X779270Y1586507D02*
X773713D01*
X772952Y1587268D01*
G01X765577Y1590893D02*
X763152D01*
G01X807077Y1573793D02*
X804652D01*
G01Y1585993D02*
X806877D01*
X807077Y1585793D01*
G01X820900Y147112D02*
Y145312D01*
X822530Y143682D01*
Y142410D01*
G01X821270Y1586507D02*
X817537D01*
X815876Y1588168D01*
X815252D01*
G01X810227Y1593793D02*
X812652D01*
G01X821270Y1584539D02*
X816807D01*
X816328Y1585018D01*
X815252D01*
G01X812698Y1587047D02*
X814727Y1585018D01*
X815252D01*
G01X810227Y1605793D02*
X812652D01*
G01X830480Y527817D02*
X830943Y528280D01*
X833039D01*
X833502Y527817D01*
X834922D01*
G01X837875Y529786D02*
X840990D01*
G01X855858Y212425D02*
X854871Y211438D01*
X852991D01*
G01Y217344D02*
Y224151D01*
X853842Y225002D01*
G01X852991Y215375D02*
X855933D01*
G01X865318Y223763D02*
X864129Y224952D01*
X859327D01*
X858783Y224408D01*
G01X853842Y225002D02*
X858189D01*
X858783Y224408D01*
G01X850432Y219903D02*
Y224551D01*
X849600Y225383D01*
Y228152D01*
G01X865318Y227763D02*
X864007Y226452D01*
X859889D01*
X858783Y227558D01*
G01X849600Y228152D02*
X850194Y227558D01*
X858783D01*
G01X849077Y1573793D02*
X846652D01*
G01X863270Y1586507D02*
X859537D01*
X857876Y1588168D01*
X857252D01*
G01X852227Y1593793D02*
X854652D01*
G01X846652Y1585993D02*
X848877D01*
X849077Y1585793D01*
G01X863270Y1584539D02*
X858807D01*
X858328Y1585018D01*
X857252D01*
G01X854777Y1586968D02*
X856727Y1585018D01*
X857252D01*
G01X852227Y1605793D02*
X854652D01*
G01X891077Y1573793D02*
X888652D01*
G01Y1585993D02*
X890877D01*
X891077Y1585793D01*
G01X899252Y1588168D02*
X899876D01*
X901537Y1586507D01*
X905270D01*
G01X894227Y1593793D02*
X896652D01*
G01X899252Y1585018D02*
X900328D01*
X900807Y1584539D01*
X905270D01*
G01X896672Y1587073D02*
X898727Y1585018D01*
X899252D01*
G01X894227Y1605793D02*
X896652D01*
G01X923836Y994116D02*
Y996248D01*
X924440Y996852D01*
G01X919407Y985750D02*
X919168Y985989D01*
X914838D01*
G01X934171Y985750D02*
X936998D01*
G01X931710Y994116D02*
Y996212D01*
X932310Y996812D01*
G01X936227Y1593393D02*
X938652D01*
G01X936227Y1585393D02*
X938652D01*
G01X963586Y1600926D02*
Y1602484D01*
X965086Y1603984D01*
G01X963586Y1607042D02*
Y1605484D01*
X962086Y1603984D01*
G01X973955Y204663D02*
Y220653D01*
X977955Y224653D01*
X988500D01*
G01X994337Y221233D02*
X990917Y224653D01*
X988500D01*
G01X1017105Y206723D02*
X1012895D01*
X1008402Y202230D01*
X1004967D01*
G01X1010005Y208424D02*
X1009880Y208299D01*
Y207159D01*
X1006920Y204199D01*
X1004967D01*
G01X1013620Y226423D02*
X1006996D01*
X1005120Y228299D01*
Y230399D01*
G01X994322Y401824D02*
Y404090D01*
G01X995198Y1600942D02*
Y1602500D01*
X996698Y1604000D01*
G01X995198Y1607058D02*
Y1605500D01*
X993698Y1604000D01*
G01X1013620Y210423D02*
Y214423D01*
G01D02*
Y218423D01*
G01Y210423D02*
X1012004D01*
X1010005Y208424D01*
G01X1016770Y229573D02*
X1011846D01*
X1011720Y229699D01*
G01X1019355Y222423D02*
X1016770D01*
G01X1019355Y218423D02*
X1016770D01*
G01X1013620D02*
Y222423D01*
G01X1034380Y291448D02*
Y292624D01*
X1035230Y293474D01*
X1035740Y293685D01*
X1038190Y296135D01*
X1038606D01*
G01X1024258Y301313D02*
Y297264D01*
G01Y293331D02*
Y297264D01*
G01X1031025Y296135D02*
X1034835D01*
G01X1030333Y292180D02*
Y295443D01*
X1031025Y296135D01*
G01X1029028Y298884D02*
X1027408Y297264D01*
G01X1029028Y298884D02*
X1029429Y299285D01*
X1031025D01*
G01X1028577Y291018D02*
X1027129Y294514D01*
Y296985D01*
X1027408Y297264D01*
G01X1024258Y305313D02*
Y301313D01*
G01X1031025Y299609D02*
Y299285D01*
G01X1031270Y303487D02*
X1031163D01*
X1031025Y303349D01*
Y299609D01*
G01X1036278Y303993D02*
X1031776D01*
X1031270Y303487D01*
G01X1027408Y301313D02*
Y305313D01*
G01D02*
X1029025D01*
X1030349Y306637D01*
X1031270D01*
G01X1036278Y307393D02*
X1032026D01*
X1031270Y306637D01*
G01X1026798Y1600942D02*
Y1602500D01*
X1028298Y1604000D01*
G01X1026798Y1607058D02*
Y1605500D01*
X1025298Y1604000D01*
G01X1058398Y1600942D02*
Y1602500D01*
X1059898Y1604000D01*
G01X1058398Y1607058D02*
Y1605500D01*
X1056898Y1604000D01*
G01X1093936Y1593314D02*
Y1602436D01*
X1095440Y1603940D01*
X1095436Y1603944D01*
G01X1093936Y1614574D02*
Y1605444D01*
X1092436Y1603944D01*
G01X1122879Y1431474D02*
X1121281D01*
X1120151Y1432604D01*
X1119003D01*
G01Y1429074D02*
X1122879D01*
G01X1119003Y1432604D02*
Y1429074D01*
G01X1119440Y1566630D02*
X1120140Y1567330D01*
Y1592479D01*
X1107630Y1604989D01*
Y1609030D01*
X1108260Y1609660D01*
X1110050D01*
X1111970Y1607740D01*
G01X1111440Y1566630D02*
Y1571430D01*
X1115440Y1575430D01*
G01D02*
X1118540Y1578530D01*
Y1591816D01*
X1106030Y1604326D01*
Y1609693D01*
X1107597Y1611260D01*
X1110090D01*
X1111970Y1613140D01*
G01X1119005Y1608420D02*
X1117735Y1609690D01*
X1113920D01*
X1111970Y1607740D01*
G01X1119035Y1612320D02*
X1117905Y1611190D01*
X1113920D01*
X1111970Y1613140D01*
G01X1129169Y1442998D02*
X1130890Y1441277D01*
Y1439667D01*
G01X1129169Y1445719D02*
X1128779D01*
X1127773Y1444713D01*
X1126117D01*
G01D02*
Y1442967D01*
X1129118Y1439966D01*
Y1439667D01*
G01X1132187Y1590738D02*
X1132600Y1591151D01*
Y1592363D01*
X1132160Y1592803D01*
X1130752D01*
X1129022Y1591073D01*
Y1576630D01*
X1152247Y1553405D01*
Y1551519D01*
X1153465Y1550301D01*
G01X1135187Y1590738D02*
X1134100Y1591825D01*
Y1592985D01*
X1132782Y1594303D01*
X1130130D01*
X1127522Y1591695D01*
Y1576008D01*
X1150747Y1552783D01*
Y1551520D01*
X1149528Y1550301D01*
G01X1132187Y1582738D02*
X1132937Y1581988D01*
Y1576930D01*
X1148835Y1561032D01*
X1161884D01*
X1166494Y1556422D01*
Y1551519D01*
X1165276Y1550301D01*
G01X1135187Y1582738D02*
X1134437Y1581988D01*
Y1577552D01*
X1149457Y1562532D01*
X1162506D01*
X1167994Y1557044D01*
Y1551520D01*
X1169213Y1550301D01*
G01X1133220Y1612190D02*
X1135210Y1610200D01*
X1136580D01*
X1138530Y1612150D01*
G01X1126940Y1612030D02*
X1128930Y1610040D01*
X1131070D01*
X1133220Y1612190D01*
G01X1126940Y1612030D02*
X1126120Y1611210D01*
X1123195D01*
X1122185Y1612220D01*
Y1612320D01*
G01X1133220Y1606390D02*
X1135530Y1608700D01*
X1136580D01*
X1138530Y1606750D01*
G01X1126940Y1606230D02*
X1129250Y1608540D01*
X1131070D01*
X1133220Y1606390D01*
G01X1126940Y1606230D02*
Y1608460D01*
X1125690Y1609710D01*
X1123445D01*
X1122155Y1608420D01*
G01X1151497Y1528937D02*
Y1524187D01*
G01X1149528Y1550301D02*
Y1545551D01*
G01X1138530Y1612150D02*
X1140750Y1609930D01*
X1142379D01*
X1143079Y1610630D01*
X1145335D01*
G01X1138530Y1606750D02*
X1140210Y1608430D01*
X1142691D01*
X1143051Y1608070D01*
X1145335D01*
G01X1156378Y133866D02*
X1156620Y133624D01*
Y124692D01*
X1174545Y106767D01*
G01X1167312Y1445964D02*
X1166739D01*
X1166026Y1445251D01*
X1164798D01*
X1164260Y1444713D01*
G01X1153465Y1550301D02*
Y1545551D01*
G01X1165276Y1550301D02*
Y1545551D01*
G01X1157402D02*
Y1550301D01*
G01X1161339Y1545551D02*
Y1550301D01*
G01X1185375Y111600D02*
Y113825D01*
X1183700Y115500D01*
X1176800D01*
X1174545Y113245D01*
Y106767D01*
G01X1180676Y106858D02*
Y110051D01*
X1182225Y111600D01*
G01X1190973Y110227D02*
X1188728D01*
X1187601Y109100D01*
X1182900D01*
X1182225Y109775D01*
Y111600D01*
G01X1169213Y1550301D02*
Y1545551D01*
G01X1182408Y1626204D02*
X1183590Y1627386D01*
X1185030D01*
G01X1269012Y1371693D02*
X1270183Y1370522D01*
X1272350D01*
X1274410Y1368462D01*
Y1365622D01*
X1269429Y1360641D01*
X1198075D01*
X1197070Y1359636D01*
G01X1269012Y1368293D02*
X1269741Y1369022D01*
X1271728D01*
X1272910Y1367840D01*
Y1366244D01*
X1268807Y1362141D01*
X1198075D01*
X1197070Y1363146D01*
G01X1185030Y1624660D02*
Y1627386D01*
G01X1239018Y197462D02*
X1236593D01*
G01X1279834Y1361664D02*
X1279871Y1361627D01*
X1280161D01*
X1281418Y1360370D01*
G01X1290927Y148170D02*
X1288258Y145501D01*
G01X1293802Y201849D02*
X1292303Y200596D01*
G01D02*
X1293802Y198149D01*
G01X1292303Y200596D02*
X1289035D01*
G01X1284437Y230280D02*
X1284990Y228946D01*
X1285767Y228169D01*
G01X1293893Y237962D02*
Y237508D01*
X1294866Y236535D01*
G01X1290102Y1365789D02*
X1290162D01*
X1290163Y1365788D01*
X1291366Y1362882D01*
Y1361720D01*
G01X1286102Y1365051D02*
Y1364757D01*
X1287823Y1363036D01*
Y1361720D01*
G01X1282928Y1361833D02*
X1284437Y1360324D01*
Y1359260D01*
G01X1286102Y1368107D02*
X1284693Y1366698D01*
X1283280D01*
G01D02*
Y1364849D01*
X1286051Y1362078D01*
Y1361720D01*
G01X1302744Y151438D02*
Y154706D01*
G01X1300207Y177799D02*
X1299137Y175949D01*
X1299134D01*
G01X1300207Y185199D02*
X1299137Y183349D01*
X1299134D01*
G01X1300207Y192599D02*
X1299137Y190749D01*
X1299134D01*
G01X1308652Y228426D02*
Y231694D01*
G01X1312070Y879124D02*
Y877014D01*
G01X1310221Y882329D02*
Y880219D01*
G01X1312070Y936801D02*
Y934692D01*
G01X1310221Y940006D02*
X1308371Y941100D01*
G01X1312070Y956027D02*
Y953917D01*
G01X1310221Y952823D02*
X1308370Y953917D01*
G01X1312503Y1003983D02*
X1314353Y1002888D01*
G01X1310654Y1007187D02*
X1308803Y1006093D01*
G01X1314353Y1013595D02*
Y1015705D01*
G01X1312503Y1023208D02*
X1314353Y1022114D01*
G01X1310654Y1026413D02*
X1308803Y1025318D01*
G01X1310654Y1020004D02*
X1308803Y1018910D01*
G01X1312503Y1042434D02*
X1314353Y1041340D01*
G01X1310654Y1045639D02*
X1308803Y1044544D01*
G01X1310654Y1039230D02*
X1310653Y1041340D01*
G01X1316203Y1061660D02*
X1314353Y1060565D01*
G01Y1124651D02*
Y1122541D01*
G01X1312503Y1127856D02*
Y1125746D01*
G01X1314353Y1118243D02*
Y1116133D01*
G01Y1131060D02*
Y1128950D01*
G01X1326377Y200199D02*
X1327952Y201774D01*
G01X1332262Y207399D02*
X1327979D01*
G01X1322438Y226792D02*
Y230060D01*
G01X1330316Y226792D02*
Y230060D01*
G01X1326377Y226792D02*
X1330316D01*
G01D02*
X1332285Y226210D01*
G01X1330570Y853490D02*
X1330571Y851380D01*
G01X1330570Y866307D02*
X1330571Y866306D01*
Y864197D01*
G01X1326870Y866307D02*
X1326871Y866306D01*
Y864197D01*
G01X1323171Y866307D02*
Y864197D01*
G01X1315771Y866307D02*
X1317621Y867401D01*
G01X1325021Y863103D02*
Y860993D01*
G01X1330570Y879124D02*
Y877015D01*
X1330571Y877014D01*
G01X1328721Y882329D02*
Y880220D01*
X1328722Y880219D01*
G01X1323171Y872716D02*
Y870606D01*
G01X1326870Y879124D02*
Y877015D01*
X1326871Y877014D01*
G01X1321321Y875920D02*
Y873810D01*
G01Y882329D02*
Y880219D01*
G01X1315771Y885533D02*
Y883423D01*
G01X1326870Y885533D02*
Y883424D01*
X1326871Y883423D01*
G01X1323171Y885533D02*
Y883423D01*
G01X1325021Y875920D02*
Y873811D01*
X1325020Y873810D01*
G01X1323171Y891942D02*
Y889832D01*
G01X1321321Y895146D02*
Y893036D01*
G01X1319470Y898350D02*
Y896240D01*
G01X1321321Y901555D02*
Y899445D01*
G01X1323171Y909057D02*
Y911167D01*
G01X1321321Y914372D02*
Y912262D01*
G01X1319470Y917576D02*
Y915467D01*
X1319471Y915466D01*
G01X1323171Y930393D02*
Y928283D01*
G01Y923985D02*
Y921875D01*
G01X1321321Y920780D02*
Y918670D01*
G01X1328721Y933598D02*
X1328720Y933597D01*
Y931488D01*
G01X1321321Y933598D02*
Y931488D01*
G01X1315771Y949619D02*
X1317621Y950713D01*
G01X1323171Y941100D02*
Y943210D01*
G01Y947509D02*
Y949619D01*
G01X1315771Y943210D02*
X1317620Y944304D01*
G01X1328721Y940006D02*
X1328720Y940005D01*
Y937896D01*
G01X1315771Y934692D02*
Y936801D01*
G01X1321321Y940006D02*
Y937896D01*
G01X1319470Y934692D02*
Y936801D01*
G01X1321321Y952823D02*
Y950713D01*
G01X1319470Y956027D02*
Y953917D01*
G01X1317621Y965640D02*
X1319471Y966735D01*
G01X1316203Y1010391D02*
X1318053Y1009297D01*
G01X1316203Y1003983D02*
X1318053Y1002888D01*
G01X1318054Y1013595D02*
X1321753Y1015705D01*
G01X1316203Y1023208D02*
X1318053Y1022114D01*
G01X1316203Y1016800D02*
X1318053Y1015705D01*
G01X1321753Y1020004D02*
X1319903Y1018910D01*
G01Y1023208D02*
X1321753Y1022114D01*
G01X1316203Y1029617D02*
X1319903Y1031727D01*
G01X1329153Y1045639D02*
Y1047749D01*
G01X1316203Y1042434D02*
X1318053Y1041340D01*
G01X1316203Y1036026D02*
X1319903Y1038136D01*
G01X1323603Y1036026D02*
Y1038136D01*
G01X1321753Y1041340D02*
Y1039230D01*
G01X1327303Y1093703D02*
X1325452Y1092609D01*
G01X1325454Y1090498D02*
X1323603Y1089404D01*
G01Y1087294D02*
X1321752Y1086200D01*
G01X1321753Y1084090D02*
X1319902Y1082996D01*
Y1082995D01*
G01X1318054Y1090498D02*
X1319849Y1091513D01*
G01X1318054Y1096907D02*
X1316203Y1095813D01*
G01X1323603Y1106520D02*
Y1108630D01*
G01X1325454Y1103316D02*
Y1105425D01*
X1325453Y1105426D01*
G01X1325454Y1116133D02*
Y1118243D01*
G01X1321753Y1116133D02*
Y1118243D01*
G01X1329153Y1116133D02*
Y1118243D01*
G01X1327303Y1125746D02*
Y1127855D01*
X1327304Y1127856D01*
G01X1329153Y1135359D02*
Y1137468D01*
X1329152Y1137469D01*
G01X1329153Y1128950D02*
Y1131060D01*
G01X1321753Y1135359D02*
Y1137468D01*
X1321752Y1137469D01*
G01X1321753Y1131060D02*
Y1128950D01*
G01X1325454D02*
Y1131059D01*
X1325453Y1131060D01*
G01X1319903Y1132154D02*
X1319904Y1132155D01*
Y1134263D01*
X1319903Y1134264D01*
G01X1323603Y1132154D02*
X1323604Y1132155D01*
Y1134263D01*
X1323603Y1134264D01*
G01X1322110Y1342755D02*
X1322170D01*
X1322171Y1342754D01*
X1323374Y1339848D01*
Y1338686D01*
G01X1318110Y1342017D02*
Y1341723D01*
X1319831Y1340002D01*
Y1338686D01*
G01X1314936Y1338799D02*
X1316445Y1337290D01*
Y1336226D01*
G01X1318059Y1338686D02*
Y1339094D01*
X1315058Y1342095D01*
Y1343732D01*
G01X1318110Y1345073D02*
X1316769Y1343732D01*
X1315058D01*
G01X1342936Y159301D02*
X1344005Y161149D01*
G01X1346137Y168549D02*
X1347207Y170399D01*
X1347210D01*
G01X1346137Y164849D02*
X1347207Y166699D01*
X1347210D01*
G01X1340799D02*
X1339727Y164849D01*
G01X1340799Y170399D02*
X1339727Y168549D01*
G01X1342903Y170399D02*
X1343970Y172240D01*
X1344005Y172249D01*
G01X1346137Y190749D02*
X1347207Y192599D01*
X1347210D01*
G01X1337901Y196035D02*
X1335827Y193961D01*
Y193899D01*
G01X1332285Y226210D02*
X1334255Y226792D01*
G01Y230060D02*
Y226792D01*
G01X1338194D02*
X1336224Y226210D01*
X1334255Y226792D01*
G01X1340163Y231694D02*
Y228426D01*
G01D02*
X1338194Y226792D01*
G01X1342133D02*
X1340163Y228426D01*
G01X1344005Y224049D02*
X1342937Y222199D01*
G01X1343521Y843877D02*
Y841467D01*
G01X1336121Y843877D02*
Y841467D01*
G01X1345370Y853490D02*
Y851381D01*
X1345371Y851380D01*
G01X1341670Y853490D02*
Y851381D01*
X1341671Y851380D01*
G01X1337970Y853490D02*
Y851381D01*
X1337971Y851380D01*
G01X1334270Y853490D02*
Y851381D01*
X1334271Y851380D01*
G01X1339821Y850286D02*
Y848178D01*
X1339820Y848177D01*
Y848176D01*
G01X1332421Y850286D02*
Y848178D01*
X1332420Y848177D01*
Y848176D01*
G01X1347221Y850286D02*
Y848178D01*
X1347220Y848177D01*
Y848176D01*
G01X1345370Y866307D02*
X1345371Y866306D01*
Y864197D01*
G01X1341670Y866307D02*
X1341671Y866306D01*
Y864197D01*
G01X1337970Y866307D02*
X1337971Y866306D01*
Y864197D01*
G01X1334270Y866307D02*
X1334271Y866306D01*
Y864197D01*
G01X1339821Y863103D02*
Y860994D01*
X1339820Y860993D01*
G01X1332421Y863103D02*
Y860994D01*
X1332420Y860993D01*
G01X1347221Y863103D02*
Y860994D01*
X1347220Y860993D01*
G01X1345370Y879124D02*
Y877015D01*
X1345371Y877014D01*
G01X1341670Y879124D02*
Y877015D01*
X1341671Y877014D01*
G01X1337970Y879124D02*
Y877015D01*
X1337971Y877014D01*
G01X1334270Y879124D02*
Y877015D01*
X1334271Y877014D01*
G01X1339821Y875920D02*
Y873811D01*
X1339820Y873810D01*
G01X1332421Y875920D02*
Y873811D01*
X1332420Y873810D01*
G01X1347221Y875920D02*
Y873811D01*
X1347220Y873810D01*
G01X1345370Y891942D02*
Y889833D01*
X1345371Y889832D01*
G01X1341670Y891942D02*
Y889833D01*
X1341671Y889832D01*
G01X1337970Y891942D02*
Y889833D01*
X1337971Y889832D01*
G01X1334270Y891942D02*
Y889832D01*
G01X1347221Y888737D02*
Y886628D01*
X1347220Y886627D01*
G01X1332421Y907963D02*
Y905854D01*
X1332420Y905853D01*
G01X1345370Y917576D02*
X1345371Y917575D01*
Y915466D01*
G01X1341670Y917576D02*
X1341671Y917575D01*
Y915466D01*
G01X1341670Y923985D02*
Y921876D01*
X1341671Y921875D01*
G01X1334270Y923985D02*
X1334271Y923984D01*
Y921875D01*
G01X1345370Y936801D02*
X1345371D01*
Y934691D01*
G01X1341670Y936801D02*
X1341671D01*
Y934691D01*
G01X1337970Y936801D02*
Y934691D01*
G01X1336554Y1045639D02*
X1336553D01*
Y1047749D01*
G01X1342103Y1100111D02*
Y1102220D01*
X1342104Y1102221D01*
G01X1338403Y1100111D02*
Y1102220D01*
X1338404Y1102221D01*
G01X1340254Y1109724D02*
X1340255Y1109725D01*
X1340254Y1111834D01*
G01X1332854Y1109724D02*
X1332855Y1109725D01*
X1332854Y1111834D01*
G01X1345803Y1100111D02*
Y1102221D01*
G01X1343954Y1103316D02*
Y1105425D01*
X1343953Y1105426D01*
G01X1336554Y1103316D02*
X1336555Y1103317D01*
Y1105425D01*
X1336554Y1105426D01*
G01X1334703Y1100111D02*
Y1102220D01*
X1334704Y1102221D01*
G01X1331003Y1112929D02*
Y1115039D01*
G01X1343954Y1116133D02*
Y1118242D01*
X1343953Y1118243D01*
G01X1340254Y1116133D02*
Y1118242D01*
X1340253Y1118243D01*
G01X1338403Y1112929D02*
Y1115039D01*
G01X1336554Y1116133D02*
X1336553Y1116134D01*
Y1118243D01*
G01X1332854Y1116133D02*
X1332853Y1116134D01*
Y1118243D01*
G01X1338403Y1119337D02*
Y1121447D01*
G01X1331003Y1119337D02*
Y1121447D01*
G01X1345803Y1119337D02*
Y1121446D01*
X1345804Y1121447D01*
G01X1343954Y1128950D02*
Y1131059D01*
X1343953Y1131060D01*
G01X1340254Y1128950D02*
Y1131060D01*
G01X1336554Y1128950D02*
Y1131060D01*
G01X1332854Y1128950D02*
Y1131060D01*
G01X1331003Y1132154D02*
Y1134264D01*
G01X1345803Y1132154D02*
Y1134263D01*
X1345804Y1134264D01*
G01X1338403Y1132154D02*
Y1134263D01*
X1338404Y1134264D01*
G01X1350187Y1325260D02*
Y1325664D01*
X1347015Y1328836D01*
Y1330308D01*
G01X1361827Y148170D02*
X1364407D01*
G01X1362793Y145262D02*
X1361827Y146228D01*
Y148170D01*
G01X1349351Y159298D02*
X1350421Y161148D01*
X1350414Y161149D01*
G01X1355761Y162998D02*
X1356825Y161149D01*
G01Y164849D02*
X1356769Y164752D01*
X1355761Y162998D01*
G01X1356825Y161149D02*
X1355758Y159298D01*
G01X1352557Y164848D02*
X1353627Y166698D01*
X1353620Y166699D01*
G01X1356825Y172249D02*
X1355761Y170398D01*
G01X1356825Y179649D02*
X1355761Y177798D01*
G01X1352557Y179648D02*
X1353627Y181498D01*
X1353620Y181499D01*
G01X1349351Y196298D02*
X1350421Y198148D01*
X1350414Y198149D01*
G01X1352561Y194448D02*
X1353631Y196298D01*
X1353621D01*
X1353620Y196299D01*
G01X1352551Y190748D02*
X1353621Y192598D01*
X1353620Y192599D01*
G01X1349345Y188898D02*
X1350415Y190748D01*
X1350414Y190749D01*
G01X1356825Y194449D02*
X1355761Y192598D01*
G01X1360451Y208474D02*
X1359334Y209591D01*
Y211296D01*
X1360451Y212413D01*
G01X1353620Y207399D02*
X1352560Y205549D01*
G01X1356825Y209249D02*
X1355765Y207399D01*
G01X1358321Y843877D02*
Y841467D01*
G01X1350921Y843877D02*
Y841467D01*
G01X1360170Y853490D02*
Y851381D01*
X1360171Y851380D01*
G01X1356470Y853490D02*
Y851381D01*
X1356471Y851380D01*
G01X1352770Y853490D02*
Y851381D01*
X1352771Y851380D01*
G01X1349070Y853490D02*
X1349071Y853489D01*
Y851380D01*
G01X1362021Y850286D02*
Y848178D01*
X1362020Y848177D01*
Y848176D01*
G01X1354621Y850286D02*
Y848178D01*
X1354620Y848177D01*
Y848176D01*
G01X1360170Y866307D02*
X1360171Y866306D01*
Y864197D01*
G01X1356470Y866307D02*
X1356471Y866306D01*
Y864197D01*
G01X1352770Y866307D02*
X1352771Y866306D01*
Y864197D01*
G01X1349070Y866307D02*
X1349071Y866306D01*
Y864197D01*
G01X1362021Y863103D02*
Y860994D01*
X1362020Y860993D01*
G01X1354621Y863103D02*
Y860994D01*
X1354620Y860993D01*
G01X1360170Y879124D02*
Y877015D01*
X1360171Y877014D01*
G01X1356470Y879124D02*
Y877015D01*
X1356471Y877014D01*
G01X1352770Y879124D02*
Y877015D01*
X1352771Y877014D01*
G01X1349070Y879124D02*
Y877015D01*
X1349071Y877014D01*
G01X1362021Y875920D02*
Y873811D01*
X1362020Y873810D01*
G01X1354621Y875920D02*
Y873811D01*
X1354620Y873810D01*
G01X1360170Y891942D02*
Y889833D01*
X1360171Y889832D01*
G01X1356470Y891942D02*
Y889833D01*
X1356471Y889832D01*
G01X1352770Y891942D02*
Y889833D01*
X1352771Y889832D01*
G01X1349070Y891942D02*
Y889833D01*
X1349071Y889832D01*
G01X1362021Y888737D02*
Y886628D01*
X1362020Y886627D01*
G01X1354621Y888737D02*
Y886628D01*
X1354620Y886627D01*
G01X1360170Y923985D02*
X1360171Y923984D01*
Y921875D01*
G01X1347654Y1039230D02*
Y1041339D01*
X1347653Y1041340D01*
G01X1347654Y1045639D02*
X1347653D01*
Y1047749D01*
G01X1355054Y1039230D02*
X1355053Y1039231D01*
Y1041340D01*
G01X1362454Y1045639D02*
X1362453D01*
Y1047749D01*
G01X1355054Y1045639D02*
X1355053D01*
Y1047749D01*
G01X1360603Y1093703D02*
Y1095812D01*
X1360604Y1095813D01*
G01X1347654Y1103316D02*
Y1105426D01*
G01Y1096907D02*
Y1099017D01*
G01Y1109724D02*
Y1111834D01*
G01X1362454Y1096907D02*
Y1099017D01*
G01X1360603Y1100111D02*
Y1102220D01*
X1360604Y1102221D01*
G01X1356903Y1106520D02*
Y1108629D01*
X1356904Y1108630D01*
G01X1355054Y1096907D02*
Y1099016D01*
X1355053Y1099017D01*
G01X1353203Y1100111D02*
Y1102220D01*
X1353204Y1102221D01*
G01X1349503Y1106520D02*
Y1108630D01*
G01Y1100111D02*
Y1102221D01*
G01X1358754Y1096907D02*
Y1099016D01*
X1358753Y1099017D01*
G01X1347654Y1116133D02*
Y1118242D01*
X1347653Y1118243D01*
G01X1362454Y1116133D02*
Y1118242D01*
X1362453Y1118243D01*
G01X1358754Y1116133D02*
Y1118242D01*
X1358753Y1118243D01*
G01X1355054Y1116133D02*
Y1118242D01*
X1355053Y1118243D01*
G01X1351354Y1116133D02*
Y1118242D01*
X1351353Y1118243D01*
G01X1360603Y1119337D02*
Y1121446D01*
X1360604Y1121447D01*
G01X1353203Y1119337D02*
Y1121446D01*
X1353204Y1121447D01*
G01X1347654Y1128950D02*
Y1131059D01*
X1347653Y1131060D01*
G01X1362454Y1128950D02*
Y1131059D01*
X1362453Y1131060D01*
G01X1358754Y1128950D02*
Y1131059D01*
X1358753Y1131060D01*
G01X1355054Y1128950D02*
Y1131059D01*
X1355053Y1131060D01*
G01X1351354Y1128950D02*
Y1131059D01*
X1351353Y1131060D01*
G01X1360603Y1132154D02*
Y1134263D01*
X1360604Y1134264D01*
G01X1353203Y1132154D02*
Y1134263D01*
X1353204Y1134264D01*
G01X1354238Y1329329D02*
X1354298D01*
X1354299Y1329328D01*
X1355502Y1326422D01*
Y1325260D01*
G01X1350238Y1328591D02*
Y1328297D01*
X1351959Y1326576D01*
Y1325260D01*
G01X1350238Y1331647D02*
X1348899Y1330308D01*
X1347015D01*
G01X1366868Y147341D02*
X1366039Y148170D01*
X1364407D01*
G01X1363870Y853490D02*
Y851381D01*
X1363871Y851380D01*
G01X1373121Y843877D02*
Y841467D01*
G01X1365721Y843877D02*
Y841467D01*
G01X1378670Y853490D02*
Y851381D01*
X1378671Y851380D01*
G01X1374970Y853490D02*
Y851381D01*
X1374971Y851380D01*
G01X1371270Y853490D02*
Y851381D01*
X1371271Y851380D01*
G01X1367570Y853490D02*
Y851381D01*
X1367571Y851380D01*
G01X1376821Y850286D02*
Y848178D01*
X1376820Y848177D01*
Y848176D01*
G01X1363870Y866307D02*
X1363871Y866306D01*
Y864197D01*
G01X1378670Y866307D02*
X1378671Y866306D01*
Y864197D01*
G01X1374970Y866307D02*
X1374971Y866306D01*
Y864197D01*
G01X1371270Y866307D02*
X1371271Y866306D01*
Y864197D01*
G01X1367570Y866307D02*
X1367571Y866306D01*
Y864197D01*
G01X1376821Y863103D02*
Y860994D01*
X1376820Y860993D01*
G01X1369421Y863103D02*
Y860994D01*
X1369420Y860993D01*
G01X1363870Y879124D02*
Y877015D01*
X1363871Y877014D01*
G01X1378670Y879124D02*
Y877015D01*
X1378671Y877014D01*
G01X1374970Y879124D02*
Y877015D01*
X1374971Y877014D01*
G01X1371270Y879124D02*
Y877015D01*
X1371271Y877014D01*
G01X1367570Y879124D02*
Y877015D01*
X1367571Y877014D01*
G01X1369421Y875920D02*
Y873811D01*
X1369420Y873810D01*
G01X1363870Y891942D02*
Y889833D01*
X1363871Y889832D01*
G01X1378670Y891942D02*
Y889833D01*
X1378671Y889832D01*
G01X1374970Y891942D02*
Y889833D01*
X1374971Y889832D01*
G01X1371270Y891942D02*
Y889833D01*
X1371271Y889832D01*
G01X1367570Y891942D02*
Y889833D01*
X1367571Y889832D01*
G01X1376821Y888737D02*
Y886628D01*
X1376820Y886627D01*
G01X1369421Y888737D02*
Y886628D01*
X1369420Y886627D01*
G01X1371270Y917576D02*
Y915467D01*
X1371271Y915466D01*
G01X1367570Y917576D02*
X1367571Y917575D01*
Y915466D01*
G01X1367570Y923985D02*
Y921876D01*
X1367571Y921875D01*
G01X1373121Y933598D02*
Y931489D01*
X1373120Y931488D01*
G01X1363870Y936801D02*
Y934691D01*
G01X1371270Y936801D02*
X1371271D01*
Y934691D01*
G01X1367570Y936801D02*
X1367571D01*
Y934691D01*
G01X1374970Y949619D02*
X1374971Y949618D01*
Y947509D01*
G01X1378670Y949619D02*
X1378671Y949618D01*
Y947509D01*
G01X1376821Y959232D02*
X1376820Y959231D01*
Y957122D01*
G01X1373121Y959232D02*
X1373120Y959231D01*
Y957122D01*
G01X1373121Y952823D02*
Y950713D01*
G01X1371270Y956027D02*
Y953918D01*
X1371271Y953917D01*
G01X1378670Y956027D02*
X1378671D01*
Y953917D01*
G01X1376821Y952823D02*
X1376822Y952822D01*
Y950713D01*
G01X1374970Y956027D02*
X1374971D01*
Y953917D01*
G01X1375403Y1016800D02*
Y1018910D01*
G01X1373554Y1026413D02*
Y1028522D01*
X1373553Y1028523D01*
G01X1373554Y1020004D02*
G03X1373553Y1022114I-2226050J0D01*
G01X1371703Y1023208D02*
Y1025317D01*
X1371704Y1025318D01*
G01X1375403Y1029617D02*
Y1031726D01*
X1375404Y1031727D01*
G01X1368003Y1029617D02*
Y1031726D01*
X1368004Y1031727D01*
G01X1375403Y1023208D02*
G02X1375404Y1025318I2226050J0D01*
G01X1379103Y1023208D02*
G02X1379104Y1025318I2226050J0D01*
G01X1379103Y1016800D02*
Y1018909D01*
X1379102Y1018910D01*
G01X1377254Y1020004D02*
Y1022113D01*
X1377253Y1022114D01*
G01X1375403Y1036026D02*
Y1038136D01*
G01X1373554Y1039230D02*
Y1041339D01*
X1373553Y1041340D01*
G01X1371703Y1042434D02*
Y1044543D01*
X1371704Y1044544D01*
G01X1373554Y1045639D02*
X1373553D01*
Y1047749D01*
G01X1379103Y1042434D02*
Y1044543D01*
X1379104Y1044544D01*
G01X1377254Y1039230D02*
Y1041339D01*
X1377253Y1041340D01*
G01X1375403Y1042434D02*
Y1044543D01*
X1375404Y1044544D01*
G01X1375403Y1048842D02*
G02X1375404Y1050952I2226050J0D01*
G01X1377254Y1077681D02*
Y1079790D01*
X1377253Y1079791D01*
G01X1373554Y1077681D02*
G03X1373553Y1079791I-2226050J0D01*
G01X1377254Y1090498D02*
Y1092608D01*
G01Y1084090D02*
Y1086199D01*
X1377253Y1086200D01*
G01X1375403Y1087294D02*
Y1089403D01*
X1375404Y1089404D01*
G01X1373554Y1084090D02*
Y1086200D01*
G01X1371703Y1080885D02*
G02X1371704Y1082995I2226050J0D01*
G01X1379103Y1093703D02*
Y1095812D01*
X1379104Y1095813D01*
G01X1375403Y1080885D02*
G02X1375404Y1082995I2226050J0D01*
G01X1364303Y1106520D02*
Y1108629D01*
X1364304Y1108630D01*
G01X1364303Y1100111D02*
Y1102220D01*
X1364304Y1102221D01*
G01X1371703Y1100111D02*
Y1102220D01*
X1371704Y1102221D01*
G01X1366154Y1103316D02*
X1366153Y1105426D01*
G01X1368003Y1100111D02*
X1368004Y1102221D01*
G01X1369854Y1103316D02*
Y1105425D01*
X1369853Y1105426D01*
G01X1377254Y1116133D02*
Y1118242D01*
X1377253Y1118243D01*
G01X1373554Y1116133D02*
Y1118242D01*
X1373553Y1118243D01*
G01X1371703Y1112929D02*
Y1115039D01*
G01X1369854Y1116133D02*
Y1118242D01*
X1369853Y1118243D01*
G01X1366154Y1116133D02*
Y1118242D01*
X1366153Y1118243D01*
G01X1368003Y1119337D02*
Y1121446D01*
X1368004Y1121447D01*
G01X1377254Y1128950D02*
Y1131059D01*
X1377253Y1131060D01*
G01X1373554Y1128950D02*
Y1131059D01*
X1373553Y1131060D01*
G01X1369854Y1128950D02*
Y1131059D01*
X1369853Y1131060D01*
G01X1366154Y1128950D02*
Y1131059D01*
X1366153Y1131060D01*
G01X1375403Y1132154D02*
Y1134263D01*
X1375404Y1134264D01*
G01X1368003Y1132154D02*
Y1134263D01*
X1368004Y1134264D01*
G01X1382366Y1331647D02*
X1380997Y1330278D01*
X1379114D01*
G01X1382315Y1325260D02*
Y1325440D01*
X1379114Y1328641D01*
Y1330278D01*
G01X1377990Y1385910D02*
Y1387922D01*
X1377470Y1388442D01*
Y1391032D01*
G01D02*
X1381880D01*
X1382577Y1390335D01*
X1384101D01*
G01X1373201Y1417374D02*
X1374041Y1416534D01*
Y1413019D01*
G01X1380521Y843877D02*
Y841467D01*
G01X1395321Y843877D02*
Y841467D01*
G01X1387921Y843877D02*
Y841467D01*
G01X1393470Y853490D02*
Y851381D01*
X1393471Y851380D01*
G01X1389770Y853490D02*
Y851381D01*
X1389771Y851380D01*
G01X1386070Y853490D02*
Y851381D01*
X1386071Y851380D01*
G01X1382370Y853490D02*
Y851381D01*
X1382371Y851380D01*
G01X1391621Y850286D02*
Y848177D01*
X1391620Y848176D01*
G01X1384221Y850286D02*
Y848178D01*
X1384220Y848177D01*
Y848176D01*
G01X1393470Y866307D02*
X1393471Y866306D01*
Y864197D01*
G01X1389770Y866307D02*
X1389771Y866306D01*
Y864197D01*
G01X1386070Y866307D02*
X1386071Y866306D01*
Y864197D01*
G01X1382370Y866307D02*
X1382371Y866306D01*
Y864197D01*
G01X1391621Y863103D02*
Y860994D01*
X1391620Y860993D01*
G01X1384221Y863103D02*
Y860994D01*
X1384220Y860993D01*
G01X1393470Y879124D02*
Y877015D01*
X1393471Y877014D01*
G01X1389770Y879124D02*
Y877015D01*
X1389771Y877014D01*
G01X1386070Y879124D02*
Y877015D01*
X1386071Y877014D01*
G01X1386070Y872716D02*
Y870607D01*
X1386071Y870606D01*
G01X1382370Y879124D02*
Y877015D01*
X1382371Y877014D01*
G01X1391621Y875920D02*
Y873811D01*
X1391620Y873810D01*
G01X1393470Y891942D02*
Y889833D01*
X1393471Y889832D01*
G01X1389770Y891942D02*
Y889833D01*
X1389771Y889832D01*
G01X1387921Y895146D02*
Y893036D01*
G01X1386070Y891942D02*
Y889833D01*
X1386071Y889832D01*
G01X1384221Y895146D02*
Y893036D01*
G01X1382370Y891942D02*
Y889833D01*
X1382371Y889832D01*
G01X1391621Y888737D02*
Y886628D01*
X1391620Y886627D01*
G01X1384221Y888737D02*
Y886628D01*
X1384220Y886627D01*
G01X1390719Y939213D02*
Y941612D01*
X1390234Y942097D01*
G01X1393903Y1042434D02*
G02X1393904Y1044544I2226050J0D01*
G01X1384654Y1039230D02*
Y1041339D01*
X1384653Y1041340D01*
G01X1380954Y1039230D02*
Y1041339D01*
X1380953Y1041340D01*
G01X1392054Y1058455D02*
X1392053Y1058456D01*
Y1060565D01*
G01X1392054Y1052047D02*
X1392053Y1052048D01*
Y1054157D01*
G01X1388354Y1058455D02*
X1388353Y1058456D01*
Y1060565D01*
G01X1384654Y1052047D02*
X1384653Y1052048D01*
Y1054157D01*
G01X1392054Y1064864D02*
X1392053Y1064865D01*
Y1066974D01*
G01X1392054Y1077681D02*
Y1079790D01*
X1392053Y1079791D01*
G01X1393903Y1080885D02*
Y1082995D01*
G01X1382803Y1093703D02*
Y1095812D01*
X1382804Y1095813D01*
G01X1380954Y1090498D02*
Y1092606D01*
X1380953Y1092607D01*
Y1092608D01*
G01X1393903Y1093703D02*
Y1095812D01*
X1393904Y1095813D01*
G01X1393903Y1100111D02*
Y1102220D01*
X1393904Y1102221D01*
G01X1392054Y1096907D02*
Y1099017D01*
G01X1380954Y1116133D02*
Y1118242D01*
X1380953Y1118243D01*
G01X1393903Y1112929D02*
Y1115039D01*
G01X1392054Y1116133D02*
X1392053Y1116134D01*
Y1118243D01*
G01X1390203Y1119337D02*
Y1121447D01*
G01X1388354Y1122541D02*
Y1124650D01*
X1388353Y1124651D01*
G01X1388354Y1116133D02*
Y1118242D01*
X1388353Y1118243D01*
G01X1384654Y1116133D02*
Y1118242D01*
X1384653Y1118243D01*
G01X1386503Y1125746D02*
Y1127856D01*
G01X1395754Y1116133D02*
Y1118243D01*
G01X1382803Y1119337D02*
Y1121447D01*
G01X1390203Y1125746D02*
X1390204Y1125747D01*
Y1127856D01*
G01X1380954Y1128950D02*
Y1131059D01*
X1380953Y1131060D01*
G01X1390203Y1132154D02*
X1390204Y1134264D01*
G01X1388354Y1128950D02*
Y1131060D01*
G01X1386503Y1138563D02*
Y1140973D01*
G01X1384654Y1128950D02*
Y1131059D01*
X1384653Y1131060D01*
G01X1382803Y1132154D02*
Y1134263D01*
X1382804Y1134264D01*
G01X1388354Y1135359D02*
Y1137469D01*
G01X1386366Y1329329D02*
X1386426D01*
X1386427Y1329328D01*
X1387630Y1326422D01*
Y1325260D01*
G01X1382366Y1328591D02*
Y1328297D01*
X1384087Y1326576D01*
Y1325260D01*
G01X1390474Y1385142D02*
Y1386087D01*
X1391872Y1387485D01*
X1393117D01*
X1394693Y1389061D01*
Y1390306D01*
G01X1387074Y1384272D02*
X1385436Y1385910D01*
X1383890D01*
G01X1402721Y843877D02*
Y841467D01*
G01X1397170Y853490D02*
Y851381D01*
X1397171Y851380D01*
G01X1408270Y853490D02*
Y851381D01*
X1408271Y851380D01*
G01X1404570Y853490D02*
Y851381D01*
X1404571Y851380D01*
G01X1400870Y853490D02*
Y851381D01*
X1400871Y851380D01*
G01X1411971Y853490D02*
Y851380D01*
G01X1399021Y850286D02*
Y848178D01*
X1399020Y848177D01*
Y848176D01*
G01X1397170Y866307D02*
X1397171Y866306D01*
Y864197D01*
G01X1408270Y866307D02*
X1408271Y866306D01*
Y864197D01*
G01X1404570Y866307D02*
X1404571Y866306D01*
Y864197D01*
G01X1400870Y866307D02*
X1400871Y866306D01*
Y864197D01*
G01X1411971Y866307D02*
Y864197D01*
G01X1399021Y863103D02*
Y860994D01*
X1399020Y860993D01*
G01X1397170Y879124D02*
Y877015D01*
X1397171Y877014D01*
G01X1408270Y879124D02*
Y877015D01*
X1408271Y877014D01*
G01X1404570Y879124D02*
Y877015D01*
X1404571Y877014D01*
G01X1400870Y879124D02*
Y877015D01*
X1400871Y877014D01*
G01X1411971Y879124D02*
Y877014D01*
G01X1399021Y875920D02*
Y873811D01*
X1399020Y873810D01*
G01X1397170Y891942D02*
Y889833D01*
X1397171Y889832D01*
G01X1408270Y891942D02*
Y889833D01*
X1408271Y889832D01*
G01X1404570Y891942D02*
Y889833D01*
X1404571Y889832D01*
G01X1400870Y891942D02*
Y889833D01*
X1400871Y889832D01*
G01X1411971D02*
Y891942D01*
G01X1406421Y888737D02*
Y886628D01*
X1406420Y886627D01*
G01X1399021Y888737D02*
Y886628D01*
X1399020Y886627D01*
G01X1406421Y940006D02*
X1406420Y940005D01*
Y937896D01*
G01X1410121Y940006D02*
X1410120Y940005D01*
Y937896D01*
G01X1410121Y946414D02*
Y944304D01*
G01Y959232D02*
Y957122D01*
G01Y952823D02*
Y950713D01*
G01Y965640D02*
Y963530D01*
G01Y978457D02*
Y976347D01*
G01Y972049D02*
Y969939D01*
G01Y984866D02*
Y982756D01*
G01X1410554Y1007187D02*
Y1009296D01*
X1410553Y1009297D01*
G01X1410554Y1000778D02*
Y1002887D01*
X1410553Y1002888D01*
G01X1410554Y1013595D02*
Y1015704D01*
X1410553Y1015705D01*
G01X1410554Y1026413D02*
Y1028522D01*
X1410553Y1028523D01*
G01X1410554Y1020004D02*
Y1022113D01*
X1410553Y1022114D01*
G01X1405003Y1042434D02*
G02X1405004Y1044544I2226050J0D01*
G01X1410554Y1032821D02*
Y1034930D01*
X1410553Y1034931D01*
G01X1406853Y1045639D02*
Y1047748D01*
X1406854Y1047749D01*
G01X1401303Y1042434D02*
X1401304Y1042435D01*
Y1044544D01*
G01X1410554Y1045638D02*
Y1045639D01*
G01D02*
Y1047749D01*
G01X1408703Y1048842D02*
Y1050952D01*
G01X1410554Y1058455D02*
X1409853Y1059156D01*
Y1059865D01*
X1410553Y1060565D01*
G01X1410554Y1052047D02*
Y1054156D01*
X1410553Y1054157D01*
G01X1408703Y1074477D02*
Y1076587D01*
G01X1410554Y1071273D02*
Y1073382D01*
X1410553Y1073383D01*
G01X1410554Y1064864D02*
Y1066973D01*
X1410553Y1066974D01*
G01X1410554Y1077681D02*
Y1079790D01*
X1410553Y1079791D01*
G01X1399454Y1077681D02*
Y1079790D01*
X1399453Y1079791D01*
G01X1408703Y1087294D02*
Y1089404D01*
G01Y1080885D02*
Y1082995D01*
G01X1405003Y1080885D02*
Y1082995D01*
G01X1397603Y1080885D02*
Y1082994D01*
X1397604Y1082995D01*
G01X1410554Y1090498D02*
Y1092607D01*
X1410553Y1092608D01*
G01X1410554Y1084090D02*
Y1086199D01*
X1410553Y1086200D01*
G01X1408703Y1093703D02*
Y1095813D01*
G01X1405003Y1093703D02*
Y1095813D01*
G01X1397603Y1093703D02*
Y1095812D01*
X1397604Y1095813D01*
G01X1403154Y1096907D02*
X1403153Y1096908D01*
Y1099017D01*
G01X1401303Y1100111D02*
Y1102221D01*
G01X1399454Y1103316D02*
Y1105425D01*
X1399453Y1105426D01*
G01X1397603Y1106520D02*
Y1108629D01*
X1397604Y1108630D01*
G01X1410554Y1103316D02*
Y1105425D01*
X1410553Y1105426D01*
G01X1399454Y1109724D02*
Y1111833D01*
X1399453Y1111834D01*
G01X1410554Y1109724D02*
Y1111833D01*
X1410553Y1111834D01*
G01X1399454Y1096907D02*
Y1099016D01*
X1399453Y1099017D01*
G01X1397603Y1100111D02*
Y1102220D01*
X1397604Y1102221D01*
G01X1410554Y1096907D02*
Y1099017D01*
G01X1399454Y1122541D02*
Y1124650D01*
X1399453Y1124651D01*
G01X1399454Y1116133D02*
Y1118242D01*
X1399453Y1118243D01*
G01X1397603Y1112929D02*
Y1115038D01*
X1397604Y1115039D01*
G01X1410554Y1122541D02*
Y1124650D01*
X1410553Y1124651D01*
G01X1410554Y1116133D02*
Y1118242D01*
X1410553Y1118243D01*
G01X1399454Y1135359D02*
Y1137469D01*
G01Y1128950D02*
Y1131059D01*
X1399453Y1131060D01*
G01X1410554Y1135359D02*
Y1137769D01*
G01Y1128950D02*
Y1131059D01*
X1410553Y1131060D01*
G01X1406853Y1135359D02*
Y1137769D01*
G01X1414494Y1331647D02*
X1413154Y1330307D01*
X1411124D01*
G01X1414443Y1325260D02*
Y1325669D01*
X1411124Y1328988D01*
Y1330307D01*
G01X1426771Y853490D02*
Y851380D01*
G01X1423070Y853490D02*
Y851380D01*
G01X1419370Y853490D02*
Y851380D01*
G01X1415670Y853490D02*
Y851381D01*
X1415671Y851380D01*
G01X1413821Y863103D02*
X1413822Y863102D01*
Y860993D01*
G01X1426771Y866307D02*
Y864197D01*
G01X1424921Y856694D02*
Y854584D01*
G01X1423070Y866307D02*
X1423071Y866306D01*
Y864197D01*
G01X1419370Y866307D02*
X1419371Y866306D01*
Y864197D01*
G01X1415670Y866307D02*
X1415671Y866306D01*
Y864197D01*
G01X1421221Y863103D02*
Y860994D01*
X1421220Y860993D01*
G01X1426771Y879124D02*
Y877014D01*
G01X1423070Y879124D02*
Y877015D01*
X1423071Y877014D01*
G01X1419370Y879124D02*
Y877015D01*
X1419371Y877014D01*
G01X1415670Y879124D02*
Y877015D01*
X1415671Y877014D01*
G01X1413821Y888737D02*
Y886628D01*
X1413820Y886627D01*
G01X1426771Y889832D02*
Y891942D01*
G01X1423070D02*
Y889833D01*
X1423071Y889832D01*
G01X1419370Y891942D02*
Y889833D01*
X1419371Y889832D01*
G01X1415670Y891942D02*
Y889833D01*
X1415671Y889832D01*
G01X1421221Y888737D02*
Y886628D01*
X1421220Y886627D01*
G01X1413821Y940006D02*
X1413820Y940005D01*
Y937896D01*
G01X1417521Y940006D02*
X1417520Y940005D01*
Y937896D01*
G01X1421221Y940006D02*
X1421220Y940005D01*
Y937896D01*
G01X1424921Y940006D02*
X1424920Y940005D01*
Y937896D01*
G01X1423070Y943210D02*
Y941100D01*
G01Y949619D02*
Y947510D01*
X1423071Y947509D01*
G01X1423070Y962436D02*
Y960327D01*
X1423071Y960326D01*
G01X1423070Y956027D02*
Y953918D01*
X1423071Y953917D01*
G01X1423070Y968845D02*
X1423071Y966735D01*
G01X1423070Y981662D02*
Y979553D01*
X1423071Y979552D01*
G01X1423070Y975253D02*
Y973144D01*
X1423071Y973143D01*
G01X1423503Y997574D02*
Y999684D01*
G01Y1003983D02*
Y1006093D01*
G01Y1012501D02*
Y1010391D01*
G01Y1023208D02*
Y1025318D01*
G01Y1016800D02*
Y1018910D01*
G01Y1029617D02*
Y1031727D01*
G01X1427203Y1042434D02*
Y1044544D01*
G01X1423503Y1036026D02*
Y1038136D01*
G01Y1055251D02*
Y1057361D01*
G01Y1048842D02*
Y1050952D01*
G01Y1061660D02*
Y1063770D01*
G01Y1074477D02*
Y1076587D01*
G01Y1068068D02*
Y1070178D01*
G01X1425354Y1077681D02*
X1425353Y1079791D01*
G01X1427203Y1087294D02*
Y1089403D01*
X1427204Y1089404D01*
G01X1425354Y1084090D02*
Y1086200D01*
G01X1423503Y1080885D02*
Y1082995D01*
G01X1427203Y1093703D02*
Y1095812D01*
G01X1423503Y1093703D02*
Y1095813D01*
G01Y1106520D02*
Y1108630D01*
G01Y1100111D02*
Y1102221D01*
G01Y1119337D02*
Y1121447D01*
G01Y1112929D02*
Y1115039D01*
G01Y1125746D02*
Y1127856D01*
G01Y1132154D02*
Y1134264D01*
G01X1418494Y1329329D02*
X1418554D01*
X1418555Y1329328D01*
X1419758Y1326422D01*
Y1325260D01*
G01X1414494Y1328591D02*
Y1328297D01*
X1416215Y1326576D01*
Y1325260D01*
G01X1431575Y1404469D02*
X1429427D01*
X1427155Y1402197D01*
Y1400554D01*
G01Y1393959D02*
Y1397404D01*
G01D02*
X1425047D01*
X1424255Y1396612D01*
G01X1424161Y1391862D02*
X1429406D01*
X1430305Y1392761D01*
Y1393959D01*
G01X1421480Y1415751D02*
X1423541D01*
X1426167Y1413125D01*
G01X1421480Y1415751D02*
Y1415731D01*
G01X1442434Y210757D02*
X1443820D01*
X1444925Y211862D01*
G01X1434170Y853490D02*
Y851381D01*
X1434171Y851380D01*
G01X1437870Y853490D02*
Y851381D01*
X1437871Y851380D01*
G01X1430470Y853490D02*
Y851380D01*
G01X1432321Y843877D02*
Y841467D01*
G01X1439721Y843877D02*
Y841467D01*
G01X1441570Y853490D02*
Y851381D01*
X1441571Y851380D01*
G01X1436021Y850286D02*
X1436020Y850285D01*
Y848176D01*
G01X1443421Y850286D02*
Y848178D01*
X1443420Y848177D01*
Y848176D01*
G01X1439721Y856694D02*
Y854584D01*
G01X1432321Y856694D02*
Y854584D01*
G01X1437870Y866307D02*
X1437871Y866306D01*
Y864197D01*
G01X1434170Y866307D02*
X1434171Y866306D01*
Y864197D01*
G01X1430470Y866307D02*
X1430471Y866306D01*
Y864197D01*
G01X1441570Y866307D02*
X1441571Y866306D01*
Y864197D01*
G01X1428621Y863103D02*
Y860993D01*
G01X1436021Y863103D02*
Y860994D01*
X1436020Y860993D01*
G01X1443421Y863103D02*
Y860994D01*
X1443420Y860993D01*
G01X1437870Y879124D02*
Y877015D01*
X1437871Y877014D01*
G01X1434170Y879124D02*
Y877015D01*
X1434171Y877014D01*
G01X1430470Y879124D02*
Y877015D01*
X1430471Y877014D01*
G01X1441570Y879124D02*
Y877015D01*
X1441571Y877014D01*
G01X1436021Y875920D02*
Y873811D01*
X1436020Y873810D01*
G01X1443421Y875920D02*
Y873811D01*
X1443420Y873810D01*
G01X1437870Y891942D02*
Y889833D01*
X1437871Y889832D01*
G01X1434170Y891942D02*
Y889833D01*
X1434171Y889832D01*
G01X1430470Y891942D02*
Y889833D01*
X1430471Y889832D01*
G01X1441570Y891942D02*
Y889833D01*
X1441571Y889832D01*
G01X1436021Y901555D02*
X1436020Y901554D01*
Y899445D01*
G01X1436021Y888737D02*
Y886628D01*
X1436020Y886627D01*
G01X1428621Y901555D02*
X1428620Y901554D01*
Y899445D01*
G01X1428621Y888737D02*
Y886628D01*
X1428620Y886627D01*
G01X1443421Y901555D02*
X1443420Y901554D01*
Y899445D01*
G01X1443421Y888737D02*
Y886628D01*
X1443420Y886627D01*
G01X1434170Y904759D02*
X1434171Y904758D01*
Y902649D01*
G01X1441570Y904759D02*
X1441571Y904758D01*
Y902649D01*
G01X1429054Y1039230D02*
Y1041338D01*
X1429053Y1041339D01*
Y1041340D01*
G01X1442003Y1042434D02*
Y1044544D01*
G01Y1055251D02*
X1442004Y1057361D01*
G01X1442003Y1061660D02*
X1442004Y1063653D01*
Y1063770D01*
G01X1443854Y1052047D02*
Y1054157D01*
G01Y1058455D02*
Y1060565D01*
G01X1429054Y1077681D02*
X1429053Y1079791D01*
G01X1430903Y1074477D02*
Y1076587D01*
G01X1443854Y1064864D02*
X1443853Y1066974D01*
G01X1432754Y1077681D02*
Y1079791D01*
G01X1443854Y1077681D02*
X1443853Y1079791D01*
G01X1429054Y1090498D02*
Y1092607D01*
X1429053Y1092608D01*
G01X1434603Y1080885D02*
Y1082995D01*
G01X1443854Y1084090D02*
Y1086200D01*
G01X1440154Y1084090D02*
X1440153Y1086200D01*
G01X1443854Y1090498D02*
Y1092608D01*
G01X1429054Y1084090D02*
Y1086199D01*
X1429053Y1086200D01*
G01X1442003Y1080885D02*
X1442004Y1080886D01*
Y1082995D01*
G01X1438303Y1080885D02*
X1438304Y1080886D01*
Y1082995D01*
G01X1429054Y1096907D02*
Y1099016D01*
X1429053Y1099017D01*
G01X1436454Y1103316D02*
Y1105426D01*
G01X1434603Y1100111D02*
Y1102220D01*
X1434604Y1102221D01*
G01X1432754Y1096907D02*
Y1099016D01*
X1432753Y1099017D01*
G01X1442003Y1106520D02*
Y1108630D01*
G01Y1100111D02*
Y1102221D01*
G01X1440154Y1103316D02*
Y1105426D01*
G01Y1096907D02*
Y1099017D01*
G01X1438303Y1106520D02*
Y1108629D01*
X1438304Y1108630D01*
G01X1440154Y1109724D02*
Y1111834D01*
G01X1443854Y1103316D02*
Y1105425D01*
X1443853Y1105426D01*
G01X1443854Y1109724D02*
X1443853Y1111834D01*
G01X1438303Y1100111D02*
X1438304Y1102221D01*
G01X1443854Y1096907D02*
X1443853Y1099017D01*
G01X1434603Y1119337D02*
Y1121446D01*
X1434604Y1121447D01*
G01X1434603Y1112929D02*
Y1115038D01*
X1434604Y1115039D01*
G01X1443854Y1122541D02*
Y1124651D01*
G01Y1116133D02*
Y1118242D01*
X1443853Y1118243D01*
G01X1442003Y1119337D02*
Y1121446D01*
X1442004Y1121447D01*
G01X1442003Y1112929D02*
Y1115038D01*
X1442004Y1115039D01*
G01X1434603Y1125746D02*
Y1127855D01*
X1434604Y1127856D01*
G01X1434603Y1132154D02*
Y1134263D01*
X1434604Y1134264D01*
G01X1446622Y1331647D02*
X1445300Y1330325D01*
X1443785D01*
G01X1446571Y1325260D02*
Y1325637D01*
X1443785Y1328423D01*
Y1330325D01*
G01X1444720Y1404387D02*
X1444728Y1404395D01*
X1448842D01*
G01X1435462Y1393009D02*
X1434512Y1393959D01*
X1430305D01*
G01X1435462Y1396409D02*
X1434643Y1395590D01*
X1432576D01*
X1431575Y1396591D01*
Y1398569D01*
G01X1439742Y1432624D02*
Y1436924D01*
G01X1454521Y843877D02*
Y841467D01*
G01X1445270Y853490D02*
Y851381D01*
X1445271Y851380D01*
G01X1447121Y843877D02*
Y841467D01*
G01X1460070Y853490D02*
Y851381D01*
X1460071Y851380D01*
G01X1452670Y853490D02*
Y851381D01*
X1452671Y851380D01*
G01X1456370Y853490D02*
Y851381D01*
X1456371Y851380D01*
G01X1448970Y853490D02*
Y851381D01*
X1448971Y851380D01*
G01X1458221Y850286D02*
Y848178D01*
X1458220Y848177D01*
Y848176D01*
G01X1450821Y850286D02*
Y848178D01*
X1450820Y848177D01*
Y848176D01*
G01X1445270Y866307D02*
X1445271Y866306D01*
Y864197D01*
G01X1460070Y866307D02*
X1460071Y866306D01*
Y864197D01*
G01X1456370Y866307D02*
X1456371Y866306D01*
Y864197D01*
G01X1454521Y856694D02*
Y854584D01*
G01X1452670Y866307D02*
X1452671Y866306D01*
Y864197D01*
G01X1447121Y856694D02*
Y854584D01*
G01X1448970Y866307D02*
X1448971Y866306D01*
Y864197D01*
G01X1458221Y863103D02*
Y860994D01*
X1458220Y860993D01*
G01X1450821Y863103D02*
Y860994D01*
X1450820Y860993D01*
G01X1445270Y879124D02*
Y877015D01*
X1445271Y877014D01*
G01X1460070Y879124D02*
Y877015D01*
X1460071Y877014D01*
G01X1456370Y879124D02*
Y877015D01*
X1456371Y877014D01*
G01X1452670Y879124D02*
Y877015D01*
X1452671Y877014D01*
G01X1448970Y879124D02*
Y877015D01*
X1448971Y877014D01*
G01X1448970Y872716D02*
Y870606D01*
G01X1447121Y875920D02*
Y873810D01*
G01X1458221Y875920D02*
Y873811D01*
X1458220Y873810D01*
G01X1450821Y875920D02*
Y873811D01*
X1450820Y873810D01*
G01X1445270Y898350D02*
X1445271Y898349D01*
Y896240D01*
G01X1445270Y891942D02*
Y889833D01*
X1445271Y889832D01*
G01X1456370Y891942D02*
Y889833D01*
X1456371Y889832D01*
G01X1460070Y891942D02*
Y889833D01*
X1460071Y889832D01*
G01X1452670Y891942D02*
Y889833D01*
X1452671Y889832D01*
G01X1448970Y891942D02*
Y889833D01*
X1448971Y889832D01*
G01X1458221Y901555D02*
X1458220Y901554D01*
Y899445D01*
G01X1450821Y901555D02*
X1450820Y901554D01*
Y899445D01*
G01X1458221Y888737D02*
Y886628D01*
X1458220Y886627D01*
G01X1450821Y888737D02*
Y886628D01*
X1450820Y886627D01*
G01X1460070Y911167D02*
X1460071Y911166D01*
Y909057D01*
G01X1458221Y914372D02*
Y912262D01*
G01X1460070Y904759D02*
Y902649D01*
G01X1458221Y907963D02*
Y905854D01*
X1458220Y905853D01*
G01X1458221Y920780D02*
X1458220Y920779D01*
Y918670D01*
G01X1456370Y923985D02*
X1456371Y923984D01*
Y921875D01*
G01X1460070Y923985D02*
Y921875D01*
G01X1452670Y923985D02*
Y921875D01*
G01X1450821Y920780D02*
X1450820Y920779D01*
Y918670D01*
G01X1458221Y933598D02*
X1458220Y933597D01*
Y931488D01*
G01X1458221Y946414D02*
Y944304D01*
G01X1456370Y936801D02*
X1456369Y936800D01*
Y934693D01*
X1456371Y934691D01*
G01X1460070Y949619D02*
Y947509D01*
G01X1456370Y949619D02*
Y947510D01*
X1456371Y947509D01*
G01X1458221Y959232D02*
X1458220Y959231D01*
Y957122D01*
G01X1458221Y952823D02*
Y950713D01*
G01X1456370Y956027D02*
X1456371Y956026D01*
Y953917D01*
G01X1454521Y959232D02*
X1454520Y959231D01*
Y957122D01*
G01X1454521Y952823D02*
X1454520Y952822D01*
Y950713D01*
G01X1458654Y1000778D02*
Y1002887D01*
X1458653Y1002888D01*
G01X1454954Y1013595D02*
X1454953Y1015705D01*
G01X1458654Y1020004D02*
Y1020053D01*
X1458653Y1022114D01*
G01X1460503Y1016800D02*
Y1018910D01*
G01X1456803Y1016800D02*
Y1018910D01*
G01X1454954Y1026413D02*
Y1028521D01*
X1454953Y1028522D01*
Y1028523D01*
G01X1454954Y1020004D02*
Y1022113D01*
X1454953Y1022114D01*
G01X1458654Y1045639D02*
Y1047748D01*
X1458653Y1047749D01*
G01X1454954Y1045639D02*
Y1047748D01*
X1454953Y1047749D01*
G01X1453103Y1042434D02*
Y1044543D01*
X1453104Y1044544D01*
G01X1460503Y1055251D02*
Y1057361D01*
G01X1458654Y1058455D02*
X1458653Y1060565D01*
G01X1456803Y1048842D02*
X1456804Y1050952D01*
G01X1451254Y1058455D02*
X1451253Y1060565D01*
G01X1447554Y1052047D02*
X1447553Y1054157D01*
G01X1460503Y1048842D02*
X1460504Y1050952D01*
G01X1454954Y1052047D02*
Y1054157D01*
G01Y1058455D02*
Y1060565D01*
G01X1456803Y1055251D02*
Y1057361D01*
G01X1453103Y1048842D02*
Y1050952D01*
G01X1445703Y1055251D02*
Y1057361D01*
G01X1447554Y1058455D02*
Y1060565D01*
G01X1449403Y1055251D02*
Y1057361D01*
G01X1451254Y1052047D02*
Y1054157D01*
G01X1445703Y1048842D02*
Y1050952D01*
G01X1456803Y1061660D02*
X1456804Y1063653D01*
Y1063770D01*
G01X1453103Y1061660D02*
X1453104Y1063653D01*
Y1063770D01*
G01X1453103Y1055251D02*
Y1057360D01*
X1453104Y1057361D01*
G01X1449403Y1061660D02*
X1449404Y1063653D01*
Y1063770D01*
G01X1445703Y1061660D02*
X1445704Y1063653D01*
Y1063770D01*
G01X1449403Y1048842D02*
Y1050951D01*
X1449404Y1050952D01*
G01X1458654Y1064864D02*
Y1066974D01*
G01Y1084090D02*
Y1086200D01*
G01X1449403Y1080885D02*
X1449404Y1082995D01*
G01X1445703Y1093703D02*
X1445704Y1095813D01*
G01X1460503Y1093703D02*
X1460504Y1095813D01*
G01X1456803Y1093703D02*
Y1095813D01*
G01Y1087294D02*
X1456804Y1089404D01*
G01X1449403Y1093703D02*
Y1095812D01*
X1449404Y1095813D01*
G01X1445703Y1080885D02*
X1445704Y1080886D01*
Y1082995D01*
G01X1445703Y1100111D02*
X1445704Y1102221D01*
G01X1458654Y1103316D02*
X1458653Y1105426D01*
G01X1456803Y1106520D02*
X1456804Y1108630D01*
G01X1454954Y1096907D02*
X1454953Y1099017D01*
G01X1449403Y1106520D02*
X1449404Y1108630D01*
G01X1453103Y1100111D02*
X1453104Y1102221D01*
G01X1451254Y1096907D02*
Y1099017D01*
G01X1447554Y1096907D02*
X1447553Y1099017D01*
G01X1458654Y1109724D02*
X1458653Y1111834D01*
G01X1460503Y1106520D02*
Y1108628D01*
X1460504Y1108629D01*
Y1108630D01*
G01X1451254Y1109724D02*
Y1111833D01*
X1451253Y1111834D01*
G01X1447554Y1109724D02*
Y1111833D01*
X1447553Y1111834D01*
G01X1454954Y1103316D02*
X1454953Y1105426D01*
G01X1445703Y1106520D02*
X1445704Y1106521D01*
Y1108630D01*
G01X1449403Y1100111D02*
Y1102220D01*
X1449404Y1102221D01*
G01X1458654Y1096907D02*
Y1099016D01*
X1458653Y1099017D01*
G01X1454954Y1109724D02*
Y1111833D01*
X1454953Y1111834D01*
G01X1453103Y1106520D02*
Y1108628D01*
X1453104Y1108629D01*
Y1108630D01*
G01X1447554Y1103316D02*
Y1105425D01*
X1447553Y1105426D01*
G01X1451254Y1103316D02*
Y1105425D01*
X1451253Y1105426D01*
G01X1460503Y1100111D02*
Y1102220D01*
X1460504Y1102221D01*
G01X1456803Y1100111D02*
Y1102220D01*
X1456804Y1102221D01*
G01X1445703Y1112929D02*
Y1115039D01*
G01X1458654Y1116133D02*
Y1118242D01*
X1458653Y1118243D01*
G01X1456803Y1112929D02*
Y1115039D01*
G01X1454954Y1116133D02*
Y1118242D01*
X1454953Y1118243D01*
G01X1453103Y1112929D02*
Y1115039D01*
G01X1451254Y1116133D02*
Y1118242D01*
X1451253Y1118243D01*
G01X1447554Y1116133D02*
Y1118242D01*
X1447553Y1118243D01*
G01X1445703Y1125746D02*
Y1127855D01*
X1445704Y1127856D01*
G01X1460503Y1112929D02*
X1460504Y1112930D01*
Y1115039D01*
G01X1449403Y1112929D02*
X1449404Y1112930D01*
Y1115039D01*
G01X1449403Y1119337D02*
X1449404Y1121447D01*
G01X1456803Y1119337D02*
X1456804Y1121447D01*
G01X1445703Y1138563D02*
Y1140973D01*
G01X1458654Y1128950D02*
Y1131059D01*
X1458653Y1131060D01*
G01X1454954Y1128950D02*
Y1131059D01*
X1454953Y1131060D01*
G01X1451254Y1128950D02*
Y1131059D01*
X1451253Y1131060D01*
G01X1447554Y1135359D02*
Y1137469D01*
G01Y1128950D02*
Y1131060D01*
G01X1449403Y1132154D02*
Y1134264D01*
G01X1456803Y1132154D02*
Y1134263D01*
X1456804Y1134264D01*
G01X1450622Y1329329D02*
X1450682D01*
X1450683Y1329328D01*
X1451886Y1326422D01*
Y1325260D01*
G01X1446622Y1328591D02*
Y1328297D01*
X1448343Y1326576D01*
Y1325260D01*
G01X1463774Y1408112D02*
X1461097Y1405435D01*
X1458609D01*
X1457609Y1404435D01*
Y1404395D01*
G01X1453509D02*
X1457609D01*
G01X1453509D02*
X1452546D01*
X1451198Y1403047D01*
G01D02*
X1449850Y1404395D01*
X1448842D01*
G01X1460804Y1415333D02*
X1459698D01*
X1459113Y1415918D01*
X1456393D01*
G01X1460166Y1411262D02*
X1459962D01*
X1457742Y1413482D01*
X1454315D01*
X1452637Y1411804D01*
Y1411397D01*
G01D02*
Y1411144D01*
G01X1452422Y1415918D02*
X1451792Y1416548D01*
X1447748D01*
X1447617Y1416417D01*
G01D02*
X1452637Y1411397D01*
G01X1457609Y1407545D02*
X1460224D01*
G01X1455787Y1411144D02*
Y1409367D01*
X1457609Y1407545D01*
G01X1458138Y1409955D02*
Y1410144D01*
X1457138Y1411144D01*
X1455787D01*
G01X1461975Y1409296D02*
X1460224Y1407545D01*
G01X1448842Y1409061D02*
Y1407545D01*
G01X1453509D02*
X1448842D01*
G01X1462000Y153362D02*
Y154787D01*
X1463000Y155787D01*
G01X1469321Y843877D02*
Y841467D01*
G01X1461921Y843877D02*
Y841467D01*
G01X1476721Y843877D02*
Y841467D01*
G01X1474870Y853490D02*
Y851381D01*
X1474871Y851380D01*
G01X1471170Y853490D02*
Y851381D01*
X1471171Y851380D01*
G01X1467470Y853490D02*
Y851381D01*
X1467471Y851380D01*
G01X1463770Y853490D02*
Y851381D01*
X1463771Y851380D01*
G01X1465621Y850286D02*
Y848178D01*
X1465620Y848177D01*
Y848176D01*
G01X1473021Y850286D02*
Y848178D01*
X1473020Y848177D01*
Y848176D01*
G01X1461921Y856694D02*
Y854584D01*
G01X1474870Y866307D02*
X1474871Y866306D01*
Y864197D01*
G01X1471170Y866307D02*
X1471171Y866306D01*
Y864197D01*
G01X1469321Y856694D02*
Y854584D01*
G01X1467470Y866307D02*
X1467471Y866306D01*
Y864197D01*
G01X1463770Y866307D02*
X1463771Y866306D01*
Y864197D01*
G01X1476721Y856694D02*
Y854584D01*
G01X1465621Y863103D02*
Y860994D01*
X1465620Y860993D01*
G01X1473021Y863103D02*
Y860994D01*
X1473020Y860993D01*
G01X1471170Y879124D02*
Y877015D01*
X1471171Y877014D01*
G01X1474870Y879124D02*
Y877015D01*
X1474871Y877014D01*
G01X1467470Y879124D02*
Y877015D01*
X1467471Y877014D01*
G01X1463770Y879124D02*
Y877015D01*
X1463771Y877014D01*
G01X1465621Y875920D02*
Y873811D01*
X1465620Y873810D01*
G01X1473021Y875920D02*
Y873811D01*
X1473020Y873810D01*
G01X1474870Y891942D02*
Y889833D01*
X1474871Y889832D01*
G01X1471170Y891942D02*
Y889833D01*
X1471171Y889832D01*
G01X1467470Y891942D02*
Y889833D01*
X1467471Y889832D01*
G01X1463770Y891942D02*
Y889833D01*
X1463771Y889832D01*
G01X1465621Y901555D02*
X1465620Y901554D01*
Y899445D01*
G01X1465621Y888737D02*
Y886628D01*
X1465620Y886627D01*
G01X1473021Y888737D02*
Y886628D01*
X1473020Y886627D01*
G01X1461921Y907963D02*
Y905854D01*
X1461920Y905853D01*
G01X1465621Y914372D02*
X1465620Y914371D01*
Y912262D01*
G01X1465621Y920780D02*
X1465620Y920779D01*
Y918670D01*
G01X1473021Y933598D02*
X1473020Y933597D01*
Y931488D01*
G01X1465621Y933598D02*
X1465620Y933597D01*
Y931488D01*
G01X1474870Y936801D02*
Y934692D01*
X1474871Y934691D01*
G01X1473454Y1007187D02*
Y1009296D01*
X1473453Y1009297D01*
G01X1466054Y1007187D02*
Y1009296D01*
X1466053Y1009297D01*
G01X1462354Y1032821D02*
Y1034930D01*
X1462353Y1034931D01*
G01X1466054Y1032821D02*
Y1034930D01*
X1466053Y1034931D01*
G01X1466054Y1045639D02*
Y1047748D01*
X1466053Y1047749D01*
G01X1473454Y1045639D02*
Y1047748D01*
X1473453Y1047749D01*
G01X1462354Y1052047D02*
X1462353Y1054157D01*
G01X1466054Y1058455D02*
X1466053Y1060565D01*
G01X1466054Y1077681D02*
Y1079790D01*
X1466053Y1079791D01*
G01X1467903Y1093703D02*
Y1095812D01*
X1467904Y1095813D01*
G01X1464203Y1093703D02*
Y1095812D01*
X1464204Y1095813D01*
G01X1462354Y1103316D02*
X1462353Y1105426D01*
G01X1462354Y1096907D02*
Y1099017D01*
G01X1473454Y1103316D02*
Y1105426D01*
G01X1469754Y1103316D02*
X1469753Y1105426D01*
G01X1467903Y1100111D02*
X1467904Y1102221D01*
G01X1464203Y1100111D02*
Y1102221D01*
G01X1473454Y1109724D02*
Y1111834D01*
G01X1466054Y1109724D02*
X1466053Y1111834D01*
G01X1466054Y1096907D02*
Y1099016D01*
X1466053Y1099017D01*
G01X1471603Y1100111D02*
X1471604Y1102221D01*
G01X1477154Y1096907D02*
Y1099016D01*
X1477153Y1099017D01*
G01X1469754Y1096907D02*
Y1099016D01*
X1469753Y1099017D01*
G01X1473454Y1096907D02*
Y1099016D01*
X1473453Y1099017D01*
G01X1471603Y1106520D02*
X1471604Y1106521D01*
Y1108630D01*
G01X1466054Y1103316D02*
X1466053Y1105426D01*
G01X1462354Y1109724D02*
Y1111833D01*
X1462353Y1111834D01*
G01X1469754Y1109724D02*
Y1111833D01*
X1469753Y1111834D01*
G01X1467903Y1106520D02*
Y1108628D01*
X1467904Y1108629D01*
Y1108630D01*
G01X1464203Y1106520D02*
Y1108628D01*
X1464204Y1108629D01*
Y1108630D01*
G01X1462354Y1116133D02*
Y1118242D01*
X1462353Y1118243D01*
G01X1477154Y1116133D02*
Y1118242D01*
X1477153Y1118243D01*
G01X1475303Y1112929D02*
Y1115039D01*
G01X1473454Y1116133D02*
Y1118242D01*
X1473453Y1118243D01*
G01X1471603Y1119337D02*
X1471604Y1121447D01*
G01X1469754Y1116133D02*
Y1118243D01*
G01X1466054Y1116133D02*
Y1118242D01*
X1466053Y1118243D01*
G01X1467903Y1112929D02*
X1467904Y1112930D01*
Y1115039D01*
G01X1471603Y1112929D02*
X1471604Y1112930D01*
Y1115039D01*
G01X1464203Y1119337D02*
X1464204Y1121447D01*
G01X1464203Y1112929D02*
X1464204Y1115039D01*
G01X1462354Y1128950D02*
Y1131059D01*
X1462353Y1131060D01*
G01X1477154Y1128950D02*
Y1131059D01*
X1477153Y1131060D01*
G01X1473454Y1128950D02*
Y1131059D01*
X1473453Y1131060D01*
G01X1469754Y1128950D02*
Y1131059D01*
X1469753Y1131060D01*
G01X1466054Y1128950D02*
Y1131059D01*
X1466053Y1131060D01*
G01X1471603Y1132154D02*
Y1134263D01*
X1471604Y1134264D01*
G01X1464203Y1132154D02*
Y1134263D01*
X1464204Y1134264D01*
G01X1478750Y1345073D02*
X1478256D01*
X1476947Y1343764D01*
X1475599D01*
G01X1478699Y1338686D02*
Y1339063D01*
X1476177Y1341585D01*
Y1342034D01*
X1475599Y1342612D01*
Y1343764D01*
G01X1481683Y281456D02*
Y279065D01*
X1484331Y276417D01*
X1509319D01*
X1512784Y279882D01*
Y284047D01*
X1514212Y285475D01*
Y294071D01*
G01X1491521Y843877D02*
Y841467D01*
G01X1484121Y843877D02*
Y841467D01*
G01X1478570Y853490D02*
Y851381D01*
X1478571Y851380D01*
G01X1482270Y853490D02*
Y851381D01*
X1482271Y851380D01*
G01X1489670Y853490D02*
Y851381D01*
X1489671Y851380D01*
G01X1485970Y853490D02*
Y851381D01*
X1485971Y851380D01*
G01X1493370Y853490D02*
Y851381D01*
X1493371Y851380D01*
G01X1487821Y850286D02*
Y848178D01*
X1487820Y848177D01*
Y848176D01*
G01X1480421Y850286D02*
Y848178D01*
X1480420Y848177D01*
Y848176D01*
G01X1478570Y866307D02*
X1478571Y866306D01*
Y864197D01*
G01X1491521Y856694D02*
Y854584D01*
G01X1489670Y866307D02*
Y864198D01*
X1489671Y864197D01*
G01X1485970Y866307D02*
X1485971Y864197D01*
G01X1482270Y866307D02*
X1482271Y866306D01*
Y864197D01*
G01X1493370Y866307D02*
Y864198D01*
X1493371Y864197D01*
G01X1484121Y856694D02*
Y854584D01*
G01X1487821Y863103D02*
Y860994D01*
X1487820Y860993D01*
G01X1480421Y863103D02*
Y860994D01*
X1480420Y860993D01*
G01X1478570Y879124D02*
Y877015D01*
X1478571Y877014D01*
G01X1485970Y879124D02*
Y877015D01*
X1485971Y877014D01*
G01X1489670Y879124D02*
Y877015D01*
X1489671Y877014D01*
G01X1482270Y879124D02*
Y877015D01*
X1482271Y877014D01*
G01X1493370Y879124D02*
Y877015D01*
X1493371Y877014D01*
G01X1487821Y875920D02*
Y873811D01*
X1487820Y873810D01*
G01X1480421Y875920D02*
Y873811D01*
X1480420Y873810D01*
G01X1478570Y891942D02*
Y889833D01*
X1478571Y889832D01*
G01X1482270Y891942D02*
Y889833D01*
X1482271Y889832D01*
G01X1489670Y891942D02*
Y889833D01*
X1489671Y889832D01*
G01X1485970Y891942D02*
Y889833D01*
X1485971Y889832D01*
G01X1493370Y891942D02*
Y889833D01*
X1493371Y889832D01*
G01X1487821Y888737D02*
Y886628D01*
X1487820Y886627D01*
G01X1480421Y888737D02*
Y886628D01*
X1480420Y886627D01*
G01X1478570Y917576D02*
Y915467D01*
X1478571Y915466D01*
G01X1482270Y917576D02*
Y915467D01*
X1482271Y915466D01*
G01X1491521Y933598D02*
X1491520Y933597D01*
Y931488D01*
G01X1478570Y936801D02*
Y934692D01*
X1478571Y934691D01*
G01X1482270Y936801D02*
X1482271D01*
Y934691D01*
G01X1484554Y1000778D02*
Y1002887D01*
X1484553Y1002888D01*
G01X1491954Y1007187D02*
Y1009296D01*
X1491953Y1009297D01*
G01X1491954Y1000778D02*
Y1002887D01*
X1491953Y1002888D01*
G01X1479003Y1023208D02*
Y1025317D01*
X1479004Y1025318D01*
G01X1479003Y1029617D02*
Y1031726D01*
X1479004Y1031727D01*
G01X1486403Y1029617D02*
Y1031726D01*
X1486404Y1031727D01*
G01X1491954Y1045639D02*
Y1047748D01*
X1491953Y1047749D01*
G01X1484554Y1045639D02*
Y1047748D01*
X1484553Y1047749D01*
G01X1491954Y1052047D02*
Y1054156D01*
X1491953Y1054157D01*
G01X1488254Y1052047D02*
Y1054156D01*
X1488253Y1054157D01*
G01X1490103Y1106520D02*
X1490104Y1108630D01*
G01X1490103Y1100111D02*
X1490104Y1102221D01*
G01X1488254Y1096907D02*
Y1099017D01*
G01X1484554Y1096907D02*
X1484553Y1099017D01*
G01X1480854Y1096907D02*
X1480853Y1099017D01*
G01X1491954Y1103316D02*
X1491953Y1105426D01*
G01X1491954Y1109724D02*
X1491953Y1111834D01*
G01X1486403Y1100111D02*
Y1102220D01*
X1486404Y1102221D01*
G01X1490103Y1112929D02*
Y1115039D01*
G01X1488254Y1116133D02*
Y1118242D01*
X1488253Y1118243D01*
G01X1484554Y1116133D02*
Y1118242D01*
X1484553Y1118243D01*
G01X1480854Y1116133D02*
Y1118242D01*
X1480853Y1118243D01*
G01X1486403Y1112929D02*
Y1115039D01*
G01X1491954Y1116133D02*
Y1118242D01*
X1491953Y1118243D01*
G01X1486403Y1119337D02*
X1486404Y1121447D01*
G01X1479003Y1119337D02*
X1479004Y1121447D01*
G01X1479003Y1112929D02*
X1479004Y1115039D01*
G01X1488254Y1128950D02*
Y1131059D01*
X1488253Y1131060D01*
G01X1484554Y1128950D02*
Y1131059D01*
X1484553Y1131060D01*
G01X1480854Y1128950D02*
Y1131059D01*
X1480853Y1131060D01*
G01X1491954Y1128950D02*
Y1131059D01*
X1491953Y1131060D01*
G01X1486403Y1132154D02*
Y1134263D01*
X1486404Y1134264D01*
G01X1479003Y1132154D02*
Y1134263D01*
X1479004Y1134264D01*
G01X1482750Y1342755D02*
X1482810D01*
X1482811Y1342754D01*
X1484014Y1339848D01*
Y1338686D01*
G01X1478750Y1342017D02*
Y1341723D01*
X1480471Y1340002D01*
Y1338686D01*
G01X1509488Y301748D02*
X1508189D01*
X1505922Y304015D01*
Y304583D01*
G01D02*
Y305861D01*
X1504602Y307181D01*
G01X1503514Y801361D02*
X1504464Y800411D01*
X1506537D01*
X1508877Y798071D01*
Y790177D01*
X1516479Y782575D01*
X1525017D01*
X1546907Y760685D01*
Y734095D01*
X1558367Y722635D01*
Y673772D01*
X1555448Y670853D01*
Y659668D01*
X1556950Y658166D01*
X1558404D01*
X1559354Y659116D01*
G01X1503514Y797961D02*
X1504464Y798911D01*
X1505915D01*
X1507377Y797449D01*
Y789555D01*
X1515857Y781075D01*
X1524395D01*
X1545407Y760063D01*
Y733473D01*
X1556867Y722013D01*
Y674394D01*
X1553948Y671475D01*
Y659046D01*
X1556328Y656666D01*
X1558404D01*
X1559354Y655716D01*
G01X1504471Y847081D02*
Y844671D01*
G01X1498921Y843877D02*
Y841467D01*
G01X1508170Y853490D02*
Y851381D01*
X1508171Y851380D01*
G01X1504471Y853490D02*
Y851380D01*
G01X1500770Y853490D02*
Y851381D01*
X1500771Y851380D01*
G01X1497070Y853490D02*
Y851381D01*
X1497071Y851380D01*
G01X1504471Y866307D02*
Y864197D01*
G01X1500770Y866307D02*
Y864198D01*
X1500771Y864197D01*
G01X1497070Y866307D02*
Y864198D01*
X1497071Y864197D01*
G01X1502621Y863103D02*
Y860993D01*
G01X1495221Y863103D02*
Y860994D01*
X1495220Y860993D01*
G01X1504471Y879124D02*
Y877014D01*
G01X1508170Y879124D02*
Y877015D01*
X1508171Y877014D01*
G01X1497070Y879124D02*
Y877015D01*
X1497071Y877014D01*
G01X1500770Y879124D02*
Y877015D01*
X1500771Y877014D01*
G01X1508170Y885533D02*
Y883423D01*
G01X1502621Y875920D02*
Y873810D01*
G01X1495221Y875920D02*
Y873811D01*
X1495220Y873810D01*
G01X1508170Y891942D02*
Y889833D01*
X1508171Y889832D01*
G01X1504471D02*
Y891942D01*
G01X1500770D02*
Y889833D01*
X1500771Y889832D01*
G01X1497070Y891942D02*
Y889833D01*
X1497071Y889832D01*
G01X1502621Y888737D02*
Y886627D01*
G01X1495221Y888737D02*
Y886628D01*
X1495220Y886627D01*
G01X1504471Y936801D02*
Y934691D01*
G01X1500770Y936801D02*
Y934691D01*
G01X1508170Y936801D02*
Y934692D01*
X1508171Y934691D01*
G01X1499354Y1007187D02*
Y1009296D01*
X1499353Y1009297D01*
G01X1508603Y1023208D02*
X1508602Y1025317D01*
X1508603Y1025318D01*
G01X1499354Y1045639D02*
Y1047748D01*
X1499353Y1047749D01*
G01X1493803Y1106520D02*
Y1108628D01*
X1493804Y1108629D01*
Y1108630D01*
G01X1503054Y1103316D02*
X1503053Y1105426D01*
G01X1497503Y1100111D02*
Y1102221D01*
G01X1495654Y1103316D02*
X1495653Y1105426D01*
G01X1495654Y1096907D02*
Y1099017D01*
G01X1508603Y1106520D02*
Y1108630D01*
G01X1506754Y1109724D02*
Y1111834D01*
G01X1499354Y1109724D02*
X1499353Y1111834D01*
G01X1503054Y1096907D02*
X1503053Y1099017D01*
G01X1508603Y1100111D02*
Y1102220D01*
X1508602Y1102221D01*
G01X1497503Y1106520D02*
Y1108628D01*
X1497504Y1108629D01*
Y1108630D01*
G01X1501203Y1106520D02*
Y1108628D01*
X1501204Y1108629D01*
Y1108630D01*
G01X1499354Y1103316D02*
X1499353Y1103317D01*
Y1105426D01*
G01X1504903Y1106520D02*
Y1108628D01*
X1504904Y1108629D01*
Y1108630D01*
G01X1495654Y1109724D02*
Y1111833D01*
X1495653Y1111834D01*
G01X1503054Y1109724D02*
Y1111833D01*
X1503053Y1111834D01*
G01X1499354Y1096907D02*
Y1099017D01*
G01X1501203Y1100111D02*
Y1102220D01*
X1501204Y1102221D01*
G01X1506754Y1103316D02*
Y1105425D01*
X1506753Y1105426D01*
G01X1504903Y1100111D02*
Y1102220D01*
X1504904Y1102221D01*
G01X1493803Y1112929D02*
X1493804Y1112930D01*
Y1115039D01*
G01X1506754Y1116133D02*
Y1118242D01*
X1506753Y1118243D01*
G01X1499354Y1116133D02*
Y1118242D01*
X1499353Y1118243D01*
G01X1497503Y1112929D02*
Y1115039D01*
G01X1495654Y1116133D02*
Y1118242D01*
X1495653Y1118243D01*
G01X1508603Y1112929D02*
Y1115039D01*
G01X1501203Y1112929D02*
X1501204Y1112930D01*
Y1115039D01*
G01X1504903Y1112929D02*
X1504904Y1112930D01*
Y1115039D01*
G01X1501203Y1119337D02*
X1501204Y1121447D01*
G01X1493803Y1119337D02*
X1493804Y1121447D01*
G01X1503054Y1116133D02*
Y1118242D01*
X1503053Y1118243D01*
G01X1506754Y1135359D02*
X1506860Y1135465D01*
Y1137363D01*
X1506754Y1137469D01*
G01Y1128950D02*
Y1131059D01*
X1506753Y1131060D01*
G01X1503054Y1128950D02*
Y1131059D01*
X1503053Y1131060D01*
G01X1499354Y1128950D02*
Y1131059D01*
X1499353Y1131060D01*
G01X1495654Y1128950D02*
Y1131059D01*
X1495653Y1131060D01*
G01X1504903Y1132154D02*
Y1134263D01*
X1504904Y1134264D01*
G01X1501203Y1132154D02*
Y1134263D01*
X1501204Y1134264D01*
G01X1493803Y1132154D02*
Y1134263D01*
X1493804Y1134264D01*
G01X1510878Y1367871D02*
X1509581Y1366574D01*
X1507751D01*
G01D02*
Y1364937D01*
X1510827Y1361861D01*
Y1361484D01*
G01X1514369Y308467D02*
X1514212Y308310D01*
Y305489D01*
G01X1515940Y795815D02*
X1516890Y796765D01*
X1519539D01*
X1552237Y764067D01*
Y736833D01*
X1555875Y733195D01*
X1561992D01*
X1562871Y732316D01*
G01X1515940Y799215D02*
X1516890Y798265D01*
X1520161D01*
X1553737Y764689D01*
Y737455D01*
X1556597Y734595D01*
X1561750D01*
X1562871Y735716D01*
G01X1511871Y847081D02*
Y844671D01*
G01X1513721Y850286D02*
Y848177D01*
X1513722Y848176D01*
G01X1521121Y863103D02*
Y860993D01*
G01Y869511D02*
Y867401D01*
G01X1510021Y875920D02*
Y873810D01*
G01X1522970Y872716D02*
X1522971Y870606D01*
G01X1511871Y885533D02*
Y883423D01*
G01X1510021Y893036D02*
Y895146D01*
G01Y899445D02*
Y901555D01*
G01X1511871Y889832D02*
Y891942D01*
G01X1517421Y895146D02*
X1513721Y893036D01*
G01X1517421Y888737D02*
Y886627D01*
G01X1521121Y888737D02*
Y886627D01*
G01X1513721Y888737D02*
Y886627D01*
G01X1522970Y891942D02*
X1526671Y889832D01*
G01X1517421Y901555D02*
X1513721Y899445D01*
G01X1510021Y888737D02*
Y886627D01*
G01Y912262D02*
Y914372D01*
G01X1522970Y911167D02*
X1524821Y912262D01*
G01X1511871Y909057D02*
Y911167D01*
G01Y904759D02*
Y902649D01*
G01X1517421Y914372D02*
X1513721Y912262D01*
G01X1517421Y907963D02*
X1515571Y909057D01*
G01X1522970Y904759D02*
X1524821Y905853D01*
G01X1513721D02*
Y907963D01*
G01X1521121D02*
X1519271Y909057D01*
G01X1510021Y933598D02*
X1510020Y933597D01*
Y931488D01*
G01X1511871Y930393D02*
Y928283D01*
G01X1521121Y927189D02*
X1519271Y928283D01*
G01X1517421Y927189D02*
X1515571Y928283D01*
G01X1517421Y920780D02*
X1513721Y918670D01*
G01X1522970Y923985D02*
X1524820Y925079D01*
G01X1522970Y930393D02*
X1524820Y931488D01*
G01X1517421Y933598D02*
X1513720Y931488D01*
G01X1510021Y937896D02*
Y940006D01*
G01X1511871Y943210D02*
Y941100D01*
G01X1517421Y940006D02*
X1513721Y937896D01*
G01X1522970Y943210D02*
X1523726D01*
X1524820Y944304D01*
G01X1513721Y946414D02*
Y944305D01*
X1513720Y944304D01*
G01X1511871Y947509D02*
Y949619D01*
G01X1522970D02*
X1525420D01*
G01X1521121Y946414D02*
X1519271Y947509D01*
G01X1517421Y946414D02*
X1515571Y947509D01*
G01X1510021Y957122D02*
Y959232D01*
G01Y950713D02*
Y952823D01*
G01X1522970Y962436D02*
X1525861D01*
G01X1511871D02*
Y960326D01*
G01X1517421Y959232D02*
X1513721Y957122D01*
G01X1517421Y952823D02*
X1513721Y950713D01*
G01Y965640D02*
X1511871Y966735D01*
G01X1517421Y965640D02*
X1513721Y963530D01*
G01X1510021Y978457D02*
Y976347D01*
G01X1511871Y981662D02*
X1510043Y980606D01*
G01X1510021Y969939D02*
X1511871Y968845D01*
G01X1517421Y978457D02*
X1515605Y979506D01*
X1515601Y979522D01*
X1515571Y979552D01*
G01X1510021Y972049D02*
X1511871Y973143D01*
G01X1517421Y972049D02*
Y969939D01*
G01X1513721Y984866D02*
Y982756D01*
G01X1517421Y984866D02*
X1519871D01*
G01X1517853Y1007187D02*
X1516004Y1006092D01*
G01X1516003Y1003983D02*
X1512303Y1006093D01*
G01X1521554Y1007187D02*
X1519705Y1006092D01*
G01X1517853Y1013595D02*
Y1015704D01*
X1517854Y1015705D01*
G01X1521554Y1013595D02*
Y1015705D01*
G01X1514154Y1013595D02*
Y1015705D01*
G01X1517853Y1026413D02*
X1516520Y1026103D01*
G01X1517853Y1020004D02*
X1516055Y1018942D01*
X1516023Y1018910D01*
X1516003D01*
G01X1523403Y1016800D02*
X1525140Y1016010D01*
X1525254Y1015705D01*
G01X1512303Y1016800D02*
Y1018910D01*
G01Y1031727D02*
Y1029617D01*
G01X1523403D02*
X1527102Y1031726D01*
X1527103D01*
G01X1510453Y1039230D02*
Y1041340D01*
G01Y1045639D02*
Y1047749D01*
G01X1523403Y1036026D02*
X1525254Y1034931D01*
G01X1521554Y1032821D02*
Y1034931D01*
G01X1516004Y1044544D02*
X1517853Y1045639D01*
G01Y1039230D02*
X1516116Y1038226D01*
X1516026Y1038136D01*
X1516003D01*
G01X1517853Y1032821D02*
Y1034931D01*
G01X1514154Y1032821D02*
X1514153Y1034931D01*
G01X1512303Y1038136D02*
Y1036026D01*
G01X1510453Y1060565D02*
Y1058455D01*
G01X1517853Y1052047D02*
Y1054157D01*
G01X1514154Y1052047D02*
Y1054156D01*
X1514153Y1054157D01*
G01X1512303Y1055251D02*
Y1057361D01*
G01X1521554Y1052047D02*
X1521553Y1054157D01*
G01X1517853Y1058455D02*
X1514153Y1060565D01*
G01X1512303Y1048842D02*
Y1050952D01*
G01X1519703Y1061660D02*
X1522779D01*
X1523515Y1061965D01*
X1525517Y1063967D01*
Y1064797D01*
X1525564Y1064844D01*
Y1064850D01*
G01X1510453Y1064864D02*
Y1066974D01*
G01Y1077681D02*
Y1079791D01*
G01X1521554Y1071273D02*
X1523404Y1070178D01*
G01X1512303Y1068068D02*
X1514153Y1066974D01*
G01X1519703Y1074477D02*
X1517853Y1073383D01*
G01X1519703Y1068068D02*
X1521553Y1066974D01*
G01X1517853Y1077681D02*
X1516116Y1076677D01*
X1516026Y1076587D01*
X1516003D01*
G01X1514154Y1071273D02*
X1512362Y1070213D01*
X1512349Y1070214D01*
X1512304Y1070178D01*
G01X1512303Y1074477D02*
X1514153Y1073383D01*
G01X1510453Y1084090D02*
Y1086200D01*
G01X1521554Y1084090D02*
X1523404Y1082996D01*
G01X1516003Y1080885D02*
X1512304Y1082996D01*
G01X1514154Y1090498D02*
Y1092607D01*
X1514153Y1092608D01*
G01X1512303Y1087294D02*
Y1089404D01*
G01X1519703Y1093703D02*
X1521553Y1092608D01*
G01X1521554Y1096907D02*
X1523403Y1095813D01*
G01X1517853Y1096907D02*
X1519703Y1095813D01*
G01X1512303Y1093703D02*
Y1095813D01*
G01X1510453Y1109724D02*
Y1111834D01*
G01Y1103316D02*
Y1105426D01*
G01X1517853Y1103316D02*
Y1105426D01*
G01Y1109724D02*
Y1111834D01*
G01X1514154Y1103316D02*
Y1105425D01*
X1514153Y1105426D01*
G01X1512303Y1106520D02*
Y1108630D01*
G01X1514154Y1109724D02*
Y1111833D01*
X1514153Y1111834D01*
G01X1519703Y1112929D02*
X1519780Y1113006D01*
Y1114963D01*
X1519704Y1115039D01*
G01X1516003Y1112929D02*
Y1115036D01*
X1516004Y1115037D01*
Y1115039D01*
G01X1512303Y1112929D02*
Y1115039D01*
G01X1517853Y1128950D02*
X1517990Y1129087D01*
Y1131424D01*
X1517854Y1131560D01*
G01X1510453Y1116133D02*
Y1118243D01*
G01X1517853Y1116133D02*
X1517960Y1116240D01*
Y1118136D01*
X1517853Y1118243D01*
G01X1512303Y1132154D02*
X1512460Y1132311D01*
Y1134108D01*
X1512304Y1134264D01*
G01X1514878Y1365553D02*
X1514938D01*
X1514939Y1365552D01*
X1516142Y1362646D01*
Y1361484D01*
G01X1510878Y1364815D02*
Y1364521D01*
X1512599Y1362800D01*
Y1361484D01*
G01X1543444Y197834D02*
X1537262D01*
G01X1557560Y196912D02*
X1558606Y195866D01*
X1566004D01*
G01Y197834D02*
X1558482D01*
X1557560Y196912D01*
G01X1559860Y240002D02*
X1560999Y241141D01*
X1566004D01*
G01Y239173D02*
X1560689D01*
X1559860Y240002D01*
G01X1566004Y243110D02*
X1559722D01*
G01X1563714Y572792D02*
X1565244Y574322D01*
Y579892D01*
X1563994Y581142D01*
G01X1567114Y572792D02*
X1566744Y573162D01*
Y579892D01*
X1567994Y581142D01*
G01X1559354Y655716D02*
X1560304Y656666D01*
X1561754D01*
X1563004Y655416D01*
G01Y659416D02*
X1561754Y658166D01*
X1560304D01*
X1559354Y659116D01*
G01X1562871Y732316D02*
X1563721Y733166D01*
X1564880D01*
X1565881Y732165D01*
G01X1562871Y735716D02*
X1563921Y734666D01*
X1564856D01*
X1565881Y735691D01*
G01X1624353Y1428766D02*
X1622855D01*
X1621725Y1429896D01*
X1620477D01*
G01Y1426366D02*
Y1429896D01*
G01Y1426366D02*
X1624353D01*
G01X1641082Y652601D02*
X1638657D01*
G01X1641082Y686601D02*
X1638657D01*
G01X1641082Y720601D02*
X1638657D01*
G01X1630643Y1440290D02*
X1632364Y1438569D01*
Y1436959D01*
G01X1627591Y1442005D02*
Y1440311D01*
X1630592Y1437310D01*
Y1436959D01*
G01X1630643Y1443090D02*
X1629558Y1442005D01*
X1627591D01*
G01X1652810Y407402D02*
X1653642Y408234D01*
Y410265D01*
G01X1645530Y549160D02*
Y546012D01*
X1649470Y542072D01*
X1655979D01*
X1657804Y540247D01*
Y540071D01*
G01X1649291Y549160D02*
X1645530D01*
G01X1656955Y611090D02*
X1655760D01*
X1654883Y610213D01*
G01X1647009D02*
Y611629D01*
X1646436Y612202D01*
X1645300D01*
G01D02*
X1645280D01*
X1645248Y612234D01*
Y614586D01*
X1645507Y614845D01*
G01X1653220Y615087D02*
X1650946Y612813D01*
Y610213D01*
G01X1653220Y618237D02*
X1652696D01*
X1649546Y615087D01*
X1649220D01*
G01D02*
Y612887D01*
X1648977Y612644D01*
Y610213D01*
G01X1653220Y620662D02*
Y618237D01*
G01X1657220Y615087D02*
X1656644D01*
X1652914Y611357D01*
Y610213D01*
G01X1652581Y646311D02*
X1652287D01*
X1650566Y644590D01*
X1649250D01*
G01X1653319Y642311D02*
Y642251D01*
X1653318Y642250D01*
X1650412Y641047D01*
X1649250D01*
G01X1654297Y649681D02*
X1652978D01*
X1649659Y646362D01*
X1649250D01*
G01X1655637Y646311D02*
X1654297Y647651D01*
Y649681D01*
G01X1652581Y680311D02*
X1650860Y678590D01*
X1649250D01*
G01X1653319Y676311D02*
Y676251D01*
X1653318Y676250D01*
X1650412Y675047D01*
X1649250D01*
G01X1655113Y680835D02*
X1654297Y681651D01*
Y683681D01*
G01D02*
X1652978D01*
X1649659Y680362D01*
X1649250D01*
G01X1652581Y714311D02*
X1652287D01*
X1650566Y712590D01*
X1649250D01*
G01X1653319Y710311D02*
Y710251D01*
X1653318Y710250D01*
X1650412Y709047D01*
X1649250D01*
G01X1655637Y714311D02*
X1654297Y715651D01*
Y717681D01*
G01D02*
X1652978D01*
X1649659Y714362D01*
X1649250D01*
G01X1657804Y528071D02*
Y524071D01*
G01D02*
Y520589D01*
X1657755Y520540D01*
G01D02*
Y517910D01*
G01X1662262Y537334D02*
X1662412D01*
X1663468Y536278D01*
G01X1659172Y534703D02*
X1657804Y536071D01*
G01Y528071D02*
X1658499Y528766D01*
X1659999D01*
G01X1657804Y532071D02*
X1660243D01*
G01D02*
X1661246D01*
G01X1664251Y545625D02*
Y546439D01*
X1661728Y548962D01*
Y550382D01*
G01X1668917Y549992D02*
Y548575D01*
G01X1657804Y544622D02*
X1660379D01*
X1660386Y544629D01*
G01X1657632Y553489D02*
X1657602Y553519D01*
Y558097D01*
G01X1661728Y550382D02*
X1657675D01*
X1657632Y550339D01*
G01X1666902Y555115D02*
Y552406D01*
X1664878Y550382D01*
G01X1666555Y544152D02*
Y548705D01*
X1664878Y550382D01*
G01X1663502Y555115D02*
Y558097D01*
G01X1662120Y604782D02*
X1661711Y604373D01*
X1659041D01*
X1658680Y604012D01*
X1657107D01*
G01X1660754Y609837D02*
X1658866Y607949D01*
X1657107D01*
G01X1663471Y609837D02*
X1663010Y609376D01*
Y609062D01*
X1661847Y607899D01*
Y607291D01*
G01X1657107Y605980D02*
X1659738D01*
X1661049Y607291D01*
X1661847D01*
G01X1662785Y598522D02*
X1660885D01*
X1660469Y598106D01*
X1657107D01*
G01X1662756Y594959D02*
X1659455D01*
X1658276Y596138D01*
X1657107D01*
G01X1668786Y1443256D02*
X1668213D01*
X1666962Y1442005D01*
X1665734D01*
G01X1689943Y479304D02*
X1688020D01*
X1687506Y478790D01*
G01Y482790D02*
X1688451Y481845D01*
X1690229D01*
G01X1681612Y499290D02*
X1684356D01*
G01X1687506D02*
Y503244D01*
X1685935Y504815D01*
G01X1681817Y495290D02*
X1684356D01*
G01X1688431Y545589D02*
X1692349Y549507D01*
X1693701D01*
G01X1683091Y547012D02*
X1686644Y550565D01*
Y552241D01*
G01D02*
X1690021D01*
X1690080Y552182D01*
G01X1683369Y562698D02*
X1684319Y563648D01*
X1686354D01*
X1686920Y563082D01*
Y557245D01*
X1683494Y553819D01*
Y552241D01*
G01X1681516Y549707D02*
X1683494Y551685D01*
Y552241D01*
G01X1683369Y566098D02*
X1684345Y565122D01*
X1688550D01*
X1690028Y566600D01*
G01X1709590Y374282D02*
X1707850Y372542D01*
X1706100D01*
X1704869Y373773D01*
G01X1709590Y369282D02*
X1707830Y371042D01*
X1706138D01*
X1704869Y369773D01*
G01X1707544Y431745D02*
Y429101D01*
X1706543Y428100D01*
X1704624D01*
G01X1698592Y561310D02*
X1693701Y556419D01*
Y553527D01*
G01Y549507D02*
Y553527D01*
G01X1690028Y560700D02*
X1690080Y555332D01*
G01X1700845Y691730D02*
Y688130D01*
G01X1703995Y691730D02*
Y688130D01*
G01D02*
X1704270Y687855D01*
X1707708D01*
X1708030Y688177D01*
G01Y691327D02*
X1704027Y695330D01*
X1703995D01*
G01X1703768Y698831D02*
Y695557D01*
X1703995Y695330D01*
G01X1700845Y691730D02*
Y695330D01*
G01X1703413Y706796D02*
Y706422D01*
X1702669Y705678D01*
X1701320D01*
G01D02*
Y697913D01*
X1700845Y697438D01*
Y695330D01*
G01X1735178Y85427D02*
X1719188D01*
X1715188Y89427D01*
Y102389D01*
X1718608Y105809D01*
G01X1720670Y125092D02*
X1721418D01*
G01X1717418D02*
X1716910Y124584D01*
Y120432D01*
G01D02*
X1718360D01*
X1720670Y122742D01*
Y125092D01*
G01X1713418D02*
X1707990D01*
X1705120Y127962D01*
Y140662D01*
X1708890Y144432D01*
Y149140D01*
X1711560Y151810D01*
X1720962D01*
X1723670Y149102D01*
G01X1710268Y128242D02*
Y134558D01*
X1717140Y141430D01*
Y148910D01*
G01X1717418Y135327D02*
Y128242D01*
G01X1717765Y364962D02*
X1717000Y364197D01*
Y361824D01*
X1718182Y360642D01*
X1719968D01*
X1724348Y365022D01*
X1727793D01*
X1728496Y365725D01*
Y366447D01*
X1729480Y367431D01*
G01X1714615Y364962D02*
X1715500Y364077D01*
Y361202D01*
X1717560Y359142D01*
X1720590D01*
X1724970Y363522D01*
X1728491D01*
X1729234Y364265D01*
X1729956D01*
X1730333Y363888D01*
X1731055D01*
X1732039Y364872D01*
G01X1717765Y364962D02*
X1716940Y365787D01*
Y369983D01*
X1714391Y372532D01*
X1711340D01*
X1709590Y374282D01*
G01X1714615Y364962D02*
X1715440Y365787D01*
Y369361D01*
X1713769Y371032D01*
X1711340D01*
X1709590Y369282D01*
G01X1717686Y502552D02*
X1717866Y502732D01*
Y507391D01*
G01X1713655Y499412D02*
X1713705Y499362D01*
X1717646D01*
X1717686Y499402D01*
G01X1707552Y503331D02*
X1708502Y504281D01*
X1710357D01*
X1711220Y503418D01*
Y502020D01*
X1710596Y501396D01*
Y499503D01*
X1710505Y499412D01*
G01X1707552Y506731D02*
X1708502Y505781D01*
X1710356D01*
X1711966Y507391D01*
G01X1713159Y688200D02*
X1713136Y688177D01*
X1708030D01*
G01X1717880Y687680D02*
X1715980D01*
X1715460Y688200D01*
X1713159D01*
G01X1722580Y688211D02*
X1721080D01*
X1720549Y687680D01*
X1717880D01*
G01X1710550Y691327D02*
X1708030D01*
G01X1713159Y691350D02*
X1716420D01*
X1716480Y691410D01*
G01X1714320Y704687D02*
X1714115D01*
X1712120Y706682D01*
Y710928D01*
X1710543Y712505D01*
X1707743D01*
G01X1708137Y716442D02*
X1708437Y716742D01*
X1708773D01*
X1709828Y717797D01*
Y719283D01*
G01D02*
Y721489D01*
X1709107Y722210D01*
G01X1714298Y711540D02*
Y709515D01*
X1714320Y709493D01*
Y707837D01*
G01X1735642Y116439D02*
Y118868D01*
X1729418Y125092D01*
G01X1733118Y128577D02*
Y125123D01*
X1737611Y120630D01*
Y116439D01*
G01X1725418Y125092D02*
X1721418D01*
G01X1729418D02*
X1725418D01*
G01X1721418Y135327D02*
Y128242D01*
G01X1729480Y373337D02*
X1727325D01*
G01X1726425Y368787D02*
X1727038Y369400D01*
X1729480D01*
G01X1757530Y689800D02*
Y688300D01*
X1756750Y687520D01*
X1727222D01*
X1726531Y688211D01*
X1725730D01*
G01X1814537Y1322105D02*
X1789299Y1347343D01*
Y1352463D01*
X1780687Y1361075D01*
X1742227D01*
X1735947Y1354795D01*
Y1317185D01*
X1737104Y1316028D01*
X1743069D01*
G01X1750500Y296962D02*
X1752500Y294962D01*
Y294363D01*
X1754432Y292431D01*
X1756177D01*
G01X1749450Y293862D02*
X1750500Y294912D01*
Y296962D01*
G01X1745000Y290962D02*
X1746600Y289362D01*
X1749308D01*
X1751222Y291276D01*
G01X1745000Y290962D02*
Y287973D01*
X1746366Y286607D01*
G01X1751222Y291276D02*
X1752035Y290463D01*
X1756177D01*
G01X1758352Y1317368D02*
X1755961D01*
X1754621Y1316028D01*
X1753305D01*
G01X1758352Y1322168D02*
X1756044D01*
X1754704Y1323508D01*
X1753305D01*
G01X1767455Y302651D02*
X1768382Y301724D01*
Y298829D01*
G01X1764955Y301951D02*
X1766413Y300493D01*
Y298829D01*
G01X1758539Y298879D02*
Y300083D01*
X1760104Y301648D01*
G01X1770350Y298829D02*
Y303722D01*
X1769230Y304842D01*
G01X1765663D02*
X1762163D01*
G01X1769230D02*
X1768913Y305159D01*
X1765980D01*
X1765663Y304842D01*
G01X1760104Y301648D02*
X1759732Y302020D01*
Y303673D01*
X1758563Y304842D01*
G01X1769097Y1310081D02*
Y1318446D01*
X1768525Y1319018D01*
X1760002D01*
X1758352Y1317368D01*
G01X1769097Y1331341D02*
Y1321194D01*
X1768421Y1320518D01*
X1760002D01*
X1758352Y1322168D01*
G01X1755860Y1495412D02*
X1770010D01*
X1774550Y1490872D01*
X1808216D01*
X1809716Y1492372D01*
Y1494318D01*
G01X1772319Y298879D02*
Y299970D01*
X1777598Y305249D01*
Y308286D01*
G01X1779868Y299243D02*
X1776038D01*
X1774731Y297936D01*
Y296368D01*
G01X1779868Y295643D02*
Y294993D01*
X1777306Y292431D01*
X1774681D01*
G01X1779853Y291876D02*
X1778440Y290463D01*
X1774681D01*
G01X1783003Y291876D02*
X1783018Y291891D01*
Y295643D01*
G01X1777598Y308286D02*
X1776905D01*
X1773461Y304842D01*
X1772863D01*
G01X1780667Y303994D02*
Y303648D01*
X1779868Y302849D01*
Y299243D01*
G01X1795857Y1521592D02*
Y1524433D01*
X1795561Y1524729D01*
G01X1809716Y1498318D02*
Y1494318D01*
G01X1806566D02*
Y1498318D01*
G01D02*
Y1498622D01*
X1809716Y1501772D01*
Y1502387D01*
G01D02*
Y1503109D01*
X1807150Y1505675D01*
G01Y1506354D02*
Y1505675D01*
G54D52*
X91949Y702670D03*
X1705381Y706796D03*
G54D16*
X17016Y193362D03*
Y200362D03*
X27736Y232362D03*
Y240362D03*
X33001Y401000D03*
X57123Y421746D03*
X59290Y1524094D03*
Y1532094D03*
Y1528194D03*
Y1548094D03*
Y1552094D03*
Y1544094D03*
Y1556094D03*
X78007Y436519D03*
Y432519D03*
X81890Y391391D03*
Y395865D03*
Y382219D03*
X88317Y428319D03*
Y424319D03*
Y420319D03*
Y450519D03*
Y446519D03*
X87656Y667734D03*
X88551Y718879D03*
X93204Y1593867D03*
Y1585852D03*
Y1589852D03*
X93279Y1611821D03*
Y1605867D03*
Y1623821D03*
X93189Y1634362D03*
Y1638362D03*
X88736Y1690362D03*
X96671Y169263D03*
X107941Y232128D03*
X104936Y493578D03*
X104966Y497374D03*
Y501374D03*
Y505374D03*
Y509374D03*
Y513374D03*
X96030Y512870D03*
X95836Y696262D03*
X107290Y1528594D03*
Y1532694D03*
Y1552594D03*
Y1556594D03*
X96516Y1655800D03*
Y1651800D03*
X123935Y278875D03*
X123916Y274800D03*
X123935Y306236D03*
X127498Y396071D03*
Y388071D03*
Y392071D03*
Y384071D03*
X116998Y404571D03*
X124254Y636153D03*
Y640103D03*
X119574Y1589352D03*
X124354Y1604367D03*
X125074Y1622321D03*
X124074Y1637862D03*
X121736Y1696362D03*
X127573Y1723182D03*
X131466Y525374D03*
X130053Y1535855D03*
X130205Y1541874D03*
X130297Y1547935D03*
X140836Y1708362D03*
X138583Y1720092D03*
X158416Y413362D03*
X144013Y510810D03*
Y514810D03*
Y518810D03*
Y526830D03*
X152824Y519281D03*
X148236Y1716362D03*
X175083Y1723592D03*
X181912Y421383D03*
Y425383D03*
Y443383D03*
Y430883D03*
X191158Y689683D03*
X182083Y1729092D03*
Y1733092D03*
X204907Y567981D03*
X197081Y584791D03*
X204907Y601981D03*
X197081Y618791D03*
X204907Y635981D03*
X197081Y652791D03*
X193686Y675092D03*
X192966Y1535377D03*
X192907Y1539678D03*
X192799Y1548430D03*
X192707Y1552940D03*
X205236Y1709862D03*
X205134Y1714017D03*
X212070Y420735D03*
Y424735D03*
Y428735D03*
Y436735D03*
Y432735D03*
Y440735D03*
Y444735D03*
Y448735D03*
Y457222D03*
Y462235D03*
X222729Y1322859D03*
Y1326859D03*
X234216Y142062D03*
X230536Y159071D03*
X242236Y75862D03*
X247313Y115743D03*
X246524Y565976D03*
X246981Y598632D03*
X246682Y633848D03*
X242534Y703397D03*
X258997Y64455D03*
X258949Y60345D03*
X258952Y56160D03*
X257813Y87543D03*
X267069Y151203D03*
Y147203D03*
X270836Y210822D03*
X266600Y439605D03*
X266570Y451735D03*
Y447735D03*
X283816Y136962D03*
X282549Y229606D03*
X275516Y451862D03*
Y447862D03*
X287036Y569548D03*
Y566022D03*
X289636Y634283D03*
Y630757D03*
X287910Y685071D03*
Y688597D03*
X295433Y67513D03*
X295943Y85983D03*
Y82483D03*
X302173Y91767D03*
X305116Y146702D03*
X290716Y139162D03*
X306235Y599318D03*
X317073Y95803D03*
X317119Y99837D03*
X320916Y161562D03*
X314990Y228258D03*
X320325Y559218D03*
X314741Y595998D03*
X336716Y141862D03*
X347554Y142869D03*
X353236Y225862D03*
X346713Y705779D03*
X385676Y119822D03*
Y132822D03*
X378736Y217362D03*
Y208862D03*
Y212862D03*
Y221362D03*
Y225362D03*
X384856Y1622722D03*
X395448Y1398653D03*
X403415Y1411231D03*
X399437Y1537810D03*
Y1545810D03*
Y1560810D03*
Y1564810D03*
X404566Y1549942D03*
X411216Y1603500D03*
Y1615200D03*
X418716Y1616600D03*
X418666Y1620402D03*
X418631Y1624692D03*
Y1628692D03*
Y1632842D03*
X419226Y1643159D03*
X419246Y1647216D03*
X418631Y1636842D03*
X412736Y1672362D03*
Y1676362D03*
Y1668362D03*
X429937Y1547810D03*
Y1551810D03*
X427061Y1583466D03*
X446872Y145710D03*
X445344Y505483D03*
Y509483D03*
Y513483D03*
Y517483D03*
Y521483D03*
Y525483D03*
Y542519D03*
Y547519D03*
X450536Y1547437D03*
X441399Y1600154D03*
X456655Y120948D03*
X455016Y213362D03*
Y222362D03*
X468363Y1400435D03*
X468332Y1396606D03*
X466429Y1610682D03*
Y1603682D03*
X466386Y1622735D03*
X466476Y1626732D03*
X471376Y1631003D03*
X471316Y1634947D03*
X472446Y1647242D03*
Y1663242D03*
X472376Y1677462D03*
Y1681462D03*
X485689Y66565D03*
X485799Y61205D03*
X485959Y55895D03*
X489352Y309398D03*
X498676Y615612D03*
X490372Y1424033D03*
X517341Y168443D03*
X507016Y223362D03*
X502516Y241862D03*
X516916Y489112D03*
X516102Y500469D03*
Y505969D03*
X516916Y495112D03*
X516102Y511469D03*
Y516969D03*
Y522469D03*
Y527969D03*
Y539819D03*
X515516Y615742D03*
X506187Y1422494D03*
X518826Y455062D03*
X526906Y500222D03*
X536356Y99172D03*
X536416Y112512D03*
X549736Y161362D03*
Y184862D03*
Y171862D03*
X536580Y269472D03*
X535466Y454270D03*
X564516Y102862D03*
Y98862D03*
X552486Y127788D03*
Y137774D03*
Y153878D03*
X566605Y310847D03*
X565341Y424392D03*
X565033Y446706D03*
X570056Y157932D03*
X579366Y157684D03*
X581972Y194378D03*
X581736Y230862D03*
X570736Y225362D03*
Y221362D03*
X577586Y493212D03*
Y488212D03*
Y497212D03*
X567586Y1355247D03*
Y1358777D03*
X592336Y136314D03*
Y125314D03*
X596271Y159480D03*
X588668Y288527D03*
X609851Y184062D03*
X599736Y416362D03*
X601736Y444362D03*
Y449362D03*
X599915Y454600D03*
X600736Y506862D03*
Y510862D03*
X631433Y88039D03*
Y92119D03*
X625552Y208076D03*
Y212076D03*
X627736Y234362D03*
Y230362D03*
X631736Y416362D03*
X617736Y426362D03*
X631736Y472862D03*
Y477862D03*
Y467862D03*
X616736Y472862D03*
Y477862D03*
Y462862D03*
Y467862D03*
X645160Y140699D03*
Y149871D03*
Y154345D03*
X646236Y184862D03*
X639650Y249202D03*
Y260202D03*
X637661Y294327D03*
Y290267D03*
Y306547D03*
X646736Y411362D03*
Y421362D03*
Y426362D03*
Y477862D03*
Y472862D03*
Y482862D03*
X633236Y526362D03*
X642236Y1714362D03*
Y1726362D03*
X680469Y119568D03*
Y123420D03*
X665534Y1647557D03*
X665609Y1659557D03*
X665636Y1664862D03*
Y1676862D03*
X668736Y1712362D03*
Y1728362D03*
X690736Y76962D03*
X690969Y91668D03*
X691738Y1640667D03*
X691663Y1636667D03*
X692136Y1662862D03*
Y1678862D03*
X710236Y221862D03*
X704628Y1567683D03*
Y1579683D03*
Y1571683D03*
Y1575683D03*
Y1587683D03*
Y1595683D03*
Y1591683D03*
X711649Y1680400D03*
X723649Y160788D03*
X720461Y1564088D03*
X719768Y1569493D03*
X726768D03*
X727869Y1614503D03*
X727768Y1609893D03*
X718849Y1680400D03*
X730009Y86998D03*
X730519Y101968D03*
X738249Y111252D03*
X730519Y105468D03*
X745761Y137864D03*
X745171Y1682362D03*
Y1678362D03*
X751649Y115288D03*
X751651Y119172D03*
X748176Y265322D03*
Y269322D03*
X760736Y413212D03*
Y403212D03*
Y408212D03*
Y398212D03*
X759856Y459862D03*
Y454862D03*
Y474862D03*
X759916Y493452D03*
X762036Y1384062D03*
Y1401562D03*
Y1397262D03*
X761936Y1414762D03*
X754628Y1583183D03*
X760731Y1698521D03*
X774936Y163254D03*
X772957Y308755D03*
X773042Y303410D03*
X775736Y393212D03*
X774856Y454862D03*
Y459862D03*
X762136Y1379962D03*
Y1375462D03*
X765655Y1573793D03*
X765668Y1581893D03*
Y1577893D03*
Y1590893D03*
X779676Y274822D03*
X786142Y303410D03*
X786057Y308755D03*
X788016Y385300D03*
X789936Y398212D03*
X789856Y444862D03*
Y439862D03*
Y449862D03*
Y454862D03*
Y459862D03*
Y469862D03*
X805586Y441060D03*
Y445100D03*
X805356Y454862D03*
Y459862D03*
Y449862D03*
Y464862D03*
X807168Y1573793D03*
Y1581793D03*
Y1597793D03*
Y1585793D03*
Y1605793D03*
X817816Y449200D03*
X825016D03*
X819356Y476800D03*
Y464862D03*
Y468900D03*
Y472900D03*
X824286Y511082D03*
Y506082D03*
Y527082D03*
Y519082D03*
X837341Y90451D03*
X839236Y135862D03*
Y129362D03*
X827493Y409260D03*
Y405260D03*
X848736Y129362D03*
Y135862D03*
X858108Y240441D03*
X856319Y265057D03*
X843763Y271049D03*
X856829Y280027D03*
Y283527D03*
X859516Y378362D03*
X849416Y473000D03*
Y469100D03*
X857136Y507162D03*
Y495300D03*
X849168Y1573793D03*
Y1581793D03*
Y1597793D03*
Y1585793D03*
Y1605793D03*
X871236Y171362D03*
Y176862D03*
X866016Y196500D03*
X865409Y227763D03*
Y223763D03*
X864559Y289311D03*
X865002Y386476D03*
Y402581D03*
Y398620D03*
X865054Y414276D03*
X881316Y201150D03*
Y195720D03*
X881241Y192055D03*
X877959Y293347D03*
X877982Y298665D03*
X891838Y874405D03*
X891168Y1573793D03*
Y1581793D03*
Y1597793D03*
Y1585793D03*
Y1605793D03*
X899369Y484913D03*
Y480913D03*
X899164Y493299D03*
Y489299D03*
X899149Y501573D03*
Y497573D03*
X892408Y920325D03*
X905005Y975134D03*
Y971234D03*
Y992834D03*
Y988934D03*
X933168Y1593393D03*
X943431Y184912D03*
X943351Y188852D03*
X948575Y424298D03*
X948498Y428124D03*
X948471Y437844D03*
X948548Y434018D03*
X945826Y997422D03*
X970109Y356896D03*
X982440Y171483D03*
X991516Y148299D03*
X998516D03*
X994428Y213233D03*
X1000826Y363352D03*
X1009892Y167278D03*
Y171278D03*
X1015106Y190176D03*
X1014986Y363222D03*
X1034349Y268264D03*
X1038385Y509606D03*
X1027794Y523628D03*
Y514176D03*
X1036126Y523642D03*
X1036546Y514182D03*
X1070937Y265574D03*
X1069671Y386723D03*
X1084237Y69602D03*
X1079205Y83698D03*
X1080126Y379251D03*
X1080006Y369061D03*
X1080066Y374131D03*
X1088306Y1670963D03*
X1104188Y60028D03*
X1110535Y72803D03*
Y77559D03*
X1134658Y1555301D03*
X1136066Y1597630D03*
Y1601630D03*
X1149053Y73679D03*
X1150596Y363231D03*
X1150526Y368041D03*
X1149198Y1626280D03*
X1168387Y61311D03*
Y65811D03*
X1168407Y57111D03*
X1157536Y211370D03*
X1182316Y111600D03*
X1175761Y194174D03*
Y190174D03*
Y206174D03*
Y210174D03*
Y222174D03*
X1195316Y97400D03*
Y89000D03*
Y101600D03*
X1195504Y212648D03*
X1197491Y240672D03*
Y244692D03*
X1194011Y1359636D03*
Y1363146D03*
X1213117Y53860D03*
X1204277Y61060D03*
X1208716Y93600D03*
X1216516D03*
X1209916Y113200D03*
X1217109Y119462D03*
Y132962D03*
X1217113Y148909D03*
Y144909D03*
X1217109Y153962D03*
Y157962D03*
Y168962D03*
X1208609Y164962D03*
X1217109D03*
Y176962D03*
X1208609D03*
X1217095Y172945D03*
X1210035Y171611D03*
X1217236Y194862D03*
X1207736Y200309D03*
Y195362D03*
X1203601Y1681767D03*
X1232906Y102608D03*
X1223010Y113982D03*
X1232907Y106609D03*
X1228627Y129409D03*
X1228609Y134262D03*
Y153115D03*
Y141110D03*
Y163462D03*
Y156962D03*
Y177962D03*
X1242398Y95008D03*
X1239109Y209462D03*
Y205862D03*
Y213462D03*
Y217462D03*
X1248109Y233462D03*
Y223462D03*
Y227462D03*
Y237462D03*
Y241462D03*
X1234876Y244332D03*
Y248332D03*
X1278807Y102928D03*
X1267270Y92724D03*
X1297527Y85138D03*
X1302550Y68562D03*
X1316316Y261662D03*
X1370132Y1403458D03*
X1370189Y1399053D03*
X1379556Y1411231D03*
X1370132Y1407458D03*
X1381153Y1415495D03*
X1394924Y1565037D03*
X1395098Y1576097D03*
X1394924Y1570037D03*
X1395416Y1609522D03*
X1405949Y1516435D03*
X1406189Y1532255D03*
X1405949Y1521335D03*
X1397116Y1521362D03*
X1406339Y1543475D03*
X1406189Y1537155D03*
X1406339Y1548375D03*
X1397016Y1537162D03*
Y1548362D03*
X1399416Y1582500D03*
Y1594000D03*
X1402516Y1630362D03*
Y1642362D03*
X1421399Y227948D03*
X1414916Y1593700D03*
X1424266Y1612812D03*
X1428516Y1637362D03*
X1441216Y60062D03*
X1441938Y1400204D03*
X1441972Y1396269D03*
X1440916Y1598400D03*
Y1611000D03*
X1436316Y1624500D03*
Y1628700D03*
X1451783Y1526689D03*
X1452023Y1542509D03*
X1452173Y1553729D03*
X1450176Y1590302D03*
X1471083Y64355D03*
X1466513Y1424033D03*
X1484899Y233448D03*
X1484601Y255378D03*
X1482316Y421982D03*
X1482328Y1422494D03*
X1502474Y280056D03*
X1526174Y150651D03*
X1517084Y231116D03*
Y239116D03*
Y249698D03*
Y262616D03*
X1516774Y280956D03*
X1517016Y272362D03*
X1517154Y268214D03*
X1516774Y288956D03*
X1532516Y125362D03*
Y121362D03*
X1537855Y310487D03*
X1546904Y127781D03*
X1550253Y634165D03*
X1560808Y651039D03*
X1589016Y199362D03*
X1588855Y256244D03*
X1597432Y1411169D03*
Y1415669D03*
Y1424669D03*
Y1429169D03*
Y1442669D03*
Y1447153D03*
X1636697Y624475D03*
X1635598Y652601D03*
X1636697Y658475D03*
X1635598Y686601D03*
X1636697Y692475D03*
X1635598Y720601D03*
X1641971Y180460D03*
X1644626Y414202D03*
X1654745Y524071D03*
X1654696Y520540D03*
X1654745Y528071D03*
Y532071D03*
Y540071D03*
Y536071D03*
X1642448Y614845D03*
X1653916Y631703D03*
X1654388Y649681D03*
X1653916Y665703D03*
X1654388Y683681D03*
X1653916Y699703D03*
X1654388Y717681D03*
X1660461Y195935D03*
X1662847Y594959D03*
X1661938Y607291D03*
X1668614Y1497362D03*
Y1512862D03*
Y1505362D03*
Y1524862D03*
Y1537862D03*
Y1541862D03*
Y1553557D03*
X1668689Y1565557D03*
Y1585321D03*
X1687149Y424694D03*
X1686011Y473878D03*
Y469878D03*
X1686036Y465940D03*
X1684447Y478790D03*
Y482790D03*
Y488290D03*
X1680004Y491790D03*
X1683585Y552241D03*
X1692520Y401485D03*
X1693792Y518107D03*
Y513107D03*
Y541507D03*
Y537507D03*
X1704551Y531613D03*
X1693792Y545507D03*
Y553527D03*
X1701983Y723005D03*
X1699264Y1500862D03*
Y1520362D03*
Y1541362D03*
X1699544Y1564057D03*
X1700264Y1583821D03*
X1711796Y165909D03*
X1711845Y161900D03*
Y157892D03*
X1711796Y170326D03*
X1715043Y424340D03*
Y420340D03*
X1719945Y490869D03*
Y486869D03*
Y482869D03*
Y494869D03*
X1710596Y499412D03*
X1707436Y701062D03*
X1720665Y1496270D03*
X1732310Y61639D03*
X1732358Y65749D03*
X1732313Y57454D03*
X1733134Y88787D03*
X1722434Y116867D03*
X1726550Y181234D03*
X1726381Y177072D03*
Y173072D03*
X1727895Y490869D03*
Y486869D03*
Y480669D03*
X1751175Y187509D03*
X1751103Y364048D03*
X1751236Y377452D03*
X1751103Y368048D03*
X1751236Y382952D03*
X1760554Y68637D03*
X1761064Y83607D03*
Y87107D03*
X1768794Y92891D03*
X1764943Y364148D03*
X1764736Y372452D03*
X1764943Y368148D03*
X1764736Y377452D03*
X1770067Y461393D03*
Y465893D03*
Y470193D03*
X1782194Y96927D03*
X1782152Y100939D03*
X1771891Y173903D03*
Y178403D03*
X1799815Y161465D03*
X1788904Y1506538D03*
X1815815Y413432D03*
Y417432D03*
X1822703Y170162D03*
X1829395Y399185D03*
X1823855Y434202D03*
X1832467Y453921D03*
X1832457Y467321D03*
Y463193D03*
X1842976Y172187D03*
X1835821Y192678D03*
G54D253*
X1004868Y190419D03*
G54D280*
X1268043Y132212D03*
G54D244*
X953235Y977250D03*
Y985596D03*
X959535Y977250D03*
Y985596D03*
G54D226*
X841742Y105951D03*
Y99651D03*
X850088Y105951D03*
Y99651D03*
X970738Y344659D03*
Y350959D03*
X979084Y344659D03*
Y350959D03*
G54D235*
X900589Y175197D03*
X945077Y155216D03*
G54D190*
X518430Y291864D03*
Y305446D03*
G54D271*
X1145335Y1605511D03*
Y1608070D03*
Y1610630D03*
Y1613189D03*
X1163839D03*
Y1610630D03*
Y1608070D03*
Y1605511D03*
G54D307*
X1714066Y507391D03*
G54D208*
X724465Y1581092D03*
Y1589950D03*
G54D163*
X400317Y120793D03*
Y129061D03*
X417443Y120793D03*
Y129061D03*
X842562Y168064D03*
Y176332D03*
X859688Y168064D03*
Y176332D03*
X1049186Y509790D03*
Y518058D03*
X1066312Y509790D03*
Y518058D03*
X1742907Y171733D03*
Y180001D03*
X1760033D03*
Y171733D03*
G54D43*
X75896Y442183D03*
X81696D03*
X108613Y531500D03*
X180867Y416827D03*
X186667D03*
X251487Y92733D03*
X257287D03*
Y97633D03*
X251487D03*
X401849Y1385910D03*
X684643Y96858D03*
X690443D03*
Y101758D03*
X684643D03*
X1034669Y373577D03*
X1034569Y367944D03*
X1040469Y373577D03*
X1040369Y367944D03*
X1321537Y255966D03*
X1327337D03*
X1377990Y1385910D03*
X1657602Y558097D03*
X1717866Y507391D03*
X1726608Y93857D03*
X1732408D03*
Y98757D03*
X1726608D03*
G54D154*
X335787Y981803D03*
X337638Y985007D03*
X336220Y1113070D03*
Y1119478D03*
Y1125887D03*
X338070Y1116274D03*
Y1122682D03*
Y1129091D03*
X339920Y1119478D03*
Y1125887D03*
X341771Y1122682D03*
Y1129091D03*
X343620Y1125887D03*
X345470Y1129091D03*
X347320Y1132295D03*
X349171Y1135500D03*
X343620Y1132295D03*
X345470Y1135500D03*
X532169Y846940D03*
X534020Y850145D03*
X535870Y846940D03*
X537720Y850145D03*
X535870Y853349D03*
X537720Y856553D03*
X539569Y853349D03*
Y859758D03*
X541420Y856553D03*
Y862962D03*
X543270Y853349D03*
Y859758D03*
Y866166D03*
X545120Y856553D03*
Y862962D03*
X546969Y866166D03*
X545120Y869370D03*
X546969Y872575D03*
X1311929Y981803D03*
X1313780Y985007D03*
X1312362Y1113070D03*
Y1119478D03*
Y1125887D03*
X1314212Y1116274D03*
Y1122682D03*
Y1129091D03*
X1316062Y1119478D03*
Y1125887D03*
X1317913Y1122682D03*
Y1129091D03*
X1319762Y1125887D03*
X1321612Y1129091D03*
X1323462Y1132295D03*
X1325313Y1135500D03*
X1319762Y1132295D03*
X1321612Y1135500D03*
X1508311Y846940D03*
X1510162Y850145D03*
X1512012Y846940D03*
X1513862Y850145D03*
X1512012Y853349D03*
X1513862Y856553D03*
X1515711Y853349D03*
Y859758D03*
X1517562Y856553D03*
Y862962D03*
X1519412Y853349D03*
Y859758D03*
Y866166D03*
X1521262Y856553D03*
Y862962D03*
X1523111Y866166D03*
X1521262Y869370D03*
X1523111Y872575D03*
G54D172*
X435262Y55016D03*
Y60016D03*
Y65016D03*
Y70016D03*
X456128Y55016D03*
Y70016D03*
Y65016D03*
Y60016D03*
X1138512Y52926D03*
Y57926D03*
Y62926D03*
Y67926D03*
X1159378Y52926D03*
Y67926D03*
Y62926D03*
Y57926D03*
G54D25*
X45876Y384395D03*
Y386364D03*
Y388333D03*
Y390301D03*
Y392269D03*
Y394238D03*
Y396207D03*
X64872D03*
Y394238D03*
Y392269D03*
Y390301D03*
Y388333D03*
Y386364D03*
Y384395D03*
X609146Y142875D03*
Y144844D03*
Y146813D03*
Y148781D03*
Y150749D03*
Y152718D03*
Y154687D03*
X628142Y152718D03*
Y150749D03*
Y148781D03*
Y146813D03*
Y144844D03*
Y142875D03*
Y154687D03*
G54D61*
X84430Y1310256D03*
X1093936Y1591739D03*
X1769097Y1308506D03*
G54D34*
X61057Y64434D03*
Y62334D03*
X72057Y70434D03*
Y68334D03*
X75657Y70434D03*
Y68334D03*
X64657Y64434D03*
Y62334D03*
X94057Y70434D03*
Y68334D03*
X86657Y64434D03*
Y62334D03*
X83057Y64434D03*
Y62334D03*
X105057Y64434D03*
Y62334D03*
X108657Y64434D03*
Y62334D03*
X97657Y70434D03*
Y68334D03*
X127057Y64434D03*
Y62334D03*
X119657Y70434D03*
Y68334D03*
X116057Y70434D03*
Y68334D03*
X130657Y64434D03*
Y62334D03*
X141657Y70434D03*
Y68334D03*
X138057Y70434D03*
Y68334D03*
X149057Y64434D03*
Y62334D03*
X152657Y64434D03*
Y62334D03*
X172261Y64434D03*
Y62334D03*
X175861Y64434D03*
Y62334D03*
X164861Y70434D03*
Y68334D03*
X161261Y70434D03*
Y68334D03*
X186861Y70434D03*
Y68334D03*
X183261Y70434D03*
Y68334D03*
X188797Y1583088D03*
X192397D03*
X188797Y1585188D03*
X192397D03*
X194261Y64434D03*
Y62334D03*
X197861Y64434D03*
Y62334D03*
X205395Y70434D03*
Y68334D03*
X200857Y1583088D03*
X204457D03*
X200857Y1585188D03*
X204457D03*
X206157Y1607286D03*
Y1609386D03*
X194097Y1607286D03*
Y1609386D03*
X197697Y1607286D03*
Y1609386D03*
X216395Y64434D03*
Y62334D03*
X219995Y64434D03*
Y62334D03*
X208995Y70434D03*
Y68334D03*
X212917Y1583088D03*
X216517D03*
X212917Y1585188D03*
X216517D03*
X218217Y1607286D03*
Y1609386D03*
X221817Y1607286D03*
Y1609386D03*
X209757Y1607286D03*
Y1609386D03*
X230995Y70434D03*
Y68334D03*
X227395Y70434D03*
Y68334D03*
X224977Y1583088D03*
X228577D03*
X237037D03*
X240637D03*
X224977Y1585188D03*
X228577D03*
X237037D03*
X240637D03*
X230277Y1607286D03*
Y1609386D03*
X233877Y1607286D03*
Y1609386D03*
X249097Y1583088D03*
X252697D03*
X249097Y1585188D03*
X252697D03*
X254397Y1607286D03*
Y1609386D03*
X242337Y1607286D03*
Y1609386D03*
X245937Y1607286D03*
Y1609386D03*
X261157Y1583088D03*
X264757D03*
X273217D03*
X261157Y1585188D03*
X264757D03*
X273217D03*
X266457Y1607286D03*
Y1609386D03*
X270057Y1607286D03*
Y1609386D03*
X257997Y1607286D03*
Y1609386D03*
X276817Y1583088D03*
X285277D03*
X288877D03*
X276817Y1585188D03*
X285277D03*
X288877D03*
X278517Y1607286D03*
Y1609386D03*
X282117Y1607286D03*
Y1609386D03*
X297337Y1583088D03*
X300937D03*
X297337Y1585188D03*
X300937D03*
X302637Y1607286D03*
Y1609386D03*
X306237Y1607286D03*
Y1609386D03*
X290577Y1607286D03*
Y1609386D03*
X294177Y1607286D03*
Y1609386D03*
X309397Y1583088D03*
X312997D03*
X321457D03*
X309397Y1585188D03*
X312997D03*
X321457D03*
X314697Y1607286D03*
Y1609386D03*
X318297Y1607286D03*
Y1609386D03*
X325057Y1583088D03*
X333517D03*
X337117D03*
X325057Y1585188D03*
X333517D03*
X337117D03*
X338817Y1607286D03*
Y1609386D03*
X330357Y1607286D03*
Y1609386D03*
X326757Y1607286D03*
Y1609386D03*
X345577Y1583088D03*
X349177D03*
X345577Y1585188D03*
X349177D03*
X350877Y1607286D03*
Y1609386D03*
X354477Y1607286D03*
Y1609386D03*
X342417Y1607286D03*
Y1609386D03*
X357637Y1583088D03*
X361237D03*
X369697D03*
X357637Y1585188D03*
X361237D03*
X369697D03*
X362937Y1607286D03*
Y1609386D03*
X366537Y1607286D03*
Y1609386D03*
X373297Y1583088D03*
Y1585188D03*
X374997Y1607286D03*
Y1609386D03*
X378597Y1607286D03*
Y1609386D03*
X402781Y1613560D03*
Y1611460D03*
X405919Y1613560D03*
Y1611460D03*
X476551Y1583088D03*
X472951D03*
X485011D03*
X476551Y1585188D03*
X472951D03*
X485011D03*
X478251Y1607286D03*
Y1609386D03*
X481851Y1607286D03*
Y1609386D03*
X488611Y1583088D03*
X500671D03*
X497071D03*
X488611Y1585188D03*
X500671D03*
X497071D03*
X490311Y1607286D03*
Y1609386D03*
X493911Y1607286D03*
Y1609386D03*
X512731Y1583088D03*
X509131D03*
X512731Y1585188D03*
X509131D03*
X502371Y1607286D03*
Y1609386D03*
X505971Y1607286D03*
Y1609386D03*
X514431Y1607286D03*
Y1609386D03*
X524791Y1583088D03*
X521191D03*
X533251D03*
X524791Y1585188D03*
X521191D03*
X533251D03*
X518031Y1607286D03*
Y1609386D03*
X526491Y1607286D03*
Y1609386D03*
X530091Y1607286D03*
Y1609386D03*
X536851Y1583088D03*
X548911D03*
X545311D03*
X536851Y1585188D03*
X548911D03*
X545311D03*
X538551Y1607286D03*
Y1609386D03*
X542151Y1607286D03*
Y1609386D03*
X560971Y1583088D03*
X557371D03*
X560971Y1585188D03*
X557371D03*
X550611Y1607286D03*
Y1609386D03*
X554211Y1607286D03*
Y1609386D03*
X562671Y1607286D03*
Y1609386D03*
X566271Y1607286D03*
Y1609386D03*
X573031Y1583088D03*
X569431D03*
X581491D03*
X573031Y1585188D03*
X569431D03*
X581491D03*
X574731Y1607286D03*
Y1609386D03*
X578331Y1607286D03*
Y1609386D03*
X585091Y1583088D03*
X597151D03*
X593551D03*
X585091Y1585188D03*
X597151D03*
X593551D03*
X586791Y1607286D03*
Y1609386D03*
X590391Y1607286D03*
Y1609386D03*
X598851Y1607286D03*
Y1609386D03*
X609211Y1583088D03*
X605611D03*
X609211Y1585188D03*
X605611D03*
X602451Y1607286D03*
Y1609386D03*
X610911Y1607286D03*
Y1609386D03*
X614511Y1607286D03*
Y1609386D03*
X621271Y1583088D03*
X617671D03*
X629731D03*
X621271Y1585188D03*
X617671D03*
X629731D03*
X622971Y1607286D03*
Y1609386D03*
X626571Y1607286D03*
Y1609386D03*
X633331Y1583088D03*
X645391D03*
X641791D03*
X633331Y1585188D03*
X645391D03*
X641791D03*
X635031Y1607286D03*
Y1609386D03*
X638631Y1607286D03*
Y1609386D03*
X647091Y1607286D03*
Y1609386D03*
X657451Y1583088D03*
X653851D03*
X657451Y1585188D03*
X653851D03*
X650691Y1607286D03*
Y1609386D03*
X662751Y1607286D03*
Y1609386D03*
X659151Y1607286D03*
Y1609386D03*
X1196672Y1583088D03*
X1200272D03*
X1196672Y1585188D03*
X1200272D03*
X1212332Y1583088D03*
X1208732D03*
X1212332Y1585188D03*
X1208732D03*
X1201972Y1607286D03*
Y1609386D03*
X1205572Y1607286D03*
Y1609386D03*
X1214032Y1607286D03*
Y1609386D03*
X1232852Y1583088D03*
X1220792D03*
X1224392D03*
X1232852Y1585188D03*
X1220792D03*
X1224392D03*
X1229692Y1607286D03*
Y1609386D03*
X1226092Y1607286D03*
Y1609386D03*
X1217632Y1607286D03*
Y1609386D03*
X1244912Y1583088D03*
X1248512D03*
X1236452D03*
X1244912Y1585188D03*
X1248512D03*
X1236452D03*
X1241752Y1607286D03*
Y1609386D03*
X1238152Y1607286D03*
Y1609386D03*
X1256972Y1583088D03*
X1260572D03*
X1256972Y1585188D03*
X1260572D03*
X1253812Y1607286D03*
Y1609386D03*
X1250212Y1607286D03*
Y1609386D03*
X1265872Y1607286D03*
Y1609386D03*
X1262272Y1607286D03*
Y1609386D03*
X1281092Y1583088D03*
X1269032D03*
X1272632D03*
X1281092Y1585188D03*
X1269032D03*
X1272632D03*
X1277932Y1607286D03*
Y1609386D03*
X1274332Y1607286D03*
Y1609386D03*
X1293152Y1583088D03*
X1296752D03*
X1284692D03*
X1293152Y1585188D03*
X1296752D03*
X1284692D03*
X1289992Y1607286D03*
Y1609386D03*
X1286392Y1607286D03*
Y1609386D03*
X1298452Y1607286D03*
Y1609386D03*
X1305212Y1583088D03*
X1308812D03*
X1305212Y1585188D03*
X1308812D03*
X1310512Y1607286D03*
Y1609386D03*
X1314112Y1607286D03*
Y1609386D03*
X1302052Y1607286D03*
Y1609386D03*
X1329332Y1583088D03*
X1317272D03*
X1320872D03*
X1329332Y1585188D03*
X1317272D03*
X1320872D03*
X1322572Y1607286D03*
Y1609386D03*
X1326172Y1607286D03*
Y1609386D03*
X1344585Y276790D03*
Y274690D03*
X1341392Y1583088D03*
X1344992D03*
X1332932D03*
X1341392Y1585188D03*
X1344992D03*
X1332932D03*
X1338232Y1607286D03*
Y1609386D03*
X1334632Y1607286D03*
Y1609386D03*
X1346692Y1607286D03*
Y1609386D03*
X1353285Y278690D03*
Y276590D03*
X1356885Y278690D03*
Y276590D03*
X1348185Y276790D03*
Y274690D03*
X1361385Y274160D03*
Y272060D03*
X1353452Y1583088D03*
X1357052D03*
X1353452Y1585188D03*
X1357052D03*
X1350292Y1607286D03*
Y1609386D03*
X1358752Y1607286D03*
Y1609386D03*
X1362352Y1607286D03*
Y1609386D03*
X1364985Y274160D03*
Y272060D03*
X1377572Y1583088D03*
X1365512D03*
X1369112D03*
X1377572Y1585188D03*
X1365512D03*
X1369112D03*
X1374412Y1607286D03*
Y1609386D03*
X1370812Y1607286D03*
Y1609386D03*
X1381172Y1583088D03*
Y1585188D03*
X1386472Y1607286D03*
Y1609386D03*
X1382872Y1607286D03*
Y1609386D03*
X1474255Y1583088D03*
X1465795D03*
X1462195D03*
X1474255Y1585188D03*
X1465795D03*
X1462195D03*
X1467495Y1607286D03*
Y1609386D03*
X1471095Y1607286D03*
Y1609386D03*
X1486315Y1583088D03*
X1489915D03*
X1477855D03*
X1486315Y1585188D03*
X1489915D03*
X1477855D03*
X1479555Y1607286D03*
Y1609386D03*
X1483155Y1607286D03*
Y1609386D03*
X1491615Y1607286D03*
Y1609386D03*
X1501975Y1583088D03*
X1498375D03*
X1501975Y1585188D03*
X1498375D03*
X1495215Y1607286D03*
Y1609386D03*
X1503675Y1607286D03*
Y1609386D03*
X1507275Y1607286D03*
Y1609386D03*
X1526095Y1583088D03*
X1522495D03*
X1514035D03*
X1510435D03*
X1526095Y1585188D03*
X1522495D03*
X1514035D03*
X1510435D03*
X1515735Y1607286D03*
Y1609386D03*
X1519335Y1607286D03*
Y1609386D03*
X1535496Y64391D03*
Y62291D03*
X1539096Y64391D03*
Y62291D03*
X1534555Y1583088D03*
X1538155D03*
X1534555Y1585188D03*
X1538155D03*
X1527795Y1607286D03*
Y1609386D03*
X1531395Y1607286D03*
Y1609386D03*
X1539855Y1607286D03*
Y1609386D03*
X1557496Y64391D03*
Y62291D03*
X1546496Y70391D03*
Y68291D03*
X1550096Y70391D03*
Y68291D03*
X1558675Y1583088D03*
X1546615D03*
X1550215D03*
X1558675Y1585188D03*
X1546615D03*
X1550215D03*
X1543455Y1607286D03*
Y1609386D03*
X1551915Y1607286D03*
Y1609386D03*
X1555515Y1607286D03*
Y1609386D03*
X1568496Y70391D03*
Y68291D03*
X1572096Y70391D03*
Y68291D03*
X1561096Y64391D03*
Y62291D03*
X1574335Y1583088D03*
X1570735D03*
X1562275D03*
X1574335Y1585188D03*
X1570735D03*
X1562275D03*
X1563975Y1607286D03*
Y1609386D03*
X1567575Y1607286D03*
Y1609386D03*
X1579496Y64391D03*
Y62291D03*
X1583096Y64391D03*
Y62291D03*
X1590496Y70391D03*
Y68291D03*
X1582795Y1583088D03*
X1586395D03*
X1582795Y1585188D03*
X1586395D03*
X1576035Y1607286D03*
Y1609386D03*
X1579635Y1607286D03*
Y1609386D03*
X1588095Y1607286D03*
Y1609386D03*
X1601496Y64391D03*
Y62291D03*
X1605096Y64391D03*
Y62291D03*
X1594096Y70391D03*
Y68291D03*
X1606915Y1583088D03*
X1598455D03*
X1594855D03*
X1606915Y1585188D03*
X1598455D03*
X1594855D03*
X1591695Y1607286D03*
Y1609386D03*
X1600155Y1607286D03*
Y1609386D03*
X1603755Y1607286D03*
Y1609386D03*
X1623496Y64391D03*
Y62291D03*
X1616096Y70391D03*
Y68291D03*
X1612496Y70391D03*
Y68291D03*
X1618975Y1583088D03*
X1622575D03*
X1610515D03*
X1618975Y1585188D03*
X1622575D03*
X1610515D03*
X1612215Y1607286D03*
Y1609386D03*
X1615815Y1607286D03*
Y1609386D03*
X1627096Y64391D03*
Y62291D03*
X1635700Y70391D03*
Y68291D03*
X1639300Y70391D03*
Y68291D03*
X1634635Y1583088D03*
X1631035D03*
X1634635Y1585188D03*
X1631035D03*
X1624275Y1607286D03*
Y1609386D03*
X1627875Y1607286D03*
Y1609386D03*
X1636335Y1607286D03*
Y1609386D03*
X1639935Y1607286D03*
Y1609386D03*
X1650300Y64391D03*
Y62291D03*
X1646700Y64391D03*
Y62291D03*
X1643095Y1583088D03*
X1646695D03*
X1643095Y1585188D03*
X1646695D03*
X1651995Y1607286D03*
Y1609386D03*
X1648395Y1607286D03*
Y1609386D03*
X1672300Y64391D03*
Y62291D03*
X1668700Y64391D03*
Y62291D03*
X1661300Y70391D03*
Y68291D03*
X1657700Y70391D03*
Y68291D03*
X1679834Y70391D03*
Y68291D03*
X1683434Y70391D03*
Y68291D03*
X1701834Y70391D03*
Y68291D03*
X1694434Y64391D03*
Y62291D03*
X1690834Y64391D03*
Y62291D03*
X1705434Y70391D03*
Y68291D03*
G54D118*
X228840Y685948D03*
X255218D03*
X1054629Y281400D03*
X1081007D03*
X1601355Y602634D03*
X1627733D03*
G54D262*
X1037026Y275752D03*
X1023640Y286776D03*
X1795857Y1521592D03*
X1809243Y1510568D03*
G54D316*
X1766413Y298829D03*
X1768382D03*
X1760508D03*
X1762476D03*
X1764445D03*
X1770350D03*
G54D181*
X470654Y303145D03*
X504054Y302445D03*
G54D136*
X275630Y109804D03*
X708786Y113929D03*
X1750751Y110928D03*
G54D145*
X317642Y1296728D03*
Y1330192D03*
X349650Y1273694D03*
Y1307158D03*
X381731Y1260612D03*
Y1294076D03*
X413909Y1260612D03*
Y1294076D03*
X446256Y1260612D03*
Y1294076D03*
X478433Y1260612D03*
Y1294076D03*
X510620Y1273793D03*
Y1307257D03*
X542985Y1296463D03*
Y1329927D03*
X1293783Y1296728D03*
Y1330192D03*
X1325791Y1273694D03*
Y1307158D03*
X1357872Y1260612D03*
Y1294076D03*
X1390050Y1260612D03*
Y1294076D03*
X1422397Y1260612D03*
Y1294076D03*
X1454574Y1260612D03*
Y1294076D03*
X1486761Y1273793D03*
Y1307257D03*
X1519126Y1296463D03*
Y1329927D03*
G54D217*
X777283Y317392D03*
X771377D03*
X808793Y264580D03*
X802887D03*
G54D127*
X238780Y1643661D03*
X230906Y1649173D03*
X238780Y1653110D03*
Y1657834D03*
X230906Y1653897D03*
Y1663346D03*
X238780Y1667283D03*
Y1672007D03*
Y1681456D03*
X230906Y1668070D03*
Y1677519D03*
Y1682244D03*
X238780Y1686180D03*
Y1695629D03*
X230906Y1691692D03*
Y1696417D03*
X238780Y1700354D03*
Y1709803D03*
Y1714527D03*
X230906Y1705866D03*
Y1710590D03*
X238780Y1723976D03*
Y1728700D03*
X230906Y1720039D03*
Y1724763D03*
X254528Y1643661D03*
X246654Y1649173D03*
X254528Y1653110D03*
Y1657834D03*
X246654Y1653897D03*
Y1663346D03*
X254528Y1667283D03*
Y1672007D03*
Y1681456D03*
X246654Y1668070D03*
Y1677519D03*
Y1682244D03*
X254528Y1686180D03*
Y1695629D03*
X246654Y1691692D03*
Y1696417D03*
X254528Y1700354D03*
Y1709803D03*
Y1714527D03*
X246654Y1705866D03*
Y1710590D03*
X254528Y1723976D03*
Y1728700D03*
X246654Y1720039D03*
Y1724763D03*
Y1734212D03*
X270276Y1643661D03*
X262402Y1649173D03*
X270276Y1653110D03*
Y1657834D03*
X262402Y1653897D03*
Y1663346D03*
X270276Y1667283D03*
Y1672007D03*
Y1681456D03*
X262402Y1668070D03*
Y1677519D03*
Y1682244D03*
X270276Y1686180D03*
Y1695629D03*
X262402Y1691692D03*
Y1696417D03*
X270276Y1700354D03*
Y1709803D03*
Y1714527D03*
X262402Y1705866D03*
Y1710590D03*
X270276Y1723976D03*
Y1728700D03*
X262402Y1720039D03*
Y1724763D03*
Y1734212D03*
X286024Y1643661D03*
X278150Y1649173D03*
X286024Y1653110D03*
Y1657834D03*
X278150Y1653897D03*
Y1663346D03*
X286024Y1667283D03*
Y1672007D03*
Y1681456D03*
X278150Y1668070D03*
Y1677519D03*
Y1682244D03*
X286024Y1686180D03*
Y1695629D03*
X278150Y1691692D03*
Y1696417D03*
X286024Y1700354D03*
Y1709803D03*
Y1714527D03*
X278150Y1705866D03*
Y1710590D03*
X286024Y1723976D03*
Y1728700D03*
X278150Y1720039D03*
Y1724763D03*
Y1734212D03*
X305709Y1672007D03*
X297835Y1677519D03*
Y1682244D03*
X305709Y1681456D03*
Y1686180D03*
X297835Y1691692D03*
Y1696417D03*
X305709Y1695629D03*
Y1700354D03*
X297835Y1705866D03*
Y1710590D03*
X305709Y1709803D03*
Y1714527D03*
X297835Y1720039D03*
Y1724763D03*
X305709Y1723976D03*
Y1728700D03*
X321457Y1672007D03*
X313583Y1677519D03*
Y1682244D03*
X321457Y1681456D03*
Y1686180D03*
X313583Y1691692D03*
Y1696417D03*
X321457Y1695629D03*
Y1700354D03*
X313583Y1705866D03*
Y1710590D03*
X321457Y1709803D03*
Y1714527D03*
X313583Y1720039D03*
Y1724763D03*
X321457Y1723976D03*
Y1728700D03*
X313583Y1734212D03*
X337205Y1672007D03*
X329331Y1677519D03*
Y1682244D03*
X337205Y1681456D03*
Y1686180D03*
X329331Y1691692D03*
Y1696417D03*
X337205Y1695629D03*
Y1700354D03*
X329331Y1705866D03*
Y1710590D03*
X337205Y1709803D03*
Y1714527D03*
X329331Y1720039D03*
Y1724763D03*
X337205Y1723976D03*
Y1728700D03*
X329331Y1734212D03*
X352953Y1672007D03*
X345079Y1677519D03*
Y1682244D03*
X352953Y1681456D03*
Y1686180D03*
X345079Y1691692D03*
Y1696417D03*
X352953Y1695629D03*
Y1700354D03*
X345079Y1705866D03*
Y1710590D03*
X352953Y1709803D03*
Y1714527D03*
X345079Y1720039D03*
Y1724763D03*
X352953Y1723976D03*
Y1728700D03*
X345079Y1734212D03*
X495079Y1677519D03*
Y1682244D03*
Y1691692D03*
Y1696417D03*
Y1705866D03*
Y1710590D03*
Y1720039D03*
Y1724763D03*
X502953Y1672007D03*
X510827Y1677519D03*
X502953Y1681456D03*
X510827Y1682244D03*
X502953Y1686180D03*
X510827Y1691692D03*
X502953Y1695629D03*
X510827Y1696417D03*
X502953Y1700354D03*
X510827Y1705866D03*
X502953Y1709803D03*
X510827Y1710590D03*
X502953Y1714527D03*
X510827Y1720039D03*
X502953Y1723976D03*
X510827Y1724763D03*
X502953Y1728700D03*
X510827Y1734212D03*
X518701Y1672007D03*
X534449D03*
X526575Y1677519D03*
X518701Y1681456D03*
X526575Y1682244D03*
X534449Y1681456D03*
X518701Y1686180D03*
X534449D03*
X526575Y1691692D03*
X518701Y1695629D03*
X526575Y1696417D03*
X534449Y1695629D03*
X518701Y1700354D03*
X534449D03*
X526575Y1705866D03*
X518701Y1709803D03*
X526575Y1710590D03*
X534449Y1709803D03*
X518701Y1714527D03*
X534449D03*
X526575Y1720039D03*
X518701Y1723976D03*
X526575Y1724763D03*
X534449Y1723976D03*
X518701Y1728700D03*
X534449D03*
X526575Y1734212D03*
X550197Y1672007D03*
X542323Y1677519D03*
Y1682244D03*
X550197Y1681456D03*
Y1686180D03*
X542323Y1691692D03*
Y1696417D03*
X550197Y1695629D03*
Y1700354D03*
X542323Y1705866D03*
Y1710590D03*
X550197Y1709803D03*
Y1714527D03*
X542323Y1720039D03*
Y1724763D03*
X550197Y1723976D03*
Y1728700D03*
X542323Y1734212D03*
X562008Y1677519D03*
Y1682244D03*
Y1691692D03*
Y1696417D03*
Y1705866D03*
Y1710590D03*
Y1720039D03*
Y1724763D03*
X569882Y1672007D03*
X577756Y1677519D03*
X569882Y1681456D03*
X577756Y1682244D03*
X569882Y1686180D03*
X577756Y1691692D03*
X569882Y1695629D03*
X577756Y1696417D03*
X569882Y1700354D03*
X577756Y1705866D03*
X569882Y1709803D03*
X577756Y1710590D03*
X569882Y1714527D03*
X577756Y1720039D03*
X569882Y1723976D03*
X577756Y1724763D03*
X569882Y1728700D03*
X577756Y1734212D03*
X585630Y1672007D03*
X593504Y1677519D03*
X585630Y1681456D03*
X593504Y1682244D03*
X585630Y1686180D03*
X593504Y1691692D03*
X585630Y1695629D03*
X593504Y1696417D03*
X585630Y1700354D03*
X593504Y1705866D03*
X585630Y1709803D03*
X593504Y1710590D03*
X585630Y1714527D03*
X593504Y1720039D03*
X585630Y1723976D03*
X593504Y1724763D03*
X585630Y1728700D03*
X593504Y1734212D03*
X601378Y1672007D03*
X609252Y1677519D03*
X601378Y1681456D03*
X609252Y1682244D03*
X601378Y1686180D03*
X609252Y1691692D03*
X601378Y1695629D03*
X609252Y1696417D03*
X601378Y1700354D03*
X609252Y1705866D03*
X601378Y1709803D03*
X609252Y1710590D03*
X601378Y1714527D03*
X609252Y1720039D03*
X601378Y1723976D03*
X609252Y1724763D03*
X601378Y1728700D03*
X609252Y1734212D03*
X617126Y1672007D03*
Y1681456D03*
Y1686180D03*
Y1695629D03*
Y1700354D03*
Y1709803D03*
Y1714527D03*
Y1723976D03*
Y1728700D03*
X1246654Y1672007D03*
X1238780Y1677519D03*
Y1682244D03*
X1246654Y1681456D03*
Y1686180D03*
X1238780Y1691692D03*
Y1696417D03*
X1246654Y1695629D03*
Y1700354D03*
X1238780Y1705866D03*
Y1710590D03*
X1246654Y1709803D03*
Y1714527D03*
X1238780Y1720039D03*
Y1724763D03*
X1246654Y1723976D03*
Y1728700D03*
X1262402Y1672007D03*
X1254528Y1677519D03*
Y1682244D03*
X1262402Y1681456D03*
Y1686180D03*
X1254528Y1691692D03*
Y1696417D03*
X1262402Y1695629D03*
Y1700354D03*
X1254528Y1705866D03*
Y1710590D03*
X1262402Y1709803D03*
Y1714527D03*
X1254528Y1720039D03*
Y1724763D03*
X1262402Y1723976D03*
Y1728700D03*
X1254528Y1734212D03*
X1278150Y1672007D03*
X1270276Y1677519D03*
Y1682244D03*
X1278150Y1681456D03*
Y1686180D03*
X1270276Y1691692D03*
Y1696417D03*
X1278150Y1695629D03*
Y1700354D03*
X1270276Y1705866D03*
Y1710590D03*
X1278150Y1709803D03*
Y1714527D03*
X1270276Y1720039D03*
Y1724763D03*
X1278150Y1723976D03*
Y1728700D03*
X1270276Y1734212D03*
X1293898Y1672007D03*
X1286024Y1677519D03*
Y1682244D03*
X1293898Y1681456D03*
Y1686180D03*
X1286024Y1691692D03*
Y1696417D03*
X1293898Y1695629D03*
Y1700354D03*
X1286024Y1705866D03*
Y1710590D03*
X1293898Y1709803D03*
Y1714527D03*
X1286024Y1720039D03*
Y1724763D03*
X1293898Y1723976D03*
Y1728700D03*
X1286024Y1734212D03*
X1313583Y1672007D03*
X1305709Y1677519D03*
Y1682244D03*
X1313583Y1681456D03*
Y1686180D03*
X1305709Y1691692D03*
Y1696417D03*
X1313583Y1695629D03*
Y1700354D03*
X1305709Y1705866D03*
Y1710590D03*
X1313583Y1709803D03*
Y1714527D03*
X1305709Y1720039D03*
Y1724763D03*
X1313583Y1723976D03*
Y1728700D03*
X1329331Y1672007D03*
X1321457Y1677519D03*
Y1682244D03*
X1329331Y1681456D03*
Y1686180D03*
X1321457Y1691692D03*
Y1696417D03*
X1329331Y1695629D03*
Y1700354D03*
X1321457Y1705866D03*
Y1710590D03*
X1329331Y1709803D03*
Y1714527D03*
X1321457Y1720039D03*
Y1724763D03*
X1329331Y1723976D03*
Y1728700D03*
X1321457Y1734212D03*
X1345079Y1672007D03*
X1337205Y1677519D03*
Y1682244D03*
X1345079Y1681456D03*
Y1686180D03*
X1337205Y1691692D03*
Y1696417D03*
X1345079Y1695629D03*
Y1700354D03*
X1337205Y1705866D03*
Y1710590D03*
X1345079Y1709803D03*
Y1714527D03*
X1337205Y1720039D03*
Y1724763D03*
X1345079Y1723976D03*
Y1728700D03*
X1337205Y1734212D03*
X1360827Y1672007D03*
X1352953Y1677519D03*
Y1682244D03*
X1360827Y1681456D03*
Y1686180D03*
X1352953Y1691692D03*
Y1696417D03*
X1360827Y1695629D03*
Y1700354D03*
X1352953Y1705866D03*
Y1710590D03*
X1360827Y1709803D03*
Y1714527D03*
X1352953Y1720039D03*
Y1724763D03*
X1360827Y1723976D03*
Y1728700D03*
X1352953Y1734212D03*
X1510827Y1672007D03*
X1502953Y1677519D03*
Y1682244D03*
X1510827Y1681456D03*
Y1686180D03*
X1502953Y1691692D03*
Y1696417D03*
X1510827Y1695629D03*
Y1700354D03*
X1502953Y1705866D03*
Y1710590D03*
X1510827Y1709803D03*
Y1714527D03*
X1502953Y1720039D03*
Y1724763D03*
X1510827Y1723976D03*
Y1728700D03*
X1526575Y1672007D03*
X1518701Y1677519D03*
Y1682244D03*
X1526575Y1681456D03*
Y1686180D03*
X1518701Y1691692D03*
Y1696417D03*
X1526575Y1695629D03*
Y1700354D03*
X1518701Y1705866D03*
Y1710590D03*
X1526575Y1709803D03*
Y1714527D03*
X1518701Y1720039D03*
Y1724763D03*
X1526575Y1723976D03*
Y1728700D03*
X1518701Y1734212D03*
X1542323Y1672007D03*
X1534449Y1677519D03*
Y1682244D03*
X1542323Y1681456D03*
Y1686180D03*
X1534449Y1691692D03*
Y1696417D03*
X1542323Y1695629D03*
Y1700354D03*
X1534449Y1705866D03*
Y1710590D03*
X1542323Y1709803D03*
Y1714527D03*
X1534449Y1720039D03*
Y1724763D03*
X1542323Y1723976D03*
Y1728700D03*
X1534449Y1734212D03*
X1558071Y1672007D03*
X1550197Y1677519D03*
Y1682244D03*
X1558071Y1681456D03*
Y1686180D03*
X1550197Y1691692D03*
Y1696417D03*
X1558071Y1695629D03*
Y1700354D03*
X1550197Y1705866D03*
Y1710590D03*
X1558071Y1709803D03*
Y1714527D03*
X1550197Y1720039D03*
Y1724763D03*
X1558071Y1723976D03*
Y1728700D03*
X1550197Y1734212D03*
X1569882Y1677519D03*
Y1682244D03*
Y1691692D03*
Y1696417D03*
Y1705866D03*
Y1710590D03*
Y1720039D03*
Y1724763D03*
X1577756Y1672007D03*
X1585630Y1677519D03*
X1577756Y1681456D03*
X1585630Y1682244D03*
X1577756Y1686180D03*
X1585630Y1691692D03*
X1577756Y1695629D03*
X1585630Y1696417D03*
X1577756Y1700354D03*
X1585630Y1705866D03*
X1577756Y1709803D03*
X1585630Y1710590D03*
X1577756Y1714527D03*
X1585630Y1720039D03*
X1577756Y1723976D03*
X1585630Y1724763D03*
X1577756Y1728700D03*
X1585630Y1734212D03*
X1593504Y1672007D03*
X1601378Y1677519D03*
X1593504Y1681456D03*
X1601378Y1682244D03*
X1593504Y1686180D03*
X1601378Y1691692D03*
X1593504Y1695629D03*
X1601378Y1696417D03*
X1593504Y1700354D03*
X1601378Y1705866D03*
X1593504Y1709803D03*
X1601378Y1710590D03*
X1593504Y1714527D03*
X1601378Y1720039D03*
X1593504Y1723976D03*
X1601378Y1724763D03*
X1593504Y1728700D03*
X1601378Y1734212D03*
X1609252Y1672007D03*
X1617126Y1677519D03*
X1609252Y1681456D03*
X1617126Y1682244D03*
X1609252Y1686180D03*
X1617126Y1691692D03*
X1609252Y1695629D03*
X1617126Y1696417D03*
X1609252Y1700354D03*
X1617126Y1705866D03*
X1609252Y1709803D03*
X1617126Y1710590D03*
X1609252Y1714527D03*
X1617126Y1720039D03*
X1609252Y1723976D03*
X1617126Y1724763D03*
X1609252Y1728700D03*
X1617126Y1734212D03*
X1625000Y1672007D03*
Y1681456D03*
Y1686180D03*
Y1695629D03*
Y1700354D03*
Y1709803D03*
Y1714527D03*
Y1723976D03*
Y1728700D03*
G54D70*
X80762Y1543015D03*
X82337D03*
X83912D03*
X85487D03*
X87061D03*
X88636D03*
X90211D03*
X91786D03*
G54D109*
G01X1660791Y1051247D02*
X1665141D01*
X186697Y1578182D03*
Y1590094D03*
X191997Y1602380D03*
Y1614292D03*
X194497Y1578182D03*
X206557D03*
X198757D03*
X194497Y1590094D03*
X206557D03*
X198757D03*
X199797Y1614292D03*
Y1602380D03*
X204057Y1614292D03*
Y1602380D03*
X218617Y1578182D03*
X210817D03*
X222877D03*
X218617Y1590094D03*
X210817D03*
X222877D03*
X211857Y1614292D03*
Y1602380D03*
X223917Y1614292D03*
X216117D03*
X223917Y1602380D03*
X216117D03*
X230677Y1578182D03*
X234937D03*
X230677Y1590094D03*
X234937D03*
X228177Y1614292D03*
X235977D03*
X228177Y1602380D03*
X235977D03*
X240237D03*
Y1614292D03*
X242737Y1578182D03*
X246997D03*
X254797D03*
X242737Y1590094D03*
X246997D03*
X254797D03*
X248037Y1602380D03*
Y1614292D03*
X252297Y1602380D03*
Y1614292D03*
X266857Y1578182D03*
X259057D03*
X271117D03*
X266857Y1590094D03*
X259057D03*
X271117D03*
X260097Y1602380D03*
Y1614292D03*
X272157Y1602380D03*
Y1614292D03*
X264357D03*
Y1602380D03*
X278917Y1578182D03*
X283177D03*
X278917Y1590094D03*
X283177D03*
X284217Y1602380D03*
Y1614292D03*
X276417D03*
Y1602380D03*
X288477Y1614292D03*
Y1602380D03*
X290977Y1578182D03*
X295237D03*
X303037D03*
X290977Y1590094D03*
X295237D03*
X303037D03*
X296277Y1614292D03*
Y1602380D03*
X300537D03*
Y1614292D03*
X315097Y1578182D03*
X307297D03*
X319357D03*
X315097Y1590094D03*
X307297D03*
X319357D03*
X308337Y1602380D03*
Y1614292D03*
X320397D03*
X312597D03*
X320397Y1602380D03*
X312597D03*
X327157Y1578182D03*
X331417D03*
X327157Y1590094D03*
X331417D03*
X324657Y1602380D03*
X332457D03*
X324657Y1614292D03*
X332457D03*
X336717Y1602380D03*
Y1614292D03*
X339217Y1578182D03*
X343477D03*
X351277D03*
X339217Y1590094D03*
X343477D03*
X351277D03*
X344517Y1602380D03*
Y1614292D03*
X348777Y1602380D03*
Y1614292D03*
X363337Y1578088D03*
X355537Y1578182D03*
X367597D03*
X363337Y1590094D03*
X355537D03*
X367597D03*
X356577Y1602380D03*
Y1614292D03*
X368637D03*
X360837D03*
X368637Y1602286D03*
X360837Y1602380D03*
X375397Y1578182D03*
Y1590094D03*
X372897Y1602380D03*
X380697D03*
X372897Y1614292D03*
X380697D03*
X482911Y1578182D03*
X478651D03*
X470851D03*
X482911Y1590094D03*
X478651D03*
X470851D03*
X483951Y1614292D03*
Y1602380D03*
X476151D03*
Y1614292D03*
X494971Y1578182D03*
X490711D03*
X494971Y1590094D03*
X490711D03*
X500271Y1614292D03*
Y1602380D03*
X488211Y1614292D03*
Y1602380D03*
X496011D03*
Y1614292D03*
X507031Y1578182D03*
X514831D03*
X502771D03*
X507031Y1590094D03*
X514831D03*
X502771D03*
X512331Y1614292D03*
Y1602380D03*
X508071Y1614292D03*
Y1602380D03*
X531151Y1578182D03*
X519091D03*
X526891D03*
X531151Y1590094D03*
X519091D03*
X526891D03*
X532191Y1614292D03*
Y1602380D03*
X524391Y1614292D03*
Y1602380D03*
X520131D03*
Y1614292D03*
X543211Y1578182D03*
X538951D03*
X543211Y1590094D03*
X538951D03*
X548511Y1614292D03*
Y1602380D03*
X536451D03*
Y1614292D03*
X544251Y1602380D03*
Y1614292D03*
X555271Y1578182D03*
X563071D03*
X551011D03*
X555271Y1590094D03*
X563071D03*
X551011D03*
X560571Y1614292D03*
Y1602380D03*
X556311Y1614292D03*
Y1602380D03*
X579391Y1578182D03*
X567331D03*
X575131D03*
X579391Y1590094D03*
X567331D03*
X575131D03*
X580431Y1614292D03*
X572631D03*
X580431Y1602380D03*
X572631D03*
X568371D03*
Y1614292D03*
X599251Y1578182D03*
X591451D03*
X587191D03*
X599251Y1590094D03*
X591451D03*
X587191D03*
X596751Y1614292D03*
Y1602380D03*
X584691D03*
Y1614292D03*
X592491Y1602380D03*
Y1614292D03*
X615571Y1578182D03*
X603511D03*
X611311D03*
X615571Y1590094D03*
X603511D03*
X611311D03*
X608811Y1602380D03*
Y1614292D03*
X604551Y1602380D03*
Y1614292D03*
X627631Y1578182D03*
X623371D03*
X627631Y1590094D03*
X623371D03*
X628671Y1602380D03*
Y1614292D03*
X620871D03*
Y1602380D03*
X616611Y1614292D03*
Y1602380D03*
X647491Y1578088D03*
X639691Y1578182D03*
X635431D03*
X647491Y1590094D03*
X639691D03*
X635431D03*
X644991Y1614292D03*
Y1602380D03*
X632931D03*
Y1614292D03*
X640731D03*
Y1602380D03*
X651751Y1578182D03*
X659551D03*
X651751Y1590094D03*
X659551D03*
X657051Y1602380D03*
Y1614292D03*
X652791Y1602286D03*
Y1614292D03*
X679353Y413289D03*
X676203D03*
X673054D03*
X669904D03*
X679353Y429037D03*
Y425888D03*
Y422738D03*
Y419588D03*
Y416439D03*
X676203Y429037D03*
Y425888D03*
Y422738D03*
Y419588D03*
Y416439D03*
X673054Y429037D03*
Y425888D03*
Y422738D03*
Y419588D03*
Y416439D03*
X669904Y429037D03*
Y425888D03*
Y422738D03*
Y419588D03*
Y416439D03*
X679353Y444785D03*
Y441636D03*
Y438486D03*
Y435336D03*
Y432187D03*
X676203Y444785D03*
Y441636D03*
Y438486D03*
Y435336D03*
Y432187D03*
X673054Y444785D03*
Y441636D03*
Y438486D03*
Y435336D03*
Y432187D03*
X669904Y444785D03*
Y441636D03*
Y438486D03*
Y435336D03*
Y432187D03*
X679353Y460533D03*
Y457384D03*
Y454234D03*
Y451084D03*
Y447935D03*
X676203Y460533D03*
Y457384D03*
Y454234D03*
Y451084D03*
Y447935D03*
X673054Y460533D03*
Y457384D03*
Y454234D03*
Y451084D03*
Y447935D03*
X669904Y460533D03*
Y457384D03*
Y454234D03*
Y451084D03*
Y447935D03*
X679353Y476281D03*
Y473132D03*
Y469982D03*
Y466832D03*
Y463683D03*
X676203Y476281D03*
Y473132D03*
Y469982D03*
Y466832D03*
Y463683D03*
X673054Y476281D03*
Y473132D03*
Y469982D03*
Y466832D03*
Y463683D03*
X669904Y476281D03*
Y473132D03*
Y469982D03*
Y466832D03*
Y463683D03*
X679353Y479431D03*
X676203D03*
X673054D03*
X669904D03*
X664851Y1602380D03*
Y1614292D03*
X695101Y413289D03*
X691951D03*
X688802D03*
X685652D03*
X682503D03*
X695101Y429037D03*
Y425888D03*
Y422738D03*
Y419588D03*
Y416439D03*
X691951Y429037D03*
Y425888D03*
Y422738D03*
Y419588D03*
Y416439D03*
X688802Y429037D03*
Y425888D03*
Y422738D03*
Y419588D03*
Y416439D03*
X685652Y429037D03*
Y425888D03*
Y422738D03*
Y419588D03*
Y416439D03*
X682503Y429037D03*
Y425888D03*
Y422738D03*
Y419588D03*
Y416439D03*
X695101Y444785D03*
Y441636D03*
Y438486D03*
Y435336D03*
Y432187D03*
X691951Y444785D03*
Y441636D03*
Y438486D03*
Y435336D03*
Y432187D03*
X688802Y444785D03*
Y441636D03*
Y438486D03*
Y435336D03*
Y432187D03*
X685652Y444785D03*
Y441636D03*
Y438486D03*
Y435336D03*
Y432187D03*
X682503Y444785D03*
Y441636D03*
Y438486D03*
Y435336D03*
Y432187D03*
X695101Y460533D03*
Y457384D03*
Y454234D03*
Y451084D03*
Y447935D03*
X691951Y460533D03*
Y457384D03*
Y454234D03*
Y451084D03*
Y447935D03*
X688802Y460533D03*
Y457384D03*
Y454234D03*
Y451084D03*
Y447935D03*
X685652Y460533D03*
Y457384D03*
Y454234D03*
Y451084D03*
Y447935D03*
X682503Y460533D03*
Y457384D03*
Y454234D03*
Y451084D03*
Y447935D03*
X695101Y476281D03*
Y473132D03*
Y469982D03*
Y466832D03*
Y463683D03*
X691951Y476281D03*
Y473132D03*
Y469982D03*
Y466832D03*
Y463683D03*
X688802Y476281D03*
Y473132D03*
Y469982D03*
Y466832D03*
Y463683D03*
X685652Y476281D03*
Y473132D03*
Y469982D03*
Y466832D03*
Y463683D03*
X682503Y476281D03*
Y473132D03*
Y469982D03*
Y466832D03*
Y463683D03*
X695101Y479431D03*
X691951D03*
X688802D03*
X685652D03*
X682503D03*
X710849Y413289D03*
X707699D03*
X704550D03*
X701400D03*
X698251D03*
X710849Y429037D03*
Y425888D03*
Y422738D03*
Y419588D03*
Y416439D03*
X707699Y429037D03*
Y425888D03*
Y422738D03*
Y419588D03*
Y416439D03*
X704550Y429037D03*
Y425888D03*
Y422738D03*
Y419588D03*
Y416439D03*
X701400Y429037D03*
Y425888D03*
Y422738D03*
Y419588D03*
Y416439D03*
X698251Y429037D03*
Y425888D03*
Y422738D03*
Y419588D03*
Y416439D03*
X710849Y444785D03*
Y441636D03*
Y438486D03*
Y435336D03*
Y432187D03*
X707699Y444785D03*
Y441636D03*
Y438486D03*
Y435336D03*
Y432187D03*
X704550Y444785D03*
Y441636D03*
Y438486D03*
Y435336D03*
Y432187D03*
X701400Y444785D03*
Y441636D03*
Y438486D03*
Y435336D03*
Y432187D03*
X698251Y444785D03*
Y441636D03*
Y438486D03*
Y435336D03*
Y432187D03*
X710849Y460533D03*
Y457384D03*
Y454234D03*
Y451084D03*
Y447935D03*
X707699Y460533D03*
Y457384D03*
Y454234D03*
Y451084D03*
Y447935D03*
X704550Y460533D03*
Y457384D03*
Y454234D03*
Y451084D03*
Y447935D03*
X701400Y460533D03*
Y457384D03*
Y454234D03*
Y451084D03*
Y447935D03*
X698251Y460533D03*
Y457384D03*
Y454234D03*
Y451084D03*
Y447935D03*
X710849Y476281D03*
Y473132D03*
Y469982D03*
Y466832D03*
Y463683D03*
X707699Y476281D03*
Y473132D03*
Y469982D03*
Y466832D03*
Y463683D03*
X704550Y476281D03*
Y473132D03*
Y469982D03*
Y466832D03*
Y463683D03*
X701400Y476281D03*
Y473132D03*
Y469982D03*
Y466832D03*
Y463683D03*
X698251Y476281D03*
Y473132D03*
Y469982D03*
Y466832D03*
Y463683D03*
X710849Y479431D03*
X707699D03*
X704550D03*
X701400D03*
X698251D03*
X726597Y413289D03*
X723447D03*
X720298D03*
X717148D03*
X713999D03*
X726597Y429037D03*
Y425888D03*
Y422738D03*
Y419588D03*
Y416439D03*
X723447Y429037D03*
Y425888D03*
Y422738D03*
Y419588D03*
Y416439D03*
X720298Y429037D03*
Y425888D03*
Y422738D03*
Y419588D03*
Y416439D03*
X717148Y429037D03*
Y425888D03*
Y422738D03*
Y419588D03*
Y416439D03*
X713999Y429037D03*
Y425888D03*
Y422738D03*
Y419588D03*
Y416439D03*
X726597Y444785D03*
Y441636D03*
Y438486D03*
Y435336D03*
Y432187D03*
X723447Y444785D03*
Y441636D03*
Y438486D03*
Y435336D03*
Y432187D03*
X720298Y444785D03*
Y441636D03*
Y438486D03*
Y435336D03*
Y432187D03*
X717148Y444785D03*
Y441636D03*
Y438486D03*
Y435336D03*
Y432187D03*
X713999Y444785D03*
Y441636D03*
Y438486D03*
Y435336D03*
Y432187D03*
X726597Y460533D03*
Y457384D03*
Y454234D03*
Y451084D03*
Y447935D03*
X723447Y460533D03*
Y457384D03*
Y454234D03*
Y451084D03*
Y447935D03*
X720298Y460533D03*
Y457384D03*
Y454234D03*
Y451084D03*
Y447935D03*
X717148Y460533D03*
Y457384D03*
Y454234D03*
Y451084D03*
Y447935D03*
X713999Y460533D03*
Y457384D03*
Y454234D03*
Y451084D03*
Y447935D03*
X726597Y476281D03*
Y473132D03*
Y469982D03*
Y466832D03*
Y463683D03*
X723447Y476281D03*
Y473132D03*
Y469982D03*
Y466832D03*
Y463683D03*
X720298Y476281D03*
Y473132D03*
Y469982D03*
Y466832D03*
Y463683D03*
X717148Y476281D03*
Y473132D03*
Y469982D03*
Y466832D03*
Y463683D03*
X713999Y476281D03*
Y473132D03*
Y469982D03*
Y466832D03*
Y463683D03*
X726597Y479431D03*
X723447D03*
X720298D03*
X717148D03*
X713999D03*
X736046Y413289D03*
X732896D03*
X729747D03*
X736046Y429037D03*
Y425888D03*
Y422738D03*
Y419588D03*
Y416439D03*
X732896Y429037D03*
Y425888D03*
Y422738D03*
Y419588D03*
Y416439D03*
X729747Y429037D03*
Y425888D03*
Y422738D03*
Y419588D03*
Y416439D03*
X736046Y444785D03*
Y441636D03*
Y438486D03*
Y435336D03*
Y432187D03*
X732896Y444785D03*
Y441636D03*
Y438486D03*
Y435336D03*
Y432187D03*
X729747Y444785D03*
Y441636D03*
Y438486D03*
Y435336D03*
Y432187D03*
X736046Y460533D03*
Y457384D03*
Y454234D03*
Y451084D03*
Y447935D03*
X732896Y460533D03*
Y457384D03*
Y454234D03*
Y451084D03*
Y447935D03*
X729747Y460533D03*
Y457384D03*
Y454234D03*
Y451084D03*
Y447935D03*
X736046Y476281D03*
Y473132D03*
Y469982D03*
Y466832D03*
Y463683D03*
X732896Y476281D03*
Y473132D03*
Y469982D03*
Y466832D03*
Y463683D03*
X729747Y476281D03*
Y473132D03*
Y469982D03*
Y466832D03*
Y463683D03*
X736046Y479431D03*
X732896D03*
X729747D03*
X1194572Y1578182D03*
Y1590094D03*
X1199872Y1614292D03*
Y1602380D03*
X1202372Y1578182D03*
X1214432D03*
X1206632D03*
X1202372Y1590094D03*
X1214432D03*
X1206632D03*
X1207672Y1602380D03*
Y1614292D03*
X1211932D03*
Y1602380D03*
X1218692Y1578182D03*
X1226492D03*
X1230752D03*
X1218692Y1590094D03*
X1226492D03*
X1230752D03*
X1219732Y1614292D03*
Y1602380D03*
X1231792Y1614292D03*
Y1602380D03*
X1223992D03*
Y1614292D03*
X1238552Y1578182D03*
X1242812D03*
X1238552Y1590094D03*
X1242812D03*
X1236052Y1602380D03*
Y1614292D03*
X1243852D03*
Y1602380D03*
X1248112D03*
Y1614292D03*
X1250612Y1578182D03*
X1262672D03*
X1254872D03*
X1250612Y1590094D03*
X1262672D03*
X1254872D03*
X1255912Y1614292D03*
Y1602380D03*
X1260172D03*
Y1614292D03*
X1266932Y1578182D03*
X1274732D03*
X1278992D03*
X1266932Y1590094D03*
X1274732D03*
X1278992D03*
X1267972Y1614292D03*
Y1602380D03*
X1272232D03*
Y1614292D03*
X1280032D03*
Y1602380D03*
X1285767Y150750D03*
X1288347Y148170D03*
X1290927D03*
X1285767Y153329D03*
X1290927Y233328D03*
X1294866D03*
X1288347Y230748D03*
X1285767Y228169D03*
Y224230D03*
X1286792Y1578182D03*
X1298852D03*
X1291052D03*
X1286792Y1590094D03*
X1298852D03*
X1291052D03*
X1284292Y1602380D03*
Y1614292D03*
X1292092D03*
Y1602380D03*
X1296352D03*
Y1614292D03*
X1303112Y1578182D03*
X1310912D03*
X1315172D03*
X1303112Y1590094D03*
X1310912D03*
X1315172D03*
X1304152Y1602380D03*
Y1614292D03*
X1308412Y1602380D03*
Y1614292D03*
X1322972Y1578182D03*
X1327232D03*
X1322972Y1590094D03*
X1327232D03*
X1316212Y1614292D03*
Y1602380D03*
X1328272D03*
Y1614292D03*
X1320472Y1602380D03*
Y1614292D03*
X1335032Y1578182D03*
X1347092D03*
X1339292D03*
X1335032Y1590094D03*
X1347092D03*
X1339292D03*
X1340332Y1602380D03*
Y1614292D03*
X1332532Y1602380D03*
Y1614292D03*
X1344592Y1602380D03*
Y1614292D03*
X1357888Y148170D03*
X1361827D03*
X1357888Y233328D03*
X1361827D03*
X1351352Y1578182D03*
X1359152D03*
X1363412D03*
X1351352Y1590094D03*
X1359152D03*
X1363412D03*
X1352392Y1602380D03*
Y1614292D03*
X1356652Y1602380D03*
Y1614292D03*
X1366987Y150750D03*
X1364407Y148170D03*
X1366987Y157268D03*
Y153329D03*
X1364407Y233328D03*
X1366987Y230748D03*
Y228169D03*
Y224230D03*
X1371212Y1578088D03*
X1375472Y1578182D03*
X1371212Y1590094D03*
X1375472D03*
X1364452Y1602380D03*
Y1614292D03*
X1376512Y1602286D03*
Y1614292D03*
X1368712Y1602380D03*
Y1614292D03*
X1383272Y1578182D03*
Y1590094D03*
X1380772Y1602380D03*
Y1614292D03*
X1388572D03*
Y1602380D03*
X1460095Y1578182D03*
Y1590094D03*
X1472155Y1578182D03*
X1467895D03*
X1472155Y1590094D03*
X1467895D03*
X1477455Y1602380D03*
Y1614292D03*
X1473195D03*
Y1602380D03*
X1465395D03*
Y1614292D03*
X1492015Y1578182D03*
X1484215D03*
X1479955D03*
X1492015Y1590094D03*
X1484215D03*
X1479955D03*
X1489515Y1614292D03*
Y1602380D03*
X1485255D03*
Y1614292D03*
X1508335Y1578182D03*
X1496275D03*
X1504075D03*
X1508335Y1590094D03*
X1496275D03*
X1504075D03*
X1501575Y1614292D03*
Y1602380D03*
X1509375D03*
Y1614292D03*
X1497315Y1602380D03*
Y1614292D03*
X1520395Y1578182D03*
X1516135D03*
X1520395Y1590094D03*
X1516135D03*
X1525695Y1614292D03*
Y1602380D03*
X1521435D03*
Y1614292D03*
X1513635D03*
Y1602380D03*
X1540255Y1578182D03*
X1532455D03*
X1528195D03*
X1540255Y1590094D03*
X1532455D03*
X1528195D03*
X1537755Y1614292D03*
Y1602380D03*
X1533495D03*
Y1614292D03*
X1556575Y1578182D03*
X1544515D03*
X1552315D03*
X1556575Y1590094D03*
X1544515D03*
X1552315D03*
X1549815Y1614292D03*
Y1602380D03*
X1557615D03*
Y1614292D03*
X1545555Y1602380D03*
Y1614292D03*
X1568635Y1578182D03*
X1564375D03*
X1568635Y1590094D03*
X1564375D03*
X1573935Y1614292D03*
Y1602380D03*
X1569675Y1614292D03*
Y1602380D03*
X1561875Y1614292D03*
Y1602380D03*
X1588495Y1578182D03*
X1580695D03*
X1576435D03*
X1588495Y1590094D03*
X1580695D03*
X1576435D03*
X1585995Y1614292D03*
Y1602380D03*
X1581735D03*
Y1614292D03*
X1604815Y1578182D03*
X1592755D03*
X1600555D03*
X1604815Y1590094D03*
X1592755D03*
X1600555D03*
X1598055Y1614292D03*
Y1602380D03*
X1605855Y1614292D03*
Y1602380D03*
X1593795Y1614292D03*
Y1602380D03*
X1616875Y1578182D03*
X1612615D03*
X1616875Y1590094D03*
X1612615D03*
X1622175Y1614292D03*
Y1602380D03*
X1617915Y1614292D03*
Y1602380D03*
X1610115Y1614292D03*
Y1602380D03*
X1636735Y1578088D03*
X1628935Y1578182D03*
X1624675D03*
X1636735Y1590094D03*
X1628935D03*
X1624675D03*
X1634235Y1614292D03*
Y1602380D03*
X1629975Y1614292D03*
Y1602380D03*
X1640995Y1578182D03*
X1648795D03*
X1640995Y1590094D03*
X1648795D03*
X1646295Y1614292D03*
Y1602380D03*
X1654095Y1614292D03*
Y1602380D03*
X1642035Y1614292D03*
Y1602286D03*
G54D344*
G01X401111Y1028523D02*
Y1026414D01*
X401112Y1026413D01*
G01X480228Y960326D02*
Y962436D01*
G54D335*
G01X577436Y1001782D02*
X577286D01*
X577141Y1001637D01*
X576808D01*
X576672Y1001773D01*
X573058D01*
G01X577436Y1000492D02*
X577286D01*
G01X1549200Y1001773D02*
X1552814D01*
X1552950Y1001637D01*
X1553283D01*
X1553428Y1001782D01*
X1553578D01*
G01X1553428Y1000492D02*
X1553578D01*
G54D326*
G01X191067Y693623D02*
Y689683D01*
G01X1226400Y125200D02*
X1228536Y127336D01*
Y129409D01*
G01X1228518Y156962D02*
X1226093D01*
G01X1228518Y168162D02*
X1226093D01*
G01X1220154Y172945D02*
Y176948D01*
X1220168Y176962D01*
G01X1222724Y176102D02*
X1222074Y176752D01*
X1220378D01*
X1220168Y176962D01*
G01X1228518Y172962D02*
X1226093D01*
G01X1665906Y594959D02*
Y598493D01*
X1665935Y598522D01*
G54D71*
X93361Y1543015D03*
G54D53*
X89981Y702670D03*
X1703413Y706796D03*
G54D26*
X36595Y385068D03*
X46834Y363428D03*
X55190D03*
X54333Y1606850D03*
X57833Y1666350D03*
X53333D03*
X49333D03*
X61000Y1676216D03*
X70333Y1615850D03*
X69833Y1666350D03*
X73833D03*
X77833D03*
X65000Y1676216D03*
X90518Y637121D03*
X82014Y699608D03*
X92096Y694696D03*
X84474Y1520110D03*
X87500Y1561610D03*
X91500D03*
X81833Y1666350D03*
X90297Y1666396D03*
X85833Y1666350D03*
X108643Y523833D03*
X96774Y1526110D03*
X108800Y1608916D03*
X117597Y491407D03*
X113597D03*
X114720Y1680378D03*
X120910Y1723563D03*
X130317Y480329D03*
X135317D03*
X138489Y525465D03*
X134557Y1728198D03*
X149174Y480329D03*
X152470Y502879D03*
X149568Y1389686D03*
X152806Y1408475D03*
X158570Y1523521D03*
X154581Y1523480D03*
X159014Y1573925D03*
X154580D03*
X170673Y1409461D03*
X175067Y1730108D03*
X190110Y569488D03*
X187711Y1389686D03*
X181806Y1390706D03*
X177702D03*
X190949Y1408475D03*
X205320Y670078D03*
X201220D03*
X207716Y1408761D03*
X220387Y1390815D03*
X216090D03*
X212120Y1706778D03*
X237220Y62378D03*
X241220D03*
X249220D03*
X245220D03*
X251487Y104776D03*
X263580Y221118D03*
X270240Y239298D03*
X267759Y254747D03*
X271821D03*
X275797Y124059D03*
X276491Y254747D03*
X281077D03*
X286481D03*
X289274Y293404D03*
X284515D03*
X302517Y68508D03*
X301315Y95815D03*
X305315D03*
X291759Y254747D03*
X304651D03*
X298184Y293404D03*
X302765D03*
X293763D03*
X302684Y559883D03*
X303551Y1347832D03*
X322155Y232235D03*
X317995Y232265D03*
X317129Y254747D03*
X306736Y293404D03*
X316463D03*
X307019Y1366553D03*
X325617Y73879D03*
X338267Y210643D03*
X329648Y254693D03*
X329002Y293404D03*
X335679Y1325034D03*
X338917Y1343823D03*
X336205Y1350863D03*
X331773Y1348969D03*
X324656Y1366707D03*
X354672Y255184D03*
X342000Y255103D03*
X354145Y293082D03*
X341295Y292730D03*
X367306Y255302D03*
X366498Y292755D03*
X367717Y1311608D03*
X366903Y1335191D03*
X370874Y1330399D03*
X363805Y1326133D03*
X356784Y1343909D03*
X379860Y254987D03*
X379112Y292877D03*
X385797Y1395701D03*
X385123Y1631475D03*
X378497Y1631411D03*
X374500Y1642938D03*
X378509Y1682675D03*
X392616Y254977D03*
X392083Y293445D03*
X399935Y1311608D03*
X395933Y1312707D03*
X402973Y1330369D03*
X390029Y1329934D03*
X393699Y1402554D03*
X403125Y1419519D03*
X399134Y1419497D03*
X391293Y1631495D03*
X417765Y255296D03*
X404985Y254906D03*
X417218Y293765D03*
X404215Y293631D03*
X418616Y936164D03*
X410816D03*
X410795Y951181D03*
X414595D03*
X414626Y965580D03*
X418626D03*
X410826D03*
X418595Y951181D03*
X414600Y980093D03*
X410800D03*
X418600D03*
X414600Y994408D03*
X410800D03*
X418600D03*
X418550Y1008966D03*
X410838D03*
X414550D03*
X410816Y1023576D03*
X414591D03*
X418591D03*
X409980Y1393969D03*
X431873Y255296D03*
X429702Y293254D03*
X422395Y936164D03*
X422426Y965580D03*
X422395Y951181D03*
X422400Y980093D03*
X422350Y994408D03*
Y1008966D03*
X422391Y1023576D03*
X432063Y1311608D03*
X428061Y1312707D03*
X434983Y1330398D03*
X421224Y1329934D03*
X442265Y293430D03*
X448520Y416778D03*
X444020D03*
X442520Y470353D03*
X437520D03*
X451520D03*
X451014Y1397495D03*
X442020Y1564953D03*
X446020D03*
X452020Y1574953D03*
X437383Y1597170D03*
X458264Y260973D03*
X467736Y293914D03*
X467211Y366249D03*
X455720Y399278D03*
X462921Y425019D03*
X453020Y416778D03*
X457520D03*
X456520Y470353D03*
X461520D03*
X462704Y965580D03*
X466704Y951181D03*
Y965580D03*
X462704Y951181D03*
X458904D03*
Y965580D03*
X466704Y980093D03*
X458904D03*
X462704D03*
X466704Y994408D03*
X462704D03*
X458904D03*
X466704Y1008966D03*
X458904D03*
X462704D03*
X458904Y1023576D03*
X466704D03*
X462704D03*
X464191Y1311608D03*
X460189Y1312707D03*
X467644Y1330416D03*
X452961Y1329926D03*
X460020Y1574953D03*
X466320Y1596245D03*
X483500Y234878D03*
X474720Y363378D03*
X485020Y416778D03*
X480520D03*
X479169Y470212D03*
X474169D03*
X470504Y951181D03*
Y965580D03*
Y980093D03*
Y994408D03*
Y1008966D03*
Y1023576D03*
X485296Y1329926D03*
X478460Y1442595D03*
X501136Y293214D03*
X490720Y363378D03*
X498720D03*
X486720D03*
X499570Y424878D03*
X489520Y416778D03*
X494020D03*
X498169Y470212D03*
X493169D03*
X488169D03*
X492317Y1312707D03*
X496319Y1325034D03*
X499458Y1343855D03*
X510830Y106188D03*
X507750Y293099D03*
X506720Y363378D03*
X517720Y392878D03*
X505720D03*
X517020Y480968D03*
X517424Y1343909D03*
X506096Y1415333D03*
X518720Y363378D03*
X531720D03*
X523720D03*
X533720Y392878D03*
X521720D03*
X524445Y1326133D03*
X528447Y1347832D03*
X531610Y1366665D03*
X547330Y363258D03*
X548300Y408423D03*
X549552Y1366707D03*
X564698Y363218D03*
X554300Y408423D03*
X564300D03*
X559300D03*
X560969Y1348984D03*
X556586D03*
X557720Y1449878D03*
X552000D03*
X578582Y363173D03*
X573460Y363218D03*
X569340D03*
X571556Y375065D03*
X569152Y416503D03*
X598795Y143168D03*
X594220Y430878D03*
X606079Y121908D03*
X604725Y275146D03*
X607675Y320915D03*
X615635Y320971D03*
X618460Y121908D03*
X621536Y208592D03*
X618115Y275146D03*
X631146Y321006D03*
X623365Y320991D03*
X634500Y79878D03*
X638500D03*
X646815Y512400D03*
X642225Y1702710D03*
X646225D03*
X648320Y84278D03*
X659000Y91878D03*
X650845Y525196D03*
X654895Y518110D03*
X650794Y518123D03*
X663187Y1389711D03*
X651725Y1646210D03*
X654225Y1657710D03*
X650225Y1695710D03*
X667610Y110428D03*
X675220Y524878D03*
X680220D03*
Y511378D03*
X666425Y1408500D03*
X684643Y108901D03*
X688470Y391678D03*
X685220Y498378D03*
X695220Y524878D03*
Y511378D03*
X691321Y1390731D03*
X695425D03*
X684292Y1408586D03*
X708953Y128184D03*
X708720Y380878D03*
X713220Y390878D03*
X705220Y498378D03*
X711220D03*
X705220Y524878D03*
X701330Y1389711D03*
X704568Y1408500D03*
X711719Y1639867D03*
X728220Y380878D03*
Y390878D03*
X718220D03*
X717220Y498378D03*
X723220D03*
X729220D03*
X717220Y511378D03*
X723220D03*
X729220D03*
X722435Y1408586D03*
X715780Y1617446D03*
X719770Y1617436D03*
X723820D03*
X718830Y1649986D03*
X737093Y87993D03*
X737340Y115751D03*
X741270Y115675D03*
X733220Y380878D03*
X740200Y368241D03*
X738220Y390878D03*
X733220D03*
X735173Y524853D03*
X745220Y511378D03*
X735220D03*
X734006Y1390840D03*
X729709D03*
X743462Y1667261D03*
X739538Y1671271D03*
X760193Y93364D03*
X753089Y498393D03*
X749179Y498373D03*
X755859Y1689111D03*
X759359Y1723611D03*
X755359D03*
X764130Y113196D03*
X777220Y438378D03*
X763859Y1689111D03*
X794220Y425378D03*
X782800Y505578D03*
X783450Y516998D03*
X794600Y363216D03*
X802200D03*
X809800D03*
X809600Y383116D03*
X800498Y413142D03*
Y398542D03*
X831539Y62859D03*
X834615Y104297D03*
X835114Y117714D03*
X833715Y225084D03*
X832500Y267230D03*
X832400Y421416D03*
X828300D03*
X840200D03*
X856629Y63009D03*
X850015Y90267D03*
X858783Y224499D03*
X844200Y421416D03*
X863294Y266052D03*
X863571Y293901D03*
X867571D03*
X886503Y271423D03*
X880772Y876851D03*
X909293Y461944D03*
X913293D03*
X920747Y467743D03*
X921720Y1006878D03*
X924747Y467743D03*
X937747D03*
X933747D03*
X931496Y964703D03*
X927220Y1006878D03*
X941747Y467743D03*
X945747D03*
X947275Y976923D03*
X943750Y980168D03*
X985500Y148315D03*
X989605Y175569D03*
X985445Y175599D03*
X988835Y187969D03*
X1005735Y153959D03*
X1001395Y214439D03*
X1019939Y297429D03*
X1031270Y303578D03*
X1033268Y502318D03*
X1052705Y363211D03*
X1095457Y1641366D03*
X1099457D03*
X1115802Y1617786D03*
X1109287Y1669956D03*
X1122879Y1426015D03*
X1126117Y1444804D03*
X1120472Y1617776D03*
X1120432Y1625436D03*
X1151013Y1427035D03*
X1143984Y1444890D03*
X1160720Y183378D03*
X1155117Y1427035D03*
X1161022Y1426015D03*
X1164260Y1444804D03*
X1164830Y1648231D03*
X1159930D03*
X1163576Y1677565D03*
X1181476Y163822D03*
X1182127Y1444890D03*
X1175830Y1648231D03*
X1181930D03*
X1170930D03*
X1174576Y1677565D03*
X1195278Y136065D03*
X1193260Y1427035D03*
X1189156D03*
X1185080Y1619005D03*
X1197400Y1648541D03*
X1186830Y1648231D03*
X1192500Y1648541D03*
X1196146Y1677875D03*
X1185576Y1677565D03*
X1197240Y1694021D03*
X1192340D03*
X1195986Y1723355D03*
X1212202Y117633D03*
X1208010Y1694066D03*
X1203110D03*
X1213910Y1694331D03*
X1206756Y1723400D03*
X1220500Y207378D03*
X1218810Y1694331D03*
X1217556Y1723665D03*
X1263040Y103638D03*
X1258539Y103443D03*
X1259150Y300032D03*
X1255150D03*
X1274520Y81378D03*
X1281913Y79415D03*
X1271150Y300032D03*
X1279812Y1348068D03*
X1291823Y87785D03*
X1287913Y87735D03*
X1295767Y92232D03*
X1298407Y104983D03*
X1294937Y749481D03*
X1283280Y1366789D03*
X1311960Y52524D03*
X1309790Y62316D03*
X1311636Y72522D03*
X1307578Y72520D03*
X1308792Y91317D03*
X1310906Y100705D03*
X1314906D03*
X1311820Y1325034D03*
X1312346Y1350863D03*
X1308140Y1348930D03*
X1315058Y1343823D03*
X1300917Y1366943D03*
X1325902Y62373D03*
X1330102D03*
X1317831Y62316D03*
X1321869Y62298D03*
X1315649Y72521D03*
X1319721D03*
X1324120Y88424D03*
X1329891Y93839D03*
X1322906Y97219D03*
Y104249D03*
X1318906Y100699D03*
X1329646Y107485D03*
X1324093Y247978D03*
X1345083Y93859D03*
X1336549Y108461D03*
X1343858Y1311608D03*
X1339946Y1326133D03*
X1343044Y1335191D03*
X1347015Y1330399D03*
X1332925Y1343909D03*
X1349621Y106738D03*
X1358277Y1396111D03*
X1366124Y104045D03*
X1378550Y118677D03*
X1372074Y1312707D03*
X1376076Y1311608D03*
X1366170Y1329934D03*
X1379114Y1330369D03*
X1377075Y1419497D03*
X1394757Y936163D03*
X1386957D03*
X1390767Y965579D03*
X1394767D03*
X1394736Y951180D03*
X1390736D03*
X1386936D03*
X1386967Y965579D03*
X1394812Y980092D03*
X1390812D03*
X1387012D03*
X1390741Y994407D03*
X1386941D03*
X1394741D03*
X1394691Y1008965D03*
X1390691D03*
X1386891D03*
X1390732Y1023575D03*
X1386869D03*
X1394732D03*
X1386181Y1394169D03*
X1381066Y1419519D03*
X1385720Y1430378D03*
X1398557Y936163D03*
X1398567Y965579D03*
X1398536Y951180D03*
X1398612Y980092D03*
X1398541Y994407D03*
X1398491Y1008965D03*
X1398532Y1023575D03*
X1408204Y1311608D03*
X1404202Y1312707D03*
X1411124Y1330398D03*
X1397365Y1329934D03*
X1398700Y1600298D03*
X1427155Y1397495D03*
X1438845Y965579D03*
X1442845D03*
X1435045D03*
X1442845Y951180D03*
X1438845D03*
X1435045D03*
X1438845Y980092D03*
X1442845D03*
X1435045D03*
X1442845Y994407D03*
X1438845D03*
X1435045D03*
X1438845Y1008965D03*
X1442845D03*
X1435045D03*
X1438845Y1023575D03*
X1435045D03*
X1442845D03*
X1436330Y1312707D03*
X1440332Y1311608D03*
X1429102Y1329926D03*
X1443785Y1330416D03*
X1442573Y1652485D03*
X1451700Y291216D03*
X1445777Y364512D03*
X1449600Y396828D03*
X1446645Y951180D03*
Y965579D03*
Y980092D03*
Y994407D03*
Y1008965D03*
Y1023575D03*
X1461437Y1329926D03*
X1454938Y1442469D03*
X1454207Y1628081D03*
X1459117Y1628061D03*
X1462777Y364512D03*
X1477384Y413804D03*
X1468458Y1312707D03*
X1472460Y1325034D03*
X1475599Y1343855D03*
X1463747Y1628061D03*
X1467840Y1628118D03*
X1473527Y1658065D03*
X1489564Y364214D03*
X1493874D03*
X1481484Y364304D03*
X1489384Y413804D03*
X1493565Y1343909D03*
X1482237Y1415333D03*
X1500904Y382784D03*
X1500586Y1326133D03*
X1504588Y1347832D03*
X1507751Y1366665D03*
X1526118Y113121D03*
X1525693Y1366707D03*
X1539720Y584378D03*
X1532727Y1348984D03*
X1537110D03*
X1543779Y121294D03*
X1556747Y589431D03*
X1552720Y584378D03*
X1546312Y637732D03*
X1550162D03*
X1619515Y114575D03*
X1624353Y1423307D03*
X1627591Y1442096D03*
X1654110Y428718D03*
X1654032Y654025D03*
Y688025D03*
X1652487Y1424327D03*
X1656591D03*
X1645458Y1442182D03*
X1659610Y397218D03*
X1663610D03*
X1663376Y518104D03*
X1667376D03*
X1657632Y550430D03*
X1665706Y586072D03*
X1661506D03*
X1661132Y620525D03*
X1661120Y613978D03*
X1658085Y642127D03*
Y676127D03*
Y710127D03*
X1662496Y1423307D03*
X1665734Y1442096D03*
X1688504Y401576D03*
X1683601Y1442182D03*
X1694314Y428671D03*
X1690154Y428701D03*
X1693648Y466292D03*
X1697648D03*
X1703960Y544019D03*
X1690080Y552273D03*
X1695446Y704034D03*
X1703768Y698922D03*
X1695172Y1424436D03*
X1690875D03*
X1716875Y62485D03*
X1711832Y62249D03*
X1720895Y62485D03*
X1711832Y75737D03*
X1716965Y75725D03*
X1710426Y407679D03*
X1717686Y499493D03*
X1725520Y62378D03*
X1726608Y105900D03*
X1750918Y125183D03*
X1752324Y200508D03*
X1738290Y417356D03*
X1767638Y69632D03*
X1767891Y97336D03*
X1771891D03*
X1779226Y278120D03*
X1778810Y444078D03*
X1790738Y75003D03*
X1802150Y1499496D03*
X1797722Y1499559D03*
X1790011Y1511514D03*
X1813955Y143036D03*
X1849191Y163391D03*
X1836750Y376499D03*
G54D17*
X19983Y193362D03*
Y200362D03*
X30703Y232362D03*
Y240362D03*
X35968Y401000D03*
X60090Y421746D03*
X62257Y1524094D03*
Y1532094D03*
Y1528194D03*
Y1548094D03*
Y1552094D03*
Y1544094D03*
Y1556094D03*
X84857Y391391D03*
Y395865D03*
Y382219D03*
X91284Y428319D03*
Y424319D03*
Y420319D03*
X80974Y436519D03*
Y432519D03*
X91284Y450519D03*
Y446519D03*
X90623Y667734D03*
X91518Y718879D03*
X91703Y1690362D03*
X99638Y169263D03*
X110908Y232128D03*
X107903Y493578D03*
X107933Y497374D03*
Y501374D03*
Y505374D03*
Y509374D03*
Y513374D03*
X98997Y512870D03*
X98803Y696262D03*
X110257Y1528594D03*
Y1532694D03*
Y1552594D03*
Y1556594D03*
X96171Y1593867D03*
Y1585852D03*
Y1589852D03*
X96246Y1611821D03*
Y1605867D03*
Y1623821D03*
X96156Y1634362D03*
Y1638362D03*
X99483Y1655800D03*
Y1651800D03*
X126902Y278875D03*
X126883Y274800D03*
X126902Y306236D03*
X119965Y404571D03*
X127221Y636153D03*
Y640103D03*
X122541Y1589352D03*
X127321Y1604367D03*
X127041Y1637862D03*
X124703Y1696362D03*
X130465Y396071D03*
Y388071D03*
Y392071D03*
Y384071D03*
X134433Y525374D03*
X133020Y1535855D03*
X133172Y1541874D03*
X133264Y1547935D03*
X128041Y1622321D03*
X143803Y1708362D03*
X141550Y1720092D03*
X130540Y1723182D03*
X146980Y510810D03*
Y514810D03*
Y518810D03*
Y526830D03*
X155791Y519281D03*
X151203Y1716362D03*
X161383Y413362D03*
X184879Y421383D03*
Y425383D03*
Y443383D03*
Y430883D03*
X178050Y1723592D03*
X185050Y1729092D03*
Y1733092D03*
X207874Y567981D03*
X200048Y584791D03*
X207874Y601981D03*
X200048Y618791D03*
X207874Y635981D03*
X200048Y652791D03*
X194125Y689683D03*
X196653Y675092D03*
X195933Y1535377D03*
X195874Y1539678D03*
X195766Y1548430D03*
X195674Y1552940D03*
X208203Y1709862D03*
X208101Y1714017D03*
X215037Y420735D03*
Y424735D03*
Y428735D03*
Y436735D03*
Y432735D03*
Y440735D03*
Y444735D03*
Y448735D03*
Y457222D03*
Y462235D03*
X237183Y142062D03*
X233503Y159071D03*
X225696Y1322859D03*
Y1326859D03*
X245203Y75862D03*
X250280Y115743D03*
X249491Y565976D03*
X249948Y598632D03*
X249649Y633848D03*
X245501Y703397D03*
X261964Y64455D03*
X261916Y60345D03*
X261919Y56160D03*
X260780Y87543D03*
X270036Y151203D03*
Y147203D03*
X273803Y210822D03*
X269567Y439605D03*
X269537Y451735D03*
Y447735D03*
X286783Y136962D03*
X285516Y229606D03*
X278483Y451862D03*
Y447862D03*
X290003Y569548D03*
Y566022D03*
X298400Y67513D03*
X298910Y85983D03*
Y82483D03*
X305140Y91767D03*
X293683Y139162D03*
X292603Y634283D03*
Y630757D03*
X290877Y685071D03*
Y688597D03*
X320040Y95803D03*
X320086Y99837D03*
X308083Y146702D03*
X317957Y228258D03*
X309202Y599318D03*
X317708Y595998D03*
X323883Y161562D03*
X323292Y559218D03*
X350521Y142869D03*
X339683Y141862D03*
X349680Y705779D03*
X356203Y225862D03*
X381703Y217362D03*
Y208862D03*
Y212862D03*
Y221362D03*
Y225362D03*
X387823Y1622722D03*
X388643Y119822D03*
Y132822D03*
X398415Y1398653D03*
X402404Y1537810D03*
Y1545810D03*
Y1560810D03*
Y1564810D03*
X406382Y1411231D03*
X407533Y1549942D03*
X414183Y1603500D03*
Y1615200D03*
X415703Y1672362D03*
Y1676362D03*
Y1668362D03*
X432904Y1547810D03*
Y1551810D03*
X430028Y1583466D03*
X421683Y1616600D03*
X421633Y1620402D03*
X421598Y1624692D03*
Y1628692D03*
Y1632842D03*
X422193Y1643159D03*
X422213Y1647216D03*
X421598Y1636842D03*
X449839Y145710D03*
X448311Y505483D03*
Y509483D03*
Y513483D03*
Y517483D03*
Y521483D03*
Y525483D03*
Y542519D03*
Y547519D03*
X444366Y1600154D03*
X459622Y120948D03*
X457983Y213362D03*
Y222362D03*
X453503Y1547437D03*
X471330Y1400435D03*
X471299Y1396606D03*
X469396Y1610682D03*
Y1603682D03*
X474343Y1631003D03*
X469353Y1622735D03*
X469443Y1626732D03*
X474283Y1634947D03*
X475413Y1647242D03*
Y1663242D03*
X475343Y1677462D03*
Y1681462D03*
X488656Y66565D03*
X488766Y61205D03*
X488926Y55895D03*
X492319Y309398D03*
X501643Y615612D03*
X493339Y1424033D03*
X509983Y223362D03*
X505483Y241862D03*
X509154Y1422494D03*
X520308Y168443D03*
X521793Y455062D03*
X519883Y489112D03*
X529873Y500222D03*
X519069Y500469D03*
Y505969D03*
X519883Y495112D03*
X519069Y511469D03*
Y516969D03*
Y522469D03*
Y527969D03*
Y539819D03*
X518483Y615742D03*
X539323Y99172D03*
X539383Y112512D03*
X539547Y269472D03*
X538433Y454270D03*
X555453Y127788D03*
Y137774D03*
Y153878D03*
X552703Y161362D03*
Y184862D03*
Y171862D03*
X567483Y102862D03*
Y98862D03*
X573023Y157932D03*
X582333Y157684D03*
X573703Y225362D03*
Y221362D03*
X569572Y310847D03*
X568308Y424392D03*
X568000Y446706D03*
X580553Y493212D03*
Y488212D03*
Y497212D03*
X570553Y1355247D03*
Y1358777D03*
X595303Y136314D03*
Y125314D03*
X599238Y159480D03*
X584939Y194378D03*
X584703Y230862D03*
X591635Y288527D03*
X612818Y184062D03*
X602703Y416362D03*
X604703Y444362D03*
Y449362D03*
X602882Y454600D03*
X603703Y506862D03*
Y510862D03*
X628519Y208076D03*
Y212076D03*
X630703Y234362D03*
Y230362D03*
X620703Y426362D03*
X619703Y472862D03*
Y477862D03*
Y462862D03*
Y467862D03*
X634400Y88039D03*
Y92119D03*
X648127Y140699D03*
Y149871D03*
Y154345D03*
X642617Y249202D03*
Y260202D03*
X640628Y294327D03*
Y290267D03*
Y306547D03*
X634703Y416362D03*
Y472862D03*
Y477862D03*
Y467862D03*
X636203Y526362D03*
X645203Y1714362D03*
Y1726362D03*
X649203Y184862D03*
X649703Y411362D03*
Y421362D03*
Y426362D03*
Y477862D03*
Y472862D03*
Y482862D03*
X668501Y1647557D03*
X668576Y1659557D03*
X668603Y1664862D03*
Y1676862D03*
X671703Y1712362D03*
Y1728362D03*
X693703Y76962D03*
X693936Y91668D03*
X683436Y119568D03*
Y123420D03*
X694705Y1640667D03*
X694630Y1636667D03*
X695103Y1662862D03*
Y1678862D03*
X713203Y221862D03*
X707595Y1567683D03*
Y1579683D03*
Y1571683D03*
Y1575683D03*
Y1587683D03*
Y1595683D03*
Y1591683D03*
X726616Y160788D03*
X723428Y1564088D03*
X722735Y1569493D03*
X721816Y1680400D03*
X714616D03*
X732976Y86998D03*
X733486Y101968D03*
X741216Y111252D03*
X733486Y105468D03*
X729735Y1569493D03*
X730836Y1614503D03*
X730735Y1609893D03*
X754616Y115288D03*
X754618Y119172D03*
X748728Y137864D03*
X751143Y265322D03*
Y269322D03*
X757595Y1583183D03*
X748138Y1682362D03*
Y1678362D03*
X777903Y163254D03*
X775924Y308755D03*
X776009Y303410D03*
X763703Y413212D03*
Y403212D03*
Y408212D03*
Y398212D03*
X777823Y454862D03*
Y459862D03*
X762823D03*
Y454862D03*
Y474862D03*
X762883Y493452D03*
X765103Y1379962D03*
Y1375462D03*
X765003Y1384062D03*
Y1401562D03*
Y1397262D03*
X764903Y1414762D03*
X768622Y1573793D03*
X768635Y1581893D03*
Y1577893D03*
Y1590893D03*
X763698Y1698521D03*
X782643Y274822D03*
X789109Y303410D03*
X789024Y308755D03*
X790983Y385300D03*
X778703Y393212D03*
X792903Y398212D03*
X792823Y444862D03*
Y439862D03*
Y449862D03*
Y454862D03*
Y459862D03*
Y469862D03*
X808553Y441060D03*
Y445100D03*
X808323Y454862D03*
Y459862D03*
Y449862D03*
Y464862D03*
X810135Y1573793D03*
Y1581793D03*
Y1597793D03*
Y1585793D03*
Y1605793D03*
X820783Y449200D03*
X822323Y476800D03*
Y464862D03*
Y468900D03*
Y472900D03*
X840308Y90451D03*
X842203Y135862D03*
Y129362D03*
X830460Y409260D03*
Y405260D03*
X827983Y449200D03*
X827253Y511082D03*
Y506082D03*
Y527082D03*
Y519082D03*
X851703Y129362D03*
Y135862D03*
X859286Y265057D03*
X846730Y271049D03*
X852383Y473000D03*
Y469100D03*
X852135Y1573793D03*
Y1581793D03*
Y1597793D03*
Y1585793D03*
Y1605793D03*
X874203Y171362D03*
Y176862D03*
X868983Y196500D03*
X868376Y227763D03*
Y223763D03*
X861075Y240441D03*
X859796Y280027D03*
X867526Y289311D03*
X859796Y283527D03*
X862483Y378362D03*
X867969Y386476D03*
Y402581D03*
Y398620D03*
X868021Y414276D03*
X860103Y507162D03*
Y495300D03*
X884283Y201150D03*
Y195720D03*
X884208Y192055D03*
X880926Y293347D03*
X880949Y298665D03*
X902336Y484913D03*
Y480913D03*
X902131Y493299D03*
Y489299D03*
X902116Y501573D03*
Y497573D03*
X894805Y874405D03*
X895375Y920325D03*
X907972Y975134D03*
Y971234D03*
Y992834D03*
Y988934D03*
X894135Y1573793D03*
Y1581793D03*
Y1597793D03*
Y1585793D03*
Y1605793D03*
X936135Y1593393D03*
X946398Y184912D03*
X946318Y188852D03*
X951542Y424298D03*
X951465Y428124D03*
X951438Y437844D03*
X951515Y434018D03*
X948793Y997422D03*
X973076Y356896D03*
X985407Y171483D03*
X994483Y148299D03*
X1001483D03*
X997395Y213233D03*
X1003793Y363352D03*
X1012859Y167278D03*
Y171278D03*
X1018073Y190176D03*
X1017953Y363222D03*
X1037316Y268264D03*
X1030761Y523628D03*
Y514176D03*
X1041352Y509606D03*
X1039093Y523642D03*
X1039513Y514182D03*
X1087204Y69602D03*
X1082172Y83698D03*
X1073904Y265574D03*
X1083093Y379251D03*
X1082973Y369061D03*
X1083033Y374131D03*
X1072638Y386723D03*
X1091273Y1670963D03*
X1107155Y60028D03*
X1113502Y72803D03*
Y77559D03*
X1152020Y73679D03*
X1137625Y1555301D03*
X1139033Y1597630D03*
Y1601630D03*
X1152165Y1626280D03*
X1160503Y211370D03*
X1153563Y363231D03*
X1153493Y368041D03*
X1171354Y61311D03*
Y65811D03*
X1171374Y57111D03*
X1178728Y194174D03*
Y190174D03*
Y206174D03*
Y210174D03*
Y222174D03*
X1198283Y97400D03*
Y89000D03*
Y101600D03*
X1185283Y111600D03*
X1198471Y212648D03*
X1200458Y240672D03*
Y244692D03*
X1196978Y1359636D03*
Y1363146D03*
X1216084Y53860D03*
X1207244Y61060D03*
X1211683Y93600D03*
X1212883Y113200D03*
X1211576Y164962D03*
Y176962D03*
X1213002Y171611D03*
X1210703Y200309D03*
Y195362D03*
X1206568Y1681767D03*
X1219483Y93600D03*
X1225977Y113982D03*
X1220076Y119462D03*
X1231594Y129409D03*
X1220076Y132962D03*
X1231576Y134262D03*
Y153115D03*
X1220080Y148909D03*
Y144909D03*
X1231576Y141110D03*
X1220076Y153962D03*
Y157962D03*
Y168962D03*
Y164962D03*
X1231576Y163462D03*
Y156962D03*
X1220076Y176962D03*
X1231576Y177962D03*
X1220062Y172945D03*
X1220203Y194862D03*
X1245365Y95008D03*
X1235873Y102608D03*
X1235874Y106609D03*
X1242076Y209462D03*
Y205862D03*
Y213462D03*
Y217462D03*
X1237843Y244332D03*
Y248332D03*
X1251076Y233462D03*
Y223462D03*
Y227462D03*
Y237462D03*
Y241462D03*
X1281774Y102928D03*
X1270237Y92724D03*
X1305517Y68562D03*
X1300494Y85138D03*
X1319283Y261662D03*
X1373099Y1403458D03*
X1373156Y1399053D03*
X1373099Y1407458D03*
X1382523Y1411231D03*
X1384120Y1415495D03*
X1408916Y1516435D03*
X1409156Y1532255D03*
X1408916Y1521335D03*
X1400083Y1521362D03*
X1409306Y1543475D03*
X1409156Y1537155D03*
X1409306Y1548375D03*
X1399983Y1537162D03*
Y1548362D03*
X1397891Y1565037D03*
X1402383Y1582500D03*
X1398065Y1576097D03*
X1397891Y1570037D03*
X1402383Y1594000D03*
X1398383Y1609522D03*
X1405483Y1630362D03*
Y1642362D03*
X1424366Y227948D03*
X1417883Y1593700D03*
X1427233Y1612812D03*
X1444183Y60062D03*
X1444905Y1400204D03*
X1444939Y1396269D03*
X1443883Y1598400D03*
Y1611000D03*
X1439283Y1624500D03*
Y1628700D03*
X1431483Y1637362D03*
X1454750Y1526689D03*
X1454990Y1542509D03*
X1455140Y1553729D03*
X1453143Y1590302D03*
X1474050Y64355D03*
X1469480Y1424033D03*
X1487866Y233448D03*
X1487568Y255378D03*
X1485283Y421982D03*
X1485295Y1422494D03*
X1505441Y280056D03*
X1520051Y231116D03*
Y239116D03*
Y249698D03*
Y262616D03*
X1519741Y280956D03*
X1519983Y272362D03*
X1520121Y268214D03*
X1519741Y288956D03*
X1535483Y125362D03*
Y121362D03*
X1529141Y150651D03*
X1540822Y310487D03*
X1549871Y127781D03*
X1553220Y634165D03*
X1563775Y651039D03*
X1591983Y199362D03*
X1591822Y256244D03*
X1600399Y1411169D03*
Y1415669D03*
Y1424669D03*
Y1429169D03*
Y1442669D03*
Y1447153D03*
X1639664Y624475D03*
X1638565Y652601D03*
X1639664Y658475D03*
X1638565Y686601D03*
X1639664Y692475D03*
X1638565Y720601D03*
X1644938Y180460D03*
X1647593Y414202D03*
X1645415Y614845D03*
X1663428Y195935D03*
X1657712Y524071D03*
X1657663Y520540D03*
X1657712Y528071D03*
Y532071D03*
Y540071D03*
Y536071D03*
X1665814Y594959D03*
X1664905Y607291D03*
X1656883Y631703D03*
X1657355Y649681D03*
X1656883Y665703D03*
X1657355Y683681D03*
X1656883Y699703D03*
X1657355Y717681D03*
X1671581Y1497362D03*
Y1512862D03*
Y1505362D03*
Y1524862D03*
Y1537862D03*
Y1541862D03*
Y1553557D03*
X1671656Y1565557D03*
Y1585321D03*
X1688978Y473878D03*
Y469878D03*
X1689003Y465940D03*
X1687414Y478790D03*
Y482790D03*
Y488290D03*
X1682971Y491790D03*
X1686552Y552241D03*
X1695487Y401485D03*
X1690116Y424694D03*
X1696759Y518107D03*
Y513107D03*
Y541507D03*
Y537507D03*
Y545507D03*
Y553527D03*
X1704950Y723005D03*
X1702231Y1500862D03*
Y1520362D03*
Y1541362D03*
X1702511Y1564057D03*
X1703231Y1583821D03*
X1714763Y165909D03*
X1714812Y161900D03*
Y157892D03*
X1714763Y170326D03*
X1718010Y424340D03*
Y420340D03*
X1713563Y499412D03*
X1707518Y531613D03*
X1710403Y701062D03*
X1735277Y61639D03*
X1735325Y65749D03*
X1735280Y57454D03*
X1736101Y88787D03*
X1725401Y116867D03*
X1729517Y181234D03*
X1729348Y177072D03*
Y173072D03*
X1722912Y490869D03*
Y486869D03*
Y482869D03*
Y494869D03*
X1730862Y490869D03*
Y486869D03*
Y480669D03*
X1723632Y1496270D03*
X1754142Y187509D03*
X1754070Y364048D03*
X1754203Y377452D03*
X1754070Y368048D03*
X1754203Y382952D03*
X1763521Y68637D03*
X1764031Y83607D03*
Y87107D03*
X1767910Y364148D03*
X1767703Y372452D03*
X1767910Y368148D03*
X1767703Y377452D03*
X1771761Y92891D03*
X1785161Y96927D03*
X1785119Y100939D03*
X1774858Y173903D03*
Y178403D03*
X1773034Y461393D03*
Y465893D03*
Y470193D03*
X1802782Y161465D03*
X1791871Y1506538D03*
X1818782Y413432D03*
Y417432D03*
X1825670Y170162D03*
X1832362Y399185D03*
X1826822Y434202D03*
X1835434Y453921D03*
X1835424Y467321D03*
Y463193D03*
X1845943Y172187D03*
X1838788Y192678D03*
G54D281*
X1270142Y134311D03*
G36*
G01X453843Y1698263D02*
G02X441043Y1711068I-12800J5D01*
G02X453843Y1698273I0J-12800D01*
G01X449293D01*
G03X441043Y1690017I-8250J-5D01*
G03X449293Y1698263I0J8251D01*
G01X453843D01*
G37*
G36*
G01X1429237Y1698262D02*
G02X1416437Y1711067I-12800J5D01*
G02X1429237Y1698272I0J-12800D01*
G01X1424687D01*
G03X1416437Y1690016I-8250J-5D01*
G03X1424687Y1698262I0J8251D01*
G01X1429237D01*
G37*
G54D227*
X842684Y389140D03*
Y392880D03*
Y396620D03*
X852998D03*
Y392880D03*
Y389140D03*
G54D164*
X400317Y123647D03*
Y126207D03*
X417443D03*
Y123647D03*
X842562Y170918D03*
Y173478D03*
X859688D03*
Y170918D03*
X1049186Y512644D03*
Y515204D03*
X1066312D03*
Y512644D03*
X1742907Y174587D03*
Y177147D03*
X1760033D03*
Y174587D03*
G54D62*
X84430Y1311831D03*
Y1333091D03*
X1093936Y1593314D03*
Y1614574D03*
X1769097Y1310081D03*
Y1331341D03*
G54D155*
X347677Y130002D03*
Y126262D03*
Y122522D03*
X357323D03*
Y130002D03*
X1460023Y60322D03*
Y64062D03*
Y67802D03*
X1450377D03*
Y60322D03*
G54D218*
X771066Y440803D03*
X764374D03*
Y445921D03*
X771066D03*
G54D191*
X536127Y250962D03*
X544001Y254702D03*
X536127Y258442D03*
X642563Y495000D03*
X650437Y491260D03*
Y498740D03*
X755505Y1674823D03*
Y1682303D03*
X763379Y1678563D03*
X793693Y505972D03*
X793673Y516142D03*
Y523622D03*
X806961Y393924D03*
Y408524D03*
Y401404D03*
Y416004D03*
X801567Y509712D03*
Y502232D03*
X801547Y519882D03*
X814835Y397664D03*
Y412264D03*
X1084394Y1650210D03*
X1076520Y1653950D03*
X1084394Y1657690D03*
G54D182*
X485673Y375319D03*
X479767D03*
Y382405D03*
X485673D03*
X499073Y375426D03*
X493167D03*
Y382512D03*
X499073D03*
X515173Y375319D03*
X509267D03*
Y382405D03*
X515173D03*
X513173Y404819D03*
X507267D03*
Y411905D03*
X513173D03*
X532173Y375819D03*
X526267D03*
Y382905D03*
X532173D03*
X529173Y404819D03*
X523267D03*
Y411905D03*
X529173D03*
G54D44*
X68365Y707219D03*
X76265D03*
X68365Y714219D03*
X76265D03*
X185667Y704526D03*
Y697526D03*
X282640Y217602D03*
Y224602D03*
X531220Y295862D03*
Y288862D03*
X764850Y253292D03*
Y260292D03*
X958452Y157603D03*
Y164603D03*
X969390Y212089D03*
Y205089D03*
X979708Y150885D03*
Y157885D03*
X1000582Y273824D03*
Y280824D03*
X1016175Y273690D03*
Y280690D03*
X1008445Y273690D03*
Y280690D03*
X1527618Y296386D03*
Y303386D03*
X1535048Y296386D03*
Y303386D03*
X1667570Y414332D03*
Y421332D03*
X1671306Y584056D03*
Y591056D03*
X1679850Y428172D03*
Y435172D03*
X1689697Y718205D03*
Y711205D03*
X1681797Y718205D03*
Y711205D03*
X1698170Y231982D03*
Y224982D03*
X1747050Y197522D03*
X1740120Y197592D03*
X1747050Y204522D03*
X1740120Y204592D03*
X1784826Y276996D03*
Y283996D03*
X1798926Y273096D03*
Y280096D03*
X1791826Y276996D03*
Y283996D03*
X1790326Y298028D03*
X1797326D03*
X1804326D03*
X1790326Y305028D03*
X1797326D03*
X1804326D03*
X1805986Y273159D03*
Y280159D03*
X1813086Y273159D03*
Y280159D03*
X1811386Y297965D03*
Y304965D03*
X1816784Y1515171D03*
Y1522171D03*
X1823684Y1515171D03*
X1830584D03*
X1823684Y1522171D03*
X1830584D03*
G54D317*
X1758539Y298879D03*
X1772319D03*
G54D263*
X1037026Y286579D03*
G54D290*
X1285767Y165146D03*
Y161207D03*
Y184841D03*
Y180902D03*
Y176963D03*
Y173024D03*
Y169085D03*
Y196657D03*
Y192718D03*
Y188780D03*
Y200596D03*
Y216352D03*
Y212413D03*
Y208474D03*
Y204535D03*
Y220291D03*
X1366987Y165146D03*
Y161207D03*
Y184841D03*
Y180902D03*
Y176963D03*
Y173024D03*
Y169085D03*
Y196657D03*
Y192718D03*
Y188780D03*
Y200596D03*
Y216352D03*
Y212413D03*
Y208474D03*
Y204535D03*
Y220291D03*
G54D137*
X274301Y115216D03*
X707457Y119341D03*
X1749422Y116340D03*
G54D128*
X230906Y1734212D03*
X297835D03*
X495079D03*
X562008D03*
X1238780D03*
X1305709D03*
X1502953D03*
X1569882D03*
G54D272*
X1156378Y133866D03*
G54D146*
X317642Y1308834D03*
Y1318086D03*
X349650Y1285800D03*
Y1295052D03*
X381731Y1272718D03*
Y1281970D03*
X413909Y1272718D03*
Y1281970D03*
X446256Y1272718D03*
Y1281970D03*
X478433Y1272718D03*
Y1281970D03*
X510620Y1285899D03*
Y1295151D03*
X542985Y1308569D03*
Y1317821D03*
X1293783Y1308834D03*
Y1318086D03*
X1325791Y1285800D03*
Y1295052D03*
X1357872Y1272718D03*
Y1281970D03*
X1390050Y1272718D03*
Y1281970D03*
X1422397Y1272718D03*
Y1281970D03*
X1454574Y1272718D03*
Y1281970D03*
X1486761Y1285899D03*
Y1295151D03*
X1519126Y1308569D03*
Y1317821D03*
G54D254*
X1005878Y291426D03*
Y308748D03*
G54D209*
X719199Y1579320D03*
Y1581092D03*
Y1582864D03*
Y1584635D03*
Y1586407D03*
Y1588178D03*
Y1589950D03*
Y1591722D03*
X744691Y1582864D03*
Y1581092D03*
Y1579320D03*
Y1591722D03*
Y1589950D03*
Y1588178D03*
Y1586407D03*
Y1584635D03*
G54D308*
X1713488Y1525698D03*
X1730810D03*
G54D35*
X62106Y169291D03*
Y177165D03*
Y185039D03*
Y192913D03*
Y200787D03*
Y208661D03*
Y216535D03*
Y224409D03*
Y232283D03*
Y240157D03*
X78838Y169291D03*
Y177165D03*
Y185039D03*
Y192913D03*
Y200787D03*
Y208661D03*
Y216535D03*
Y224409D03*
Y232283D03*
Y240157D03*
G54D119*
X211090Y681519D03*
X1645883Y607063D03*
G54D245*
X953904Y1573642D03*
X977270D03*
X1000636D03*
X1024002D03*
X1047368D03*
X1070734D03*
X1094100D03*
X1737611Y1482629D03*
G54D80*
X99460Y641839D03*
Y643414D03*
Y644989D03*
Y646564D03*
Y648139D03*
Y649713D03*
Y651288D03*
Y652863D03*
Y654438D03*
Y656013D03*
X116776Y503281D03*
Y504856D03*
Y506431D03*
Y508006D03*
Y509581D03*
Y511155D03*
Y512730D03*
Y514305D03*
Y515880D03*
Y517455D03*
X118358Y656013D03*
Y654438D03*
Y652863D03*
Y651288D03*
Y649713D03*
Y648139D03*
Y646564D03*
Y644989D03*
Y643414D03*
Y641839D03*
X135674Y509581D03*
Y508006D03*
Y506431D03*
Y504856D03*
Y503281D03*
Y517455D03*
Y515880D03*
Y514305D03*
Y512730D03*
Y511155D03*
X1666555Y529978D03*
Y531553D03*
Y533128D03*
Y534703D03*
Y536278D03*
Y537852D03*
Y539427D03*
Y541002D03*
Y542577D03*
Y544152D03*
X1685453Y542577D03*
Y541002D03*
Y539427D03*
Y537852D03*
Y536278D03*
Y534703D03*
Y533128D03*
Y531553D03*
Y529978D03*
Y544152D03*
X1693311Y477120D03*
Y478695D03*
Y480270D03*
Y481845D03*
Y483420D03*
Y484994D03*
Y486569D03*
Y488144D03*
Y489719D03*
Y491294D03*
X1712209Y477120D03*
Y491294D03*
Y489719D03*
Y488144D03*
Y486569D03*
Y484994D03*
Y483420D03*
Y481845D03*
Y480270D03*
Y478695D03*
G54D236*
X922441Y154311D03*
Y243799D03*
G54D345*
G01X1386684Y145017D02*
Y146182D01*
X1386234Y146632D01*
X1383921D01*
X1382409Y148144D01*
Y149782D01*
G01X1386404Y149008D02*
Y148137D01*
X1386019Y147752D01*
X1384244D01*
X1383429Y148567D01*
Y149782D01*
G54D336*
G01X402528Y943210D02*
X402529Y943209D01*
Y941100D01*
G01X400679Y946414D02*
Y944304D01*
G01X480228Y917576D02*
X480229Y917575D01*
Y915466D01*
G01X1377254Y1026413D02*
X1377253Y1026414D01*
Y1028523D01*
G01X1456370Y917576D02*
Y915467D01*
X1456371Y915466D01*
G01X1456370Y960326D02*
Y962436D01*
G54D327*
G01X14092Y290137D02*
Y287115D01*
G01X22223Y388057D02*
Y396925D01*
X23590Y398292D01*
X29349D01*
X29509Y398132D01*
G01X22419Y387861D02*
X22223Y388057D01*
G01X25981Y387783D02*
X25903Y387861D01*
X22419D01*
G01X29509Y398132D02*
Y396424D01*
X31099Y394834D01*
Y394475D01*
G01X22419Y387861D02*
Y384953D01*
X24550Y382822D01*
X33020D01*
G01X29509Y398132D02*
Y400547D01*
X29962Y401000D01*
G01X36524Y398013D02*
X29628D01*
X29509Y398132D01*
G01X44692Y290637D02*
X41492D01*
G01X36255Y302472D02*
Y304972D01*
G01X42809Y363337D02*
Y360862D01*
G01X39226Y395346D02*
X39090Y395482D01*
Y397112D01*
X38189Y398013D01*
X36524D01*
G01Y395346D02*
Y398013D01*
G01X39410Y384582D02*
X39015Y384977D01*
X36595D01*
G01X36524Y395346D02*
X39226D01*
G01X29962Y401000D02*
X32910D01*
G01X47333Y1659909D02*
X44833D01*
G01X62106Y185039D02*
X54920D01*
G01X62106Y177165D02*
X54920D01*
G01X46834Y363337D02*
Y360862D01*
G01X55190Y363337D02*
Y360862D01*
G01X53825Y421746D02*
X57032D01*
G01X56163Y417078D02*
Y418605D01*
X56874Y419316D01*
Y421588D01*
X57032Y421746D01*
G01X56799Y1524094D02*
X59199D01*
G01Y1528194D02*
X56899D01*
X56799Y1528094D01*
G01Y1532094D02*
X59199D01*
G01X56799Y1544094D02*
X59199D01*
G01X56799Y1548094D02*
X59199D01*
G01X56799Y1552094D02*
X59199D01*
G01X56799Y1556094D02*
X59199D01*
G01X54333Y1606759D02*
Y1604359D01*
G01X53700Y1677775D02*
X50900D01*
G01X73020Y32756D02*
Y37106D01*
G01Y28406D02*
Y32756D01*
G01Y44370D02*
Y48720D01*
G01Y40020D02*
Y44370D01*
G01X65881Y302926D02*
Y305426D01*
G01X71772Y421746D02*
X68683D01*
G01X69523Y417078D02*
Y420906D01*
X68683Y421746D01*
G01X77916Y420319D02*
X75516D01*
G01X77916Y424319D02*
X75516D01*
G01X77916Y436519D02*
X75516D01*
G01X77916Y432519D02*
X75490D01*
G01X74340Y663422D02*
X75280D01*
X77588Y661114D01*
Y659727D01*
G01X73832Y1689362D02*
Y1686810D01*
X73833Y1686809D01*
G01X69833Y1686709D02*
X73733D01*
X73833Y1686809D01*
G01X77833Y1686709D02*
Y1689162D01*
G01X94279Y32756D02*
Y37106D01*
G01Y28406D02*
Y32756D01*
G01X87193D02*
Y37106D01*
G01Y28406D02*
Y32756D01*
G01X80106D02*
Y37106D01*
G01Y28406D02*
Y32756D01*
G01X94279Y44370D02*
Y48720D01*
G01Y40020D02*
Y44370D01*
G01X87193D02*
Y48720D01*
G01Y40020D02*
Y44370D01*
G01X80106D02*
Y48720D01*
G01Y40020D02*
Y44370D01*
G01X78838Y200787D02*
X86490D01*
G01X78838Y208661D02*
X86490D01*
G01X78838Y224409D02*
X85960D01*
G01X78838Y240157D02*
X85788D01*
G01X93400Y282762D02*
X90700D01*
G01X93400Y300262D02*
X90700D01*
G01X84966Y376026D02*
X87654D01*
G01X84949Y386502D02*
X87520D01*
G01X88226Y424319D02*
X85826D01*
G01X88226Y420319D02*
X85826D01*
G01X82661Y449604D02*
X84482D01*
X85397Y450519D01*
X88226D01*
G01X83100Y649762D02*
X81953D01*
X80765Y648574D01*
G01X84274Y1517619D02*
X84474Y1517819D01*
Y1520019D01*
G01X93113Y1585852D02*
X90713D01*
G01X93113Y1589852D02*
X90713D01*
G01X93113Y1593867D02*
X90713D01*
G01X82637Y1631013D02*
Y1629063D01*
X84700Y1627000D01*
G01X93098Y1638362D02*
X90698D01*
G01X93098Y1634362D02*
X90698D01*
G01X88645Y1690362D02*
X86245D01*
G01X81833Y1686709D02*
Y1689162D01*
G01X91805Y1686622D02*
X94220D01*
G01X108453Y32756D02*
Y37106D01*
G01Y28406D02*
Y32756D01*
G01X101366D02*
Y37106D01*
G01Y28406D02*
Y32756D01*
G01X108453Y44370D02*
Y48720D01*
G01Y40020D02*
Y44370D01*
G01X101366D02*
Y48720D01*
G01Y40020D02*
Y44370D01*
G01X105967Y431727D02*
X101317D01*
G01X104845Y493578D02*
X102060D01*
G01X98134Y722501D02*
X98825Y721810D01*
Y718880D01*
G01X99274Y1526019D02*
X96774D01*
G01X110349Y1524594D02*
X112749D01*
G01Y1540594D02*
X110349D01*
G01X112749Y1544594D02*
X110349D01*
G01X112749Y1548594D02*
X110349D01*
G01X112749Y1536594D02*
X110349D01*
G01X112749Y1564594D02*
X110349D01*
G01X112749Y1560594D02*
X110349D01*
G01X104318Y1592304D02*
X104711Y1591911D01*
X106818D01*
G01Y1603690D02*
X104318D01*
G01X108800Y1608825D02*
Y1606600D01*
X110200Y1605200D01*
G01X106818Y1622380D02*
X104318D01*
G01Y1641075D02*
X104972Y1640421D01*
X106818D01*
G01X102480Y1685362D02*
X99980D01*
G01Y1696052D02*
X100290Y1696362D01*
X102480D01*
G01X122626Y32756D02*
Y37106D01*
G01Y28406D02*
Y32756D01*
G01X115539D02*
Y37106D01*
G01Y28406D02*
Y32756D01*
G01X122626Y44370D02*
Y48720D01*
G01Y40020D02*
Y44370D01*
G01X115539D02*
Y48720D01*
G01Y40020D02*
Y44370D01*
G01X114087Y282995D02*
Y285495D01*
G01Y302854D02*
Y300354D01*
G01X127407Y392071D02*
X125007D01*
G01X127407Y388071D02*
X125007D01*
G01X127407Y384071D02*
X125007D01*
G01X127407Y396071D02*
X125007D01*
G01X116907Y404571D02*
X114507D01*
G01X123257Y547506D02*
Y544960D01*
G01D02*
X123327Y545030D01*
X127377D01*
G01X119087Y544870D02*
Y547506D01*
G01X115060D02*
Y544797D01*
G01X110987Y544790D02*
X115053D01*
X115060Y544797D01*
G01X125725Y669400D02*
X129600D01*
G01X116798Y1586288D02*
X116293Y1586793D01*
X114298D01*
G01Y1598572D02*
X116798D01*
G01X114298Y1617262D02*
X116798D01*
G01X114298Y1635303D02*
X116798D01*
G01X114720Y1680287D02*
X117220D01*
G01X124795Y1670362D02*
X127195D01*
G01X117795Y1696362D02*
Y1698862D01*
G01X124795Y1688362D02*
X127195D01*
G01X124795Y1692362D02*
X127195D01*
G01X124795Y1708362D02*
X127195D01*
G01X129713Y32756D02*
Y37106D01*
G01Y28406D02*
Y32756D01*
G01Y44370D02*
Y48720D01*
G01Y40020D02*
Y44370D01*
G01X145624Y396885D02*
X140974D01*
G01X145624Y401885D02*
X140974D01*
G01X145624Y399385D02*
X140974D01*
G01X138492Y1720092D02*
Y1717592D01*
G01X158492Y32756D02*
Y37106D01*
G01Y28406D02*
Y32756D01*
G01X151405D02*
Y37106D01*
G01Y28406D02*
Y32756D01*
G01X158492Y44370D02*
Y48720D01*
G01Y40020D02*
Y44370D01*
G01X151405D02*
Y48720D01*
G01Y40020D02*
Y44370D01*
G01X146971Y423383D02*
X149371D01*
G01X146971Y415062D02*
Y419383D01*
G01D02*
X149371D01*
G01X146971Y427383D02*
X149371D01*
G01X146971Y439383D02*
X149371D01*
G01X146971Y431383D02*
X149371D01*
G01X146971Y435383D02*
X149371D01*
G01X146971Y443383D02*
X149371D01*
G01X172665Y32756D02*
Y37106D01*
G01Y28406D02*
Y32756D01*
G01X165579D02*
Y37106D01*
G01Y28406D02*
Y32756D01*
G01X172665Y44370D02*
Y48720D01*
G01Y40020D02*
Y44370D01*
G01X165579D02*
Y48720D01*
G01Y40020D02*
Y44370D01*
G01X170014Y230928D02*
X174327D01*
G01X166530Y401885D02*
X171180D01*
G01X161475Y409362D02*
X163900D01*
G01X175471Y421383D02*
X177871D01*
G01X175471Y425383D02*
X177871D01*
G01X175471Y430883D02*
X177871D01*
G01X175471Y443383D02*
X177871D01*
G01X168686Y1443390D02*
X171262D01*
G01X170829Y1707678D02*
X166529D01*
G01X162461Y1732967D02*
X166761D01*
G01X179752Y32756D02*
Y37106D01*
G01Y28406D02*
Y32756D01*
G01Y44370D02*
Y48720D01*
G01Y40020D02*
Y44370D01*
G01X186457Y393071D02*
X186266Y392880D01*
X184248D01*
X184057Y393071D01*
G01Y385071D02*
X186457D01*
G01X184057Y389071D02*
X186457D01*
G01X184057Y405071D02*
X186457D01*
G01X184971Y425383D02*
X187371D01*
G01X187532Y421387D02*
X184975D01*
X184971Y421383D01*
G01Y443383D02*
X187371D01*
G01X187490Y568752D02*
X188135Y569397D01*
X190110D01*
G01X193461Y669718D02*
X190977D01*
G01X190800Y675662D02*
X191370Y675092D01*
X193595D01*
G01X191976Y681291D02*
Y684326D01*
G01X176793Y1582549D02*
Y1585173D01*
G01X202626Y32756D02*
Y28406D01*
G01Y37106D02*
Y32756D01*
G01X195539D02*
Y28406D01*
G01Y37106D02*
Y32756D01*
G01X202626Y44370D02*
Y40020D01*
G01Y48720D02*
Y44370D01*
G01X195539D02*
Y40020D01*
G01Y48720D02*
Y44370D01*
G01X205320Y669987D02*
Y667562D01*
G01X205899Y1031168D02*
X210249D01*
G01Y1051247D02*
X205899D01*
G01X196443Y1719697D02*
Y1722197D01*
G01X223886Y32756D02*
Y28406D01*
G01Y37106D02*
Y32756D01*
G01X216799D02*
Y28406D01*
G01Y37106D02*
Y32756D01*
G01X209713D02*
Y28406D01*
G01Y37106D02*
Y32756D01*
G01X223886Y44370D02*
Y40020D01*
G01Y48720D02*
Y44370D01*
G01X216799D02*
Y40020D01*
G01Y48720D02*
Y44370D01*
G01X209713D02*
Y40020D01*
G01Y48720D02*
Y44370D01*
G01X211979Y457222D02*
X209579D01*
G01X210249Y1031168D02*
X214599D01*
G01Y1051247D02*
X210249D01*
G01X230972Y32756D02*
Y28406D01*
G01Y37106D02*
Y32756D01*
G01Y44370D02*
Y48720D01*
G01Y40020D02*
Y44370D01*
G01X233800Y162692D02*
X231890D01*
X230445Y161247D01*
Y159071D01*
G01X228550Y420412D02*
Y423231D01*
X229143Y423824D01*
X229825D01*
G01X245295Y71862D02*
X247720D01*
G01X245295Y75862D02*
X247720D01*
G01X242215Y149438D02*
Y151788D01*
G01X249695Y144320D02*
X252195D01*
G01X249735Y155044D02*
Y152694D01*
G01X242255Y160162D02*
Y162512D01*
G01X266978Y155203D02*
X264578D01*
G01X266978Y159203D02*
X264578D01*
G01X260700Y218662D02*
Y214663D01*
X261341Y214022D01*
X262645D01*
G01X270745Y207562D02*
Y210822D01*
G01X263580Y221027D02*
Y218627D01*
G01X263240Y242357D02*
X265343Y244460D01*
G01X286071Y28406D02*
Y32756D01*
G01X278984Y28406D02*
Y32756D01*
G01X286071Y48720D02*
Y44370D01*
G01X278984Y48720D02*
Y44370D01*
G01X282640Y217602D02*
Y214102D01*
G01X279740Y205962D02*
Y207594D01*
X280855Y208709D01*
G01D02*
Y210802D01*
G01X276890Y249022D02*
X277240Y248672D01*
Y242357D01*
G01X286945Y569548D02*
X284482D01*
G01X286945Y566022D02*
X284482D01*
G01X289545Y630757D02*
X286582D01*
G01X289045Y637809D02*
X286582D01*
G01X289545Y634283D02*
X286582D01*
G01X287819Y688597D02*
Y691097D01*
G01X305025Y146702D02*
Y144202D01*
G01X299628Y151703D02*
Y149203D01*
G01Y156203D02*
Y158703D01*
G01X306087Y569718D02*
Y571678D01*
X305107Y572658D01*
X303147D01*
G01X292195Y637809D02*
X294658D01*
G01X321333Y148598D02*
X324733D01*
G01X320825Y161562D02*
Y159062D01*
G01X324106Y602448D02*
X320691D01*
G01X336240Y147638D02*
Y150738D01*
G01X333174Y380482D02*
X330417D01*
G01X333174Y368261D02*
X330674D01*
G01X336370Y406302D02*
X336138Y406534D01*
X333568D01*
G01X328106Y602448D02*
X324106D01*
G01X336347Y1348353D02*
X336205Y1348495D01*
Y1350772D01*
G01X347677Y122522D02*
X343040D01*
G01X347876Y148462D02*
X344776D01*
G01X353145Y225862D02*
Y228362D01*
G01X345164Y311334D02*
Y314234D01*
G01X340654Y363143D02*
X343411D01*
G01X340654Y375364D02*
X343411D01*
G01X343354Y387988D02*
X341356D01*
X340654Y388690D01*
G01Y400628D02*
X343720D01*
G01X349187Y715485D02*
Y712285D01*
X349808Y711664D01*
Y709995D01*
G01X348804Y1346877D02*
X348160Y1347521D01*
X346244D01*
G01X338917Y1346882D02*
Y1349488D01*
G01X366775Y130162D02*
Y127662D01*
G01X366675Y156202D02*
Y158702D01*
G01X357764Y311334D02*
Y314234D01*
G01X363750Y369362D02*
X366696D01*
X366714Y369344D01*
G01X364014Y382304D02*
X366012D01*
X366714Y381602D01*
G01X366679Y394596D02*
X364179D01*
G01X373800Y400628D02*
X371066D01*
G01X374690Y1631700D02*
X374600Y1631610D01*
X371690D01*
X368331Y1628251D01*
Y1627042D01*
G01X385585Y119822D02*
X383140D01*
G01X378645Y212862D02*
X376245D01*
G01X378645Y217362D02*
X376245D01*
G01X378645Y221362D02*
X376245D01*
G01X378645Y225362D02*
X376245D01*
G01X388480Y323761D02*
X385720D01*
G01X376500Y362736D02*
X374502D01*
X373800Y363438D01*
G01X371370Y373622D02*
X371726D01*
X373800Y375696D01*
G01X376770Y387272D02*
X374564Y389478D01*
X374159D01*
G01X385797Y1395610D02*
X383127D01*
G01X378497Y1631320D02*
X385059D01*
X385123Y1631384D01*
G01X378497Y1631320D02*
X375070D01*
X374690Y1631700D01*
G01X373449Y1634522D02*
X374560Y1633411D01*
Y1631830D01*
X374690Y1631700D01*
G01X388200Y1631384D02*
X385123D01*
G01X375550Y1664844D02*
Y1662052D01*
G01X381068Y1674824D02*
X380668Y1674424D01*
Y1672324D01*
G01X386824Y1678070D02*
Y1682866D01*
G01X394780Y155833D02*
X390830D01*
G01X393415Y209949D02*
X388965D01*
G01X395960Y318643D02*
X398720D01*
G01X401175Y363081D02*
X403675D01*
G01X393695Y368199D02*
X391195D01*
G01X401081Y375880D02*
X403581D01*
G01X391101Y380939D02*
X391160Y380998D01*
X393601D01*
G01X390730Y394852D02*
X391590Y393992D01*
X393590D01*
G01X401070Y388874D02*
X403570D01*
G01X403700Y402422D02*
Y402042D01*
X403403Y401745D01*
X401129D01*
G01X393649Y406863D02*
X390892D01*
G01X399346Y1545810D02*
Y1547385D01*
X396921Y1549810D01*
G01X399346Y1560810D02*
X396946D01*
G01X388220Y1631404D02*
X388200Y1631384D01*
G01X391293Y1631404D02*
X388220D01*
G01X391293D02*
X391273Y1631384D01*
X388200D01*
G01X387925Y1627062D02*
X388200Y1627337D01*
Y1631384D01*
G01X417443Y129061D02*
X413459D01*
G01X411434Y161162D02*
Y163662D01*
G01X409178Y236726D02*
X405478D01*
G01X421769Y368762D02*
X419012D01*
G01X421359Y394722D02*
X418602D01*
G01X421523Y381760D02*
X419023D01*
G01X421482Y407847D02*
X418982D01*
G01X404475Y1549942D02*
Y1552452D01*
G01X419866Y1550046D02*
X422566D01*
G01X411125Y1603500D02*
X408700D01*
G01X411125Y1615200D02*
X409600D01*
X408700Y1614300D01*
G01X426440Y1606441D02*
X423559D01*
X422600Y1607400D01*
Y1609800D01*
X420841Y1611559D01*
X418960D01*
G01X407557Y1658460D02*
X410700D01*
G01X430655Y58677D02*
Y56427D01*
X432066Y55016D01*
X435262D01*
G01X426650Y117491D02*
X429050D01*
G01X437840Y125346D02*
X435340D01*
G01X431295Y214862D02*
X433695D01*
G01X426995Y232562D02*
X429395D01*
G01X426295Y225362D02*
Y227862D01*
G01X426995Y236562D02*
X429395D01*
G01X426995Y240562D02*
X429395D01*
G01X429249Y363644D02*
X432006D01*
G01X429003Y376642D02*
X431503D01*
G01X428839Y389604D02*
X431596D01*
G01X428962Y402729D02*
X431462D01*
G01X436920Y1541562D02*
X435244D01*
X432996Y1543810D01*
G01Y1555810D02*
Y1558322D01*
G01X428099Y1586282D02*
X426970Y1585153D01*
Y1583466D01*
G01X426440Y1606441D02*
X428941D01*
G01X450380Y107747D02*
Y104647D01*
G01X446781Y145710D02*
X443678D01*
G01X445964Y311334D02*
Y314234D01*
G01X445944Y363503D02*
Y359053D01*
G01Y364503D02*
Y363503D01*
G01X446730Y382432D02*
X445944Y383218D01*
Y387503D01*
G01X451720Y411337D02*
X455720D01*
G01X443744Y434003D02*
Y429553D01*
G01X451421Y434003D02*
Y429553D01*
G01X443744Y457003D02*
Y452462D01*
G01X437520Y482412D02*
Y484837D01*
G01X447520Y482412D02*
Y484837D01*
G01X442520Y482412D02*
Y484837D01*
G01X451520Y482412D02*
Y484837D01*
G01X448079Y1559677D02*
Y1562177D01*
G01X443910Y1555602D02*
X442961Y1554653D01*
Y1552197D01*
G01X438020Y1568012D02*
Y1568602D01*
X439728Y1570310D01*
Y1572479D01*
X442128Y1574879D01*
G01X446020Y1568012D02*
Y1570412D01*
G01X440019Y1579509D02*
Y1576809D01*
G01X442578Y1579509D02*
X440019D01*
G01X441308Y1600154D02*
Y1602654D01*
G01X437383Y1600229D02*
Y1602629D01*
G01X454580Y1643282D02*
X451910D01*
G01X454568Y75985D02*
Y78782D01*
G01X466992Y145888D02*
X468173Y147069D01*
X471316D01*
G01X455746Y149864D02*
X453346D01*
G01X458264Y260882D02*
Y254862D01*
G01X467736Y293823D02*
X465236D01*
G01X453621Y363503D02*
Y359053D01*
G01Y364503D02*
Y363503D01*
G01X467211Y366158D02*
X469830D01*
G01X462720Y404762D02*
X463011Y405053D01*
Y410291D01*
X462020Y411282D01*
X455775D01*
X455720Y411337D01*
G01X462720Y402337D02*
Y404762D01*
G01X462921Y424928D02*
X465421D01*
G01X466520Y473412D02*
Y475812D01*
G01X456520Y482412D02*
Y484837D01*
G01X461520Y482412D02*
Y484837D01*
G01X460323Y510183D02*
Y511683D01*
X462012Y513372D01*
X464994D01*
G01X455602Y1412334D02*
X454811Y1413125D01*
X453176D01*
G01X456961Y1562197D02*
Y1559697D01*
G01X456020Y1578012D02*
Y1580412D01*
G01X462079Y1569677D02*
Y1572177D01*
G01X460020Y1578012D02*
Y1580412D01*
G01X454661Y1599255D02*
Y1596755D01*
G01X464160Y1587122D02*
Y1587582D01*
X466320Y1589742D01*
Y1596154D01*
G01X459779Y1606735D02*
Y1609235D01*
G01X464930Y1654807D02*
X468040D01*
G01X475258Y55935D02*
X478240D01*
G01X475328Y66575D02*
X478240D01*
G01X475302Y61129D02*
X478240D01*
G01X484396Y158864D02*
Y161364D01*
G01X471000Y212685D02*
X475500D01*
G01X480393Y433862D02*
Y429412D01*
G01X479379Y452445D02*
X480393Y453459D01*
Y456862D01*
G01X479169Y482271D02*
Y484696D01*
G01X474169Y482271D02*
Y484696D01*
G01X484169Y482271D02*
Y484696D01*
G01X476281Y1419068D02*
X480252D01*
G01X485236Y1417844D02*
X484012Y1419068D01*
X480252D01*
G01X469488Y1614682D02*
Y1618583D01*
X469445Y1618626D01*
G01X472210D02*
X469445D01*
G01X487340Y1641352D02*
X485450Y1643242D01*
X475505D01*
G01X475435Y1673462D02*
X477835D01*
G01X475505Y1667242D02*
X477905D01*
G01X475435Y1685462D02*
X477835D01*
G01X501136Y293123D02*
X498636D01*
G01X489261Y309398D02*
X486861D01*
G01X499570Y424787D02*
X502070D01*
G01X488070Y433862D02*
Y429412D01*
G01X498169Y482271D02*
Y484696D01*
G01X493169Y482271D02*
Y484696D01*
G01X488169Y482271D02*
Y484696D01*
G01X494193Y547947D02*
Y550447D01*
G01X499458Y1346914D02*
Y1349468D01*
G01X510815Y49194D02*
Y53544D01*
G01Y69508D02*
Y65158D01*
G01X517250Y168443D02*
X514850D01*
G01X504075Y228362D02*
Y231262D01*
G01X505575Y237862D02*
X508000D01*
G01X513444Y470181D02*
Y473281D01*
G01X503169Y473271D02*
Y475671D01*
G01X516825Y489112D02*
X514425D01*
G01X516825Y495112D02*
X514425D01*
G01X507093Y539819D02*
X509493D01*
G01X515425Y615742D02*
X513025D01*
G01X506884Y1347521D02*
X509382D01*
G01X517902Y49194D02*
Y53544D01*
G01X524988Y49194D02*
Y53544D01*
G01X532075Y57894D02*
Y53544D01*
G01X517902Y69508D02*
Y65158D01*
G01X532075Y69508D02*
Y65158D01*
G01X524988Y69508D02*
Y65158D01*
G01X531523Y131802D02*
X527823D01*
G01X531523Y149802D02*
X527823D01*
G01X530978Y164726D02*
X527278D01*
G01X531980Y183921D02*
X529480D01*
G01X522641Y447802D02*
X526941D01*
G01X518735Y455062D02*
Y452442D01*
G01X531610Y1369724D02*
X528975D01*
G01X539161Y57894D02*
Y53544D01*
G01X546248Y69508D02*
Y65158D01*
G01X539161Y69508D02*
Y65158D01*
G01X542620Y103352D02*
X539395D01*
G01D02*
X539465Y103422D01*
Y108062D01*
G01X536127Y250962D02*
Y247652D01*
G01X550024Y373573D02*
Y369123D01*
G01Y396573D02*
Y401023D01*
G01X543035Y441005D02*
X544686Y442656D01*
X548670D01*
G01X542554Y462744D02*
X538513D01*
X538120Y463137D01*
G01X542256Y1369935D02*
X541872Y1370319D01*
X539012D01*
G01X560421Y69508D02*
Y65158D01*
G01X553335Y69508D02*
Y65158D01*
G01X555545Y131756D02*
Y134340D01*
G01X550545Y149802D02*
Y147302D01*
G01X565500Y145252D02*
X566020Y144732D01*
X569273D01*
G01X552720Y167937D02*
X555220D01*
G01X567644Y252173D02*
X564944D01*
G01X553536Y307527D02*
X552006Y309057D01*
X550760D01*
G01X557701Y373573D02*
Y369123D01*
G01X559300Y422732D02*
Y420332D01*
G01X565250Y424392D02*
X560960D01*
X559300Y422732D01*
G01X571373Y130542D02*
X567673D01*
G01X583875Y164717D02*
X581175D01*
G01X569965Y157932D02*
Y161232D01*
G01X581881Y202378D02*
X579481D01*
G01X581881Y210378D02*
X579481D01*
G01X581645Y230862D02*
Y233362D01*
G01X578509Y262632D02*
Y265132D01*
G01X569880Y300992D02*
X569764Y301108D01*
Y305247D01*
G01X570200Y372229D02*
X571556Y373585D01*
Y374974D01*
G01X569080Y414002D02*
X569300Y413782D01*
Y411482D01*
G01X569152Y416412D02*
Y414074D01*
X569080Y414002D01*
G01X568092Y451710D02*
X570760D01*
G01X571990Y498546D02*
Y501046D01*
G01X593925Y53544D02*
Y49193D01*
G01X591395Y129642D02*
Y132142D01*
G01X595220Y140922D02*
X588000D01*
G01D02*
X588181Y141103D01*
Y145883D01*
G01X595220Y140922D02*
X597375Y143077D01*
X598795D01*
G01X588000Y140922D02*
X586680D01*
X583430Y144172D01*
Y153432D01*
X586270Y156272D01*
X592640D01*
X592710Y156342D01*
G01D02*
X593299Y155753D01*
Y152575D01*
G01X602306Y143077D02*
X598795D01*
G01X592710Y156342D02*
X597700D01*
X598724Y155318D01*
Y153446D01*
G01X602430Y153862D02*
X602014Y153446D01*
X598724D01*
G01X593248Y159480D02*
X596180D01*
G01X598295Y174612D02*
Y171862D01*
G01X598416Y229965D02*
X593966D01*
G01X589639Y252202D02*
X592039D01*
G01X588577Y288527D02*
Y285862D01*
G01X594220Y430787D02*
X591720D01*
G01X591145Y488212D02*
X593545D01*
G01X596800Y505107D02*
X594090D01*
G01X586760Y519421D02*
X589260D01*
G01X594240Y514303D02*
Y511953D01*
G01X603374Y69508D02*
Y65158D01*
G01X610104Y121817D02*
Y119342D01*
G01X606079Y121817D02*
X610104D01*
G01X606260Y161652D02*
Y163147D01*
X604795Y164612D01*
G01X611030Y188372D02*
X609760Y187102D01*
Y184062D01*
G01X614531Y202878D02*
Y200378D01*
G01Y207378D02*
Y209878D01*
G01X609419Y254966D02*
X606719D01*
G01X611310Y266272D02*
X608720Y268862D01*
X607370D01*
X604725Y271507D01*
Y275055D01*
G01X604779Y426622D02*
Y423862D01*
G01X601645Y444362D02*
X599220D01*
G01X600351Y464768D02*
Y461862D01*
G01X610820Y472862D02*
X610206Y472248D01*
X605469D01*
G01X603779Y489622D02*
Y486922D01*
G01X603795Y514862D02*
X606200D01*
G01X609520Y515162D02*
X614657Y520299D01*
X615480D01*
G01X615185Y53544D02*
Y49193D01*
G01Y69508D02*
Y65158D01*
G01X618460Y121817D02*
Y119342D01*
G01X620030Y188782D02*
X621382Y187430D01*
Y184022D01*
G01X627645Y234362D02*
Y236862D01*
G01X627064Y256277D02*
X629564D01*
G01X623150Y273172D02*
X621267Y275055D01*
X618115D01*
G01X625800Y311912D02*
X625581Y311693D01*
X621992D01*
G01X629248Y436972D02*
X629570Y436650D01*
X631648D01*
G01X631645Y472862D02*
X629220D01*
G01X631645Y477862D02*
X629220D01*
G01X631645Y467862D02*
X629220D01*
G01X645146Y65158D02*
X645053Y65251D01*
Y69411D01*
X645150Y69508D01*
G01X646145Y184862D02*
X642480D01*
G01X646645Y482862D02*
X644245D01*
G01X636960Y512425D02*
Y516002D01*
G01X641386Y1682983D02*
Y1687283D01*
G01X642145Y1714362D02*
X639745D01*
G01X642145Y1726362D02*
X639745D01*
G01X661681Y53544D02*
Y49193D01*
G01X654595Y53544D02*
Y49193D01*
G01X652680Y89712D02*
Y88477D01*
X653820Y87337D01*
G01X651579Y102703D02*
Y105972D01*
X652279Y106672D01*
G01X659000Y91787D02*
Y89262D01*
G01X649575Y93362D02*
Y95527D01*
X652153Y98105D01*
G01X651980Y133822D02*
X651296Y134506D01*
X648236D01*
G01X648219Y144982D02*
X650790D01*
G01X651490Y226602D02*
X656921D01*
X656926Y226597D01*
G01X667020Y225762D02*
X666185Y226597D01*
X656926D01*
G01X651759Y504277D02*
X649218D01*
G01X650437Y498740D02*
X653800D01*
G01X656877Y511757D02*
Y514716D01*
G01X659039Y521166D02*
X661743D01*
G01X654927Y528255D02*
X657734D01*
G01X665545Y1664862D02*
X663145D01*
G01X654225Y1657619D02*
X656725D01*
G01X665545Y1676862D02*
X663145D01*
G01X648290Y1720052D02*
X649930D01*
X650240Y1720362D01*
X651480D01*
G01X675854Y53544D02*
Y49193D01*
G01X668768Y53544D02*
Y49193D01*
G01X666406Y69508D02*
Y65158D01*
G01X669904Y413289D02*
X668329Y411714D01*
G01X676203Y416439D02*
X674628Y414864D01*
G01X676203Y444785D02*
X674628Y443210D01*
G01X673054Y432187D02*
X671479Y430612D01*
G01X673054Y460533D02*
X671479Y462108D01*
G01X669904Y479431D02*
X668329Y481006D01*
G01X675220Y501437D02*
Y503837D01*
G01X680220Y501437D02*
Y503837D01*
G01X675220Y514437D02*
Y516852D01*
G01X666425Y1411559D02*
Y1414200D01*
G01X676312Y1411554D02*
X675668Y1412198D01*
X673752D01*
G01X673612Y1639962D02*
X671112D01*
G01X679148Y1657380D02*
X676648D01*
G01X674880Y1670862D02*
X671620D01*
G01X671795Y1708362D02*
X674195D01*
G01X669120Y1718862D02*
Y1719562D01*
X668320Y1720362D01*
X666795D01*
G01X671795Y1732362D02*
X674195D01*
G01X682941Y69982D02*
Y65158D01*
G01X686760Y222912D02*
X689832Y225984D01*
X694225D01*
G01X680600Y372987D02*
Y375462D01*
G01X685600Y372987D02*
Y375462D01*
G01X690600Y372987D02*
Y375462D01*
G01X695600Y372987D02*
Y375462D01*
G01X688220Y388362D02*
Y385567D01*
X688290Y385497D01*
G01X685652Y416439D02*
X684077Y414864D01*
G01X682503Y425888D02*
X680928Y424313D01*
G01X698251Y438486D02*
X696676Y436911D01*
G01X695101Y444785D02*
X693526Y443210D01*
G01X695101Y441636D02*
X693526Y440061D01*
G01X695101Y438486D02*
X693526Y436911D01*
G01X691951Y441636D02*
X690376Y440061D01*
G01X691951Y435336D02*
X690376Y433761D01*
G01X695101Y451084D02*
X693526Y452659D01*
G01X695101Y447935D02*
X693526Y449510D01*
G01X698251Y454234D02*
X696676Y455809D01*
G01X695101Y454234D02*
X693526Y455809D01*
G01X691951Y451084D02*
X690376Y452659D01*
G01X691951Y457384D02*
X690376Y458959D01*
G01X685652Y476281D02*
X684077Y477856D01*
G01X682503Y466832D02*
X680928Y468407D01*
G01X698251Y476281D02*
X696676Y477856D01*
G01X690220Y514437D02*
Y516852D01*
G01X685015Y1438475D02*
X684975Y1438515D01*
Y1442245D01*
G01X681092Y1634844D02*
X683592D01*
G01X686628Y1652262D02*
X689128D01*
G01X695195Y1658862D02*
X697595D01*
G01X690195Y1670862D02*
X692595D01*
G01X697770Y1680810D02*
X695718Y1682862D01*
X695195D01*
G01X700600Y372987D02*
Y375462D01*
G01X710600Y372987D02*
X705600D01*
G01D02*
Y375462D01*
G01X704550Y422738D02*
X706125Y421163D01*
G01X701400Y416439D02*
X702975Y414864D01*
G01X707699Y438486D02*
X709274Y436911D01*
G01X704550Y441636D02*
X706125Y440061D01*
G01X704550Y438486D02*
X706125Y436911D01*
G01X701400Y441636D02*
X699825Y440061D01*
G01X701400Y438486D02*
X699825Y436911D01*
G01X710849Y444785D02*
X712424Y443210D01*
G01X710849Y441636D02*
X712424Y440061D01*
G01X710849Y438486D02*
X712424Y436911D01*
G01X710849Y454234D02*
X712424Y455809D01*
G01X707699Y454234D02*
X709274Y455809D01*
G01X704550Y454234D02*
X706125Y455809D01*
G01X704550Y451084D02*
X706125Y452659D01*
G01X701400Y454234D02*
X699825Y455809D01*
G01X701400Y451084D02*
X699825Y452659D01*
G01X710849Y451084D02*
X712424Y452659D01*
G01X710849Y447935D02*
X712424Y449510D01*
G01X707699Y476281D02*
X709274Y477856D01*
G01X701400Y466832D02*
X699825Y468407D01*
G01X711220Y514437D02*
Y516852D01*
G01X705220Y514437D02*
Y516852D01*
G01X704568Y1411559D02*
Y1414119D01*
G01X704567Y1563733D02*
Y1567653D01*
X704537Y1567683D01*
G01D02*
Y1571683D01*
G01D02*
X702112D01*
G01X704537Y1575683D02*
X702112D01*
G01X704537Y1579683D02*
X702112D01*
G01X707687Y1583683D02*
X708876D01*
X710056Y1582503D01*
X714480D01*
X716612Y1584635D01*
G01X711719Y1639776D02*
X714203D01*
G01X702462Y1673258D02*
X703880Y1671840D01*
Y1669140D01*
G01X723866Y53544D02*
Y53543D01*
X723860Y53537D01*
Y50462D01*
X722580Y49182D01*
G01X724133Y141288D02*
X723933Y141088D01*
Y138563D01*
G01X715600Y372987D02*
Y375462D01*
G01X728220Y380787D02*
X725220D01*
G01X718220Y390787D02*
Y388362D01*
G01X723447Y416439D02*
X725022Y414864D01*
G01X713999Y435336D02*
X715574Y433761D01*
G01X713999Y457384D02*
X715574Y458959D01*
G01X726597Y447935D02*
X728172Y449510D01*
G01X723447Y476281D02*
X725022Y477856D01*
G01X720370Y1564088D02*
Y1566910D01*
G01X717152Y1570093D02*
X717752Y1569493D01*
X719677D01*
G01X727778Y1614503D02*
X725378D01*
G01X719770Y1617345D02*
Y1614590D01*
G01X715780Y1617355D02*
Y1614590D01*
G01X725910Y1611900D02*
Y1611891D01*
X725552Y1611533D01*
Y1605668D01*
G01X722270Y1627615D02*
Y1624200D01*
X722040Y1623970D01*
G01X721345Y1644550D02*
Y1647300D01*
G01X718830Y1649895D02*
X716140D01*
G01X726830Y1659065D02*
Y1655380D01*
G01X721908Y1676500D02*
X724500D01*
G01X745126Y53544D02*
Y53543D01*
X745125Y53542D01*
Y51800D01*
X744987Y51662D01*
Y49062D01*
G01X745130Y69508D02*
Y65162D01*
X745126Y65158D01*
G01X738043Y69508D02*
Y65162D01*
X738039Y65158D01*
G01X730957Y69508D02*
Y65162D01*
X730953Y65158D01*
G01X733220Y390787D02*
Y388362D01*
G01X736046Y413289D02*
X737621Y411714D01*
G01X729747Y432187D02*
X731322Y430612D01*
G01X729747Y460533D02*
X731322Y462108D01*
G01X736046Y479431D02*
X737621Y481006D01*
G01X745220Y527937D02*
Y530362D01*
G01X743462Y1667170D02*
Y1666178D01*
X744800Y1664840D01*
G01X745080Y1678362D02*
X742655D01*
G01X745080Y1682362D02*
X742655D01*
G01X747488Y53544D02*
Y49063D01*
X747487Y49062D01*
G01X761245Y172636D02*
X758110D01*
G01X748085Y265322D02*
X745685D01*
G01X748085Y269322D02*
X745685D01*
G01X748085Y276322D02*
Y278942D01*
G01X761720Y283262D02*
X762855Y284397D01*
X765160D01*
G01X759940Y438232D02*
X760700Y437472D01*
X776405D01*
X777220Y438287D01*
G01X780020D02*
X782595Y440862D01*
Y448127D01*
X779940Y450782D01*
X760220D01*
X758420Y448982D01*
Y447662D01*
G01D02*
X760220D01*
X761961Y445921D01*
X764374D01*
G01X751220Y527937D02*
Y530362D01*
G01X757687Y1592183D02*
X760112D01*
G01X755505Y1674823D02*
X758830D01*
G01X755859Y1689020D02*
Y1686090D01*
G01X760640Y1698521D02*
Y1696477D01*
X761770Y1695347D01*
G01X754533Y1713264D02*
X755183Y1712614D01*
Y1709850D01*
G01X766769Y143438D02*
Y140138D01*
G01X768725Y167518D02*
X771774D01*
G01X764850Y253292D02*
Y249792D01*
G01X772866Y311558D02*
X772557Y311249D01*
X766718D01*
G01X772866Y308755D02*
Y311558D01*
G01X772951Y303410D02*
Y308670D01*
X772866Y308755D01*
G01X777283Y317392D02*
Y320892D01*
G01X781660Y374665D02*
X776535D01*
X776100Y375100D01*
G01X763795Y418212D02*
X766195D01*
G01X777220Y438287D02*
X780020D01*
G01X762915Y464862D02*
X765315D01*
G01X762915Y488862D02*
X765315D01*
G01X765195Y1379962D02*
X768520D01*
G01X765095Y1388562D02*
Y1392762D01*
G01D02*
X768620D01*
G01X767820Y1410262D02*
X764995D01*
G01D02*
Y1406162D01*
X765095Y1406062D01*
G01X772952Y1587268D02*
X770252D01*
G01X763359Y1726670D02*
Y1729520D01*
G01X782735Y281822D02*
X785135D01*
G01X782735Y267822D02*
X785135D01*
G01X780617Y299279D02*
Y296345D01*
G01X787925Y385300D02*
Y387900D01*
G01X792995Y402500D02*
X795600D01*
G01X778795Y418212D02*
X781195D01*
G01X796546Y416201D02*
X792439D01*
X791590Y417050D01*
G01X780340Y468982D02*
X779460Y469862D01*
X777915D01*
G01X792915Y474862D02*
X795370D01*
G01X793673Y516142D02*
Y512862D01*
G01X794600Y363125D02*
Y360600D01*
G01X809800Y363125D02*
Y360600D01*
G01X802200Y363125D02*
Y360600D01*
G01X799800Y372315D02*
Y368700D01*
G01X806961Y393924D02*
X802417D01*
X802220Y393727D01*
G01X806961Y408524D02*
X803162D01*
X803150Y408512D01*
G01X801567Y509712D02*
Y512942D01*
G01X807077Y1581793D02*
X804652D01*
G01X819114Y117623D02*
Y115223D01*
G01X826614Y150273D02*
X829114D01*
G01X819684Y269698D02*
X813900D01*
G01X827402Y405260D02*
X824980D01*
G01X827402Y409260D02*
X824980D01*
G01X824220Y428437D02*
X821720D01*
G01X817725Y449200D02*
Y444775D01*
X819135Y443365D01*
X821060D01*
G01X817725Y449200D02*
Y450925D01*
X818500Y451700D01*
G01X819265Y476800D02*
X816500D01*
G01X824195Y519082D02*
X821720D01*
G01X813352Y1590893D02*
Y1590068D01*
X815252Y1588168D01*
G01X836126Y62681D02*
X834536Y61091D01*
Y58632D01*
G01X837791Y85186D02*
X840037Y82940D01*
Y81448D01*
G01X834615Y104206D02*
Y88362D01*
X837791Y85186D01*
G01X840037Y81448D02*
Y77832D01*
X841028Y76841D01*
X849355D01*
X853497Y80983D01*
Y90622D01*
X854107Y91232D01*
G01X834615Y104206D02*
X831297D01*
G01X854577Y99651D02*
Y109305D01*
X853586Y110296D01*
X842864D01*
G01X831114Y117623D02*
Y115223D01*
G01X827114Y117623D02*
Y115223D01*
G01X833715Y228143D02*
X830339D01*
G01X827164Y264580D02*
X829680D01*
G01X836210Y275045D02*
Y272452D01*
G01Y275045D02*
Y280045D01*
G01X843672Y271049D02*
X842777D01*
X841786Y270058D01*
X837442D01*
X836390Y271110D01*
Y272272D01*
X836210Y272452D01*
G01X829320Y296762D02*
X830410Y297852D01*
X845505D01*
G01X833300Y386500D02*
X831200Y384400D01*
X830575D01*
G01X842684Y392880D02*
X838784D01*
G01X840200Y421325D02*
X844200D01*
G01X839200Y430185D02*
Y434300D01*
G01X838575Y446800D02*
X841300D01*
G01X839564Y474241D02*
X842341D01*
G01X842600Y477200D02*
X841500D01*
X841100Y476800D01*
X839564D01*
G01X841795Y495362D02*
Y492862D01*
G01X827338Y494000D02*
Y498075D01*
X827345Y498082D01*
G01D02*
X829745D01*
G01X839035Y515447D02*
X834635D01*
G01X854107Y91232D02*
X854577Y91702D01*
Y99651D01*
G01X850088D02*
X854577D01*
G01X851895Y162762D02*
Y160262D01*
G01X843669Y374622D02*
X848000D01*
G01X853100Y410760D02*
X856842D01*
G01X858560Y422131D02*
X857560Y421131D01*
Y417762D01*
G01X844200Y421325D02*
Y418800D01*
G01X849325Y473000D02*
X846700D01*
G01X846010Y505641D02*
X848710D01*
G01X849077Y1581793D02*
X846652D01*
G01X855352Y1590893D02*
Y1590068D01*
X857252Y1588168D01*
G01X874295Y166362D02*
Y163862D01*
G01X859688Y176332D02*
X863488D01*
G01X865925Y196500D02*
Y192125D01*
X864880Y191080D01*
X862232D01*
G01X871980Y199500D02*
X867590D01*
X865925Y197835D01*
Y196500D01*
G01X868061Y382415D02*
X870700D01*
G01X868061Y390620D02*
X870700D01*
G01X868061Y394620D02*
X870700D01*
G01X871320Y416752D02*
X869236Y418836D01*
X868113D01*
G01X860195Y503162D02*
X862620D01*
G01X860195Y499062D02*
X862620D01*
G01X860345Y519582D02*
Y522162D01*
G01Y515582D02*
Y513062D01*
G01X881150Y192055D02*
X878220D01*
G01X880772Y879910D02*
X878192D01*
G01X881372Y918030D02*
Y920655D01*
G01X891077Y1581793D02*
X888652D01*
G01X897000Y886962D02*
Y891895D01*
G01X897352Y1590893D02*
Y1590068D01*
X899252Y1588168D01*
G01X931950Y979362D02*
Y975372D01*
X936730Y970592D01*
X943380D01*
X946865Y974077D01*
G01X963610Y981292D02*
Y974002D01*
X962250Y972642D01*
X953235D01*
G01Y977250D02*
Y972642D01*
G01D02*
X953125Y972752D01*
X948230D01*
X946905Y974077D01*
X946865D01*
G01D02*
Y976422D01*
X947275Y976832D01*
G01X946938Y991162D02*
X958850D01*
X959535Y990477D01*
G01X947348Y988652D02*
X946938Y989062D01*
Y991162D01*
G01X965792Y350959D02*
Y341373D01*
X967175Y339990D01*
X974791D01*
G01X970738Y350959D02*
X965792D01*
G01D02*
Y355127D01*
X967561Y356896D01*
X970018D01*
G01X959535Y990477D02*
X962105D01*
X963610Y988972D01*
Y981292D01*
G01X959535Y985596D02*
Y990477D01*
G01X961365Y997496D02*
X963780D01*
G01X988835Y185443D02*
X988739Y185347D01*
X984699D01*
G01X988835Y187878D02*
Y185443D01*
G01X979084Y344659D02*
X985016D01*
G01X974791Y339990D02*
X982145D01*
X985016Y342861D01*
Y344659D01*
G01D02*
X984751Y344924D01*
Y353028D01*
X980869Y356910D01*
G01X986182Y363660D02*
Y361062D01*
G01D02*
Y359681D01*
X983411Y356910D01*
X980869D01*
G01X994553Y365711D02*
X996598Y363666D01*
Y363155D01*
G01X1023220Y185174D02*
Y187574D01*
G01X1038294Y509606D02*
Y506504D01*
G01X1072310Y364422D02*
X1071101Y365631D01*
X1067070D01*
G01X1077751Y522235D02*
X1073574Y518058D01*
X1066312D01*
G01X1079225Y55682D02*
X1075100D01*
G01X1084146Y69602D02*
Y67102D01*
G01X1079915Y369061D02*
X1077270D01*
G01X1079975Y374131D02*
X1077270D01*
G01X1080035Y379251D02*
X1077270D01*
G01X1076739Y509645D02*
Y506461D01*
G01X1096357Y1650635D02*
Y1653213D01*
X1094800Y1654770D01*
X1085310D01*
X1084394Y1655686D01*
Y1657690D01*
G01X1097794Y65262D02*
Y67881D01*
G01X1099861Y78461D02*
X1102561D01*
G01X1095457Y1641275D02*
Y1639067D01*
X1095649Y1638875D01*
G01X1099457Y1641275D02*
Y1638875D01*
G01X1095900Y1646935D02*
Y1647000D01*
X1096357Y1647457D01*
Y1650635D01*
G01X1101605Y1675970D02*
X1103977D01*
X1104457Y1675490D01*
G01X1101605Y1679870D02*
Y1675970D01*
G01X1105457Y1673025D02*
X1103431D01*
X1102930Y1672524D01*
Y1668690D01*
G01X1105553Y356475D02*
X1109429Y360351D01*
Y364235D01*
G01X1138512Y52926D02*
X1132856D01*
G01X1134567Y1555301D02*
X1132142D01*
G01X1120472Y1617685D02*
Y1615010D01*
G01X1124762Y1628485D02*
X1127377D01*
G01X1134512Y1625969D02*
X1131632D01*
G01X1148962Y73679D02*
X1145603D01*
G01X1153264Y197407D02*
X1150914D01*
G01X1150704Y222677D02*
X1148354D01*
G01X1140465Y377011D02*
Y379592D01*
G01X1145108Y1479313D02*
Y1476732D01*
G01X1141992Y1620851D02*
X1139392D01*
G01X1160720Y183287D02*
Y180862D01*
G01X1158382Y204887D02*
X1160732D01*
G01X1155822Y230157D02*
X1158172D01*
G01X1153585Y373231D02*
X1156790D01*
G01X1163839Y1605511D02*
X1166811D01*
X1168192Y1604130D01*
G01X1152545Y1618960D02*
Y1616875D01*
X1152950Y1616470D01*
G01X1156086Y1630090D02*
Y1633880D01*
G01D02*
X1152930D01*
G01X1159930Y1648140D02*
Y1645632D01*
G01X1164830Y1648140D02*
Y1645632D01*
G01X1158671Y1665575D02*
Y1667580D01*
X1160203Y1669112D01*
X1161613D01*
G01D02*
X1163789Y1671288D01*
Y1673055D01*
G01X1175670Y190174D02*
Y194174D01*
G01D02*
X1173065D01*
G01X1175670Y206174D02*
Y210174D01*
G01D02*
X1172865D01*
G01X1175670Y222174D02*
X1172795D01*
G01X1182041Y1031168D02*
X1186391D01*
G01X1182041Y1051247D02*
X1186391D01*
G01X1185080Y1618914D02*
X1182470D01*
G01X1181930Y1648140D02*
Y1645632D01*
G01X1175830Y1648140D02*
Y1645632D01*
G01X1170930Y1648140D02*
Y1645632D01*
G01X1180671Y1665575D02*
Y1667580D01*
X1182203Y1669112D01*
X1183613D01*
G01X1169671Y1665575D02*
Y1667580D01*
X1171203Y1669112D01*
X1172613D01*
G01X1183613D02*
X1185789Y1671288D01*
Y1673055D01*
G01X1172613Y1669112D02*
X1174789Y1671288D01*
Y1673055D01*
G01X1185546Y65811D02*
Y61411D01*
X1185646Y61311D01*
G01X1185566Y57111D02*
Y61231D01*
X1185646Y61311D01*
G01X1185566Y57111D02*
X1188364D01*
X1188720Y56755D01*
G01X1195225Y97400D02*
X1192300D01*
X1190700Y99000D01*
G01X1185500Y101400D02*
Y96901D01*
X1193401Y89000D01*
X1195225D01*
G01X1197627Y132859D02*
X1195278Y135208D01*
Y135974D01*
G01X1196551Y127804D02*
Y131783D01*
X1197627Y132859D01*
G01X1197400Y240672D02*
X1194840D01*
G01X1186391Y1031168D02*
X1190741D01*
G01X1186391Y1051247D02*
X1190741D01*
G01X1185030Y1630536D02*
Y1633010D01*
G01X1186830Y1648140D02*
Y1645632D01*
G01X1192500Y1648450D02*
Y1645942D01*
G01X1197400Y1648450D02*
Y1645942D01*
G01X1191341Y1665885D02*
X1191241Y1665985D01*
Y1668480D01*
X1192183Y1669422D01*
X1194183D01*
G01X1196459Y1673365D02*
X1196359Y1673265D01*
Y1671598D01*
X1194183Y1669422D01*
G01X1197240Y1693930D02*
Y1691422D01*
G01X1192340Y1693930D02*
Y1691422D01*
G01X1194023Y1714902D02*
X1196199Y1717078D01*
Y1718845D01*
G01X1191081Y1711365D02*
Y1713370D01*
X1192613Y1714902D01*
X1194023D01*
G01X1213026Y53860D02*
Y56742D01*
G01X1230250Y89450D02*
X1220460Y79660D01*
X1209735D01*
G01X1208625Y93600D02*
X1202800D01*
X1201800Y94600D01*
G01X1204800Y108900D02*
Y104600D01*
X1205600Y103800D01*
X1208885D01*
G01X1209825Y113200D02*
X1209600D01*
X1206900Y115900D01*
G01X1217022Y144909D02*
Y148909D01*
G01D02*
X1214573D01*
G01X1204420Y195362D02*
X1207645D01*
G01D02*
Y200309D01*
G01X1223720Y217862D02*
X1219355Y222227D01*
X1216610D01*
G01X1210084Y228495D02*
Y224362D01*
G01X1210457Y1661115D02*
Y1658415D01*
G01X1203510Y1681767D02*
X1201110D01*
G01X1213980Y1673963D02*
Y1676500D01*
G01X1208010Y1693975D02*
Y1691467D01*
G01X1203110Y1693975D02*
Y1691467D01*
G01X1213910Y1694240D02*
Y1691732D01*
G01X1201851Y1711410D02*
Y1713415D01*
X1203383Y1714947D01*
X1204793D01*
G01X1212651Y1711675D02*
Y1713680D01*
X1214183Y1715212D01*
X1215593D01*
G01X1204793Y1714947D02*
X1206969Y1717123D01*
Y1718890D01*
G01X1215593Y1715212D02*
X1217769Y1717388D01*
Y1719155D01*
G01X1228420Y58862D02*
X1231138Y61580D01*
X1232955D01*
G01X1226093Y152792D02*
X1226416Y153115D01*
X1228518D01*
G01X1234785Y244332D02*
X1232000D01*
G01X1234785Y248332D02*
X1232000D01*
G01X1218810Y1694240D02*
Y1691732D01*
G01X1242307Y95008D02*
X1239907D01*
G01X1239018Y213462D02*
Y217462D01*
G01D02*
X1236584D01*
G01X1248018Y227462D02*
X1245614D01*
G01X1267179Y92724D02*
X1264620D01*
G01X1252040Y306480D02*
X1251150Y305590D01*
Y303091D01*
G01X1263150D02*
X1267150D01*
G01X1278300Y81232D02*
X1278245Y81287D01*
X1274520D01*
G01X1281913Y79324D02*
X1279028D01*
X1278300Y80052D01*
Y81232D01*
G01X1279485Y105752D02*
Y105412D01*
X1278716Y104643D01*
Y102928D01*
G01X1267150Y303091D02*
Y305998D01*
G01X1280312Y1365689D02*
X1279834Y1365211D01*
Y1361664D01*
G01X1293430Y84072D02*
X1294496Y85138D01*
X1297436D01*
G01X1291823Y87694D02*
X1293430Y86087D01*
Y84072D01*
G01X1287913Y87644D02*
X1291773D01*
X1291823Y87694D01*
G01X1294937Y749390D02*
Y746965D01*
G01X1283280Y1369848D02*
Y1372301D01*
G01X1291482Y1370043D02*
X1293887D01*
G01X1311960Y52433D02*
Y49672D01*
G01X1315649Y72430D02*
Y70613D01*
X1314741Y69705D01*
Y68652D01*
G01X1311636Y72431D02*
X1311637Y72430D01*
X1315649D01*
G01X1325902Y62282D02*
X1330102D01*
G01D02*
Y59025D01*
G01X1317831Y65375D02*
Y68652D01*
G01X1327920Y84418D02*
X1327332Y83830D01*
Y80451D01*
G01X1316478Y89007D02*
Y92970D01*
G01X1358277Y1396020D02*
X1355357D01*
G01X1378550Y118586D02*
Y110692D01*
G01X1395007Y1576097D02*
X1392475D01*
G01X1405858Y1516435D02*
X1403350D01*
G01X1406098Y1532255D02*
X1403590D01*
G01X1405858Y1521335D02*
X1403350D01*
G01X1406248Y1548375D02*
X1403740D01*
G01X1406098Y1537155D02*
X1403590D01*
G01X1406248Y1543475D02*
X1403740D01*
G01X1399325Y1582500D02*
X1396600D01*
G01X1399325Y1594000D02*
X1396600D01*
G01X1408250Y1600723D02*
Y1603282D01*
G01X1408260Y1588559D02*
Y1590340D01*
X1407200Y1591400D01*
G01X1398700Y1600207D02*
Y1597800D01*
G01X1408250Y1603282D02*
X1411070D01*
G01X1402425Y1630362D02*
X1400000D01*
G01X1402425Y1642362D02*
X1400000D01*
G01X1416800Y1564862D02*
X1417830D01*
X1419760Y1562932D01*
X1422534D01*
G01X1428403Y1581378D02*
X1427940Y1581841D01*
Y1585323D01*
G01X1415740Y1583441D02*
X1418241D01*
G01X1423845Y1603262D02*
X1426680D01*
G01X1427345Y1608442D02*
X1430250D01*
G01X1426750Y1623391D02*
X1429250D01*
G01X1419270Y1628509D02*
Y1631000D01*
G01X1425770Y1633772D02*
X1424739Y1634803D01*
X1423240D01*
G01X1413230Y1641042D02*
X1414351Y1639921D01*
X1415760D01*
G01X1441125Y60062D02*
Y57362D01*
G01X1441490Y224062D02*
X1440199Y222771D01*
X1436383D01*
G01X1435880Y251265D02*
X1431430D01*
G01X1431829Y1412370D02*
X1431074Y1413125D01*
X1429317D01*
G01X1436330Y1521152D02*
X1438506Y1518976D01*
X1440273D01*
G01X1432793Y1524094D02*
X1434798D01*
X1436330Y1522562D01*
Y1521152D01*
G01X1440513Y1534796D02*
X1438746D01*
X1436570Y1536972D01*
G01D02*
Y1538382D01*
X1435038Y1539914D01*
X1433033D01*
G01X1436720Y1548192D02*
X1438896Y1546016D01*
X1440663D01*
G01X1433183Y1551134D02*
X1435188D01*
X1436720Y1549602D01*
Y1548192D01*
G01X1446600Y1595400D02*
X1443255Y1592055D01*
Y1590382D01*
G01X1440825Y1598400D02*
X1438300D01*
G01X1440825Y1611000D02*
X1438300D01*
G01X1439375Y1620300D02*
X1441800D01*
G01X1439375Y1632900D02*
X1441800D01*
G01X1460023Y67802D02*
X1464200D01*
G01X1453670Y281190D02*
Y278170D01*
G01X1458300Y361663D02*
Y364387D01*
G01X1445777Y364421D02*
Y362021D01*
G01X1449777Y364421D02*
Y362021D01*
G01X1451780Y410497D02*
X1449296D01*
G01X1456393Y1419068D02*
X1452422D01*
G01X1461377Y1417844D02*
X1460153Y1419068D01*
X1456393D01*
G01X1457540Y1602441D02*
X1460441D01*
G01X1446786Y1610639D02*
Y1609115D01*
X1448342Y1607559D01*
X1450060D01*
G01X1463747Y1627970D02*
X1459117D01*
G01X1451580Y1627990D02*
X1454207D01*
G01X1459117Y1627970D02*
X1454227D01*
X1454207Y1627990D01*
G01X1452757Y1676702D02*
Y1671399D01*
G01X1474458Y225448D02*
X1476858D01*
G01X1466958Y242448D02*
Y244948D01*
G01X1466660Y271378D02*
Y273878D01*
G01X1462777Y364421D02*
Y362021D01*
G01X1470877Y374496D02*
X1470954Y374573D01*
Y378996D01*
G01X1463277Y401996D02*
Y406446D01*
G01X1470954Y401996D02*
Y406446D01*
G01X1473527Y1657974D02*
X1476570D01*
G01X1486884Y378788D02*
Y374338D01*
G01X1479207Y378788D02*
Y374338D01*
G01X1478203Y406207D02*
X1479207Y405203D01*
Y401788D01*
G01X1493384Y419263D02*
X1491975Y420672D01*
Y421982D01*
G01X1493384Y416863D02*
Y419263D01*
G01Y416863D02*
X1497384D01*
G01X1481384Y419392D02*
X1482225Y420233D01*
Y421982D01*
G01X1481384Y416863D02*
Y419392D01*
G01X1500904Y382693D02*
X1503450D01*
G01X1507751Y1369724D02*
X1505116D01*
G01X1519575Y116462D02*
Y114887D01*
X1521432Y113030D01*
X1522920D01*
G01X1526118D02*
X1522920D01*
G01X1526083Y150651D02*
Y146225D01*
G01X1513759Y263676D02*
X1514819Y262616D01*
X1516993D01*
G01X1511476Y288030D02*
Y291027D01*
X1511624Y291175D01*
G01X1535320Y113062D02*
X1539397Y108985D01*
Y106732D01*
G01X1526224Y129602D02*
X1529500D01*
G01X1526675Y136146D02*
Y140117D01*
G01X1540989Y622038D02*
Y616587D01*
G01X1547429Y32756D02*
Y28406D01*
G01Y32756D02*
Y37106D01*
G01X1554515Y32756D02*
Y28406D01*
G01Y32756D02*
Y37106D01*
G01Y44370D02*
Y40020D01*
G01Y44370D02*
Y48720D01*
G01X1547429Y44370D02*
Y48720D01*
G01Y44370D02*
Y40020D01*
G01X1549881Y138263D02*
X1554239D01*
G01X1545447Y156035D02*
X1545527Y155955D01*
Y152873D01*
G01X1554723Y200375D02*
X1554724Y200374D01*
Y192657D01*
G01Y211909D02*
Y200376D01*
X1554723Y200375D01*
G01X1554724Y211909D02*
Y224528D01*
X1554723Y224529D01*
G01D02*
X1554724Y224530D01*
Y236909D01*
G01X1554723Y248945D02*
X1554724Y248946D01*
Y256161D01*
G01Y236909D02*
Y248944D01*
X1554723Y248945D01*
G01X1556747Y589340D02*
X1559387D01*
G01X1554727Y631527D02*
X1555210Y632010D01*
X1557287D01*
G01X1561602Y32756D02*
Y28406D01*
G01Y32756D02*
Y37106D01*
G01X1568688Y32756D02*
Y28406D01*
G01Y32756D02*
Y37106D01*
G01Y44370D02*
Y40020D01*
G01Y44370D02*
Y48720D01*
G01X1561602Y44370D02*
Y40020D01*
G01Y44370D02*
Y48720D01*
G01X1560717Y651039D02*
Y648522D01*
G01X1570720Y729362D02*
X1569031Y731051D01*
Y732165D01*
G01X1575775Y32756D02*
Y28406D01*
G01Y32756D02*
Y37106D01*
G01X1582862Y32756D02*
Y28406D01*
G01Y32756D02*
Y37106D01*
G01X1589948Y32756D02*
Y28406D01*
G01Y32756D02*
Y37106D01*
G01Y44370D02*
Y40020D01*
G01Y44370D02*
Y48720D01*
G01X1582862Y44370D02*
Y40020D01*
G01Y44370D02*
Y48720D01*
G01X1575775Y44370D02*
Y40020D01*
G01Y44370D02*
Y48720D01*
G01X1597035Y32756D02*
Y28406D01*
G01Y32756D02*
Y37106D01*
G01X1604122Y32756D02*
Y28406D01*
G01Y32756D02*
Y37106D01*
G01Y44370D02*
Y48720D01*
G01Y44370D02*
Y40020D01*
G01X1597035Y44370D02*
Y40020D01*
G01Y44370D02*
Y48720D01*
G01X1596444Y215526D02*
Y217768D01*
X1594686Y219526D01*
X1592153D01*
G01X1591894Y252126D02*
Y248028D01*
X1591914Y248008D01*
G01X1598030Y251002D02*
X1595036Y248008D01*
X1591914D01*
G01X1619515Y117634D02*
X1619882Y117267D01*
X1623521D01*
X1623881Y117627D01*
G01X1625814Y32756D02*
Y28406D01*
G01Y32756D02*
Y37106D01*
G01X1632901Y32756D02*
Y28406D01*
G01Y32756D02*
Y37106D01*
G01X1639988Y32756D02*
Y28406D01*
G01Y32756D02*
Y37106D01*
G01X1625814Y44370D02*
Y40020D01*
G01Y44370D02*
Y48720D01*
G01X1632901Y44370D02*
Y40020D01*
G01Y44370D02*
Y48720D01*
G01X1639988Y44370D02*
Y40020D01*
G01Y44370D02*
Y48720D01*
G01X1623881Y117627D02*
X1626458D01*
G01D02*
Y121627D01*
G01Y129627D02*
X1623881D01*
G01X1636393Y181778D02*
X1637711Y180460D01*
X1641880D01*
G01X1641290Y196188D02*
X1635032D01*
G01X1644360Y205815D02*
X1640096D01*
X1632899Y213012D01*
G01X1654161Y32756D02*
Y28406D01*
G01Y32756D02*
Y37106D01*
G01X1647074Y32756D02*
Y28406D01*
G01Y32756D02*
Y37106D01*
G01Y44370D02*
Y40020D01*
G01Y44370D02*
Y48720D01*
G01X1654161Y44370D02*
Y40020D01*
G01Y44370D02*
Y48720D01*
G01X1644535Y414202D02*
X1642135D01*
G01X1647110Y431777D02*
Y434177D01*
G01X1654605Y520540D02*
X1651890D01*
G01X1649220Y618237D02*
Y620662D01*
G01X1646182Y1476695D02*
X1648947D01*
G01X1669948Y32756D02*
Y28406D01*
G01Y32756D02*
Y37106D01*
G01Y44370D02*
Y40020D01*
G01Y44370D02*
Y48720D01*
G01X1668100Y180852D02*
X1666561Y179313D01*
X1660636D01*
G01X1668030Y200580D02*
X1667790Y200820D01*
X1664660D01*
X1656982Y208498D01*
Y209120D01*
G01X1671605Y201670D02*
X1669120D01*
X1668030Y200580D01*
G01X1661110Y431777D02*
Y434177D01*
G01X1664040Y567227D02*
Y569642D01*
G01X1668040Y567227D02*
Y569642D01*
G01X1672040Y567227D02*
Y569642D01*
G01X1664997Y607291D02*
Y604762D01*
G01X1657220Y618237D02*
Y620662D01*
G01X1668523Y1497362D02*
X1666123D01*
G01X1668523Y1501362D02*
X1666123D01*
G01X1668523Y1512862D02*
X1665940D01*
G01X1666110Y1504662D02*
X1666810Y1505362D01*
X1668523D01*
G01Y1520862D02*
X1666123D01*
G01X1668523Y1537862D02*
X1666123D01*
G01X1668523Y1541862D02*
X1666123D01*
G01X1677035Y32756D02*
Y28406D01*
G01Y32756D02*
Y37106D01*
G01X1684122Y32756D02*
Y28406D01*
G01Y32756D02*
Y37106D01*
G01X1677035Y44370D02*
Y40020D01*
G01Y44370D02*
Y48720D01*
G01X1684122Y44370D02*
Y40020D01*
G01Y44370D02*
Y48720D01*
G01X1680040Y567227D02*
X1676040D01*
G01D02*
Y569627D01*
G01X1682008Y1503421D02*
X1679508D01*
G01X1682008Y1522921D02*
X1679508D01*
G01X1682008Y1543921D02*
X1679508D01*
G01X1682008Y1563380D02*
X1679508D01*
G01X1682008Y1583880D02*
X1679508D01*
G01X1691208Y32756D02*
Y28406D01*
G01Y32756D02*
Y37106D01*
G01X1698295Y32756D02*
Y28406D01*
G01Y32756D02*
Y37106D01*
G01X1697824Y39974D02*
X1698295Y40445D01*
Y44370D01*
G01D02*
Y48720D01*
G01X1691208Y44370D02*
Y40020D01*
G01Y44370D02*
Y48720D01*
G01X1703720Y506937D02*
Y509362D01*
G01X1698720Y506937D02*
X1696120D01*
G01X1689488Y1498303D02*
X1691988D01*
G01X1689488Y1517803D02*
X1691988D01*
G01X1689488Y1538803D02*
X1691988D01*
G01X1689488Y1558262D02*
X1691988D01*
G01X1705381Y32756D02*
Y28406D01*
G01Y32756D02*
Y37106D01*
G01Y44370D02*
Y48720D01*
G01X1710106Y44370D02*
Y48720D01*
G01Y44370D02*
Y40020D01*
G01X1710920Y82162D02*
X1711832Y81250D01*
Y78796D01*
G01X1714904Y157892D02*
Y155514D01*
X1714180Y154790D01*
G01X1714792Y174970D02*
X1717280D01*
G01X1721400Y374462D02*
X1722500Y373362D01*
Y371937D01*
G01X1706602Y655141D02*
X1709027D01*
G01X1709107Y725360D02*
Y728449D01*
G01X1723240Y185200D02*
X1725262D01*
X1726459Y184003D01*
Y181234D01*
G01X1725400Y372062D02*
X1726094Y371368D01*
X1729480D01*
G01X1725500Y380937D02*
Y383662D01*
G01X1737434Y402130D02*
Y398990D01*
G01X1730290Y420415D02*
X1727760D01*
G01X1753393Y32756D02*
Y28365D01*
X1753388Y28360D01*
G01X1753398Y48720D02*
X1753393Y48715D01*
Y44370D01*
G01X1744422Y151527D02*
X1741222D01*
G01X1742907Y171733D02*
X1747591D01*
G01X1751084Y187509D02*
Y190928D01*
G01X1760480Y32756D02*
Y28365D01*
X1760475Y28360D01*
G01X1760480Y44370D02*
X1760485Y44375D01*
Y48720D01*
G01X1766585Y164362D02*
X1768483Y166260D01*
G01X1762163Y307992D02*
X1758563D01*
G01X1768002Y364148D02*
X1770520D01*
G01X1768002Y368148D02*
X1770520D01*
G01X1769976Y461393D02*
X1767300D01*
G01X1765670Y453986D02*
Y458012D01*
G01X1769976Y465893D02*
X1767300D01*
G01X1789328Y150744D02*
X1784238D01*
G01X1778810Y443987D02*
X1782420D01*
G01X1790546Y438156D02*
X1778805D01*
X1778182Y437533D01*
G01X1773870Y438222D02*
X1774559Y437533D01*
X1778182D01*
G01X1799724Y161465D02*
X1797324D01*
G01X1798179Y408056D02*
X1795479D01*
G01X1798168Y421334D02*
X1795468D01*
G01X1806566Y1502389D02*
X1803582Y1499405D01*
X1802150D01*
G01X1803517Y1495567D02*
X1802150Y1496934D01*
Y1499405D01*
G01X1813335Y163986D02*
X1810835D01*
G01X1806365Y156557D02*
Y154032D01*
G01X1803129Y362293D02*
X1805069Y364233D01*
Y366053D01*
G01X1805629Y385293D02*
X1802929D01*
G01X1818874Y421432D02*
Y423932D01*
G01X1818816Y472521D02*
Y468872D01*
G01X1804410Y1505801D02*
Y1504545D01*
X1806566Y1502389D01*
G01X1831277Y156520D02*
X1828777D01*
G01X1820815Y158868D02*
X1823508D01*
G01X1820307Y371329D02*
Y373829D01*
G01X1826626Y367701D02*
X1829026D01*
G01X1820144Y395552D02*
Y398052D01*
G01X1819374Y407932D02*
Y410432D01*
G01X1826075Y1507916D02*
X1823426D01*
G01X1838757Y151402D02*
X1841257D01*
G01X1838910Y182712D02*
Y185772D01*
G01X1843134Y244362D02*
X1843166Y244330D01*
Y241921D01*
G01X1836750Y376408D02*
Y373632D01*
G01X1835516Y459121D02*
X1838020D01*
G54D45*
X77416Y1534944D03*
G54D273*
X1179922Y1537244D03*
G54D282*
X1278150Y135612D03*
G54D27*
X36595Y388035D03*
X46834Y366395D03*
X55190D03*
X54333Y1609817D03*
X57833Y1669317D03*
X53333D03*
X49333D03*
X61000Y1679183D03*
X70333Y1618817D03*
X69833Y1669317D03*
X73833D03*
X77833D03*
X65000Y1679183D03*
X90518Y640088D03*
X82014Y702575D03*
X92096Y697663D03*
X84474Y1523077D03*
X87500Y1564577D03*
X91500D03*
X81833Y1669317D03*
X90297Y1669363D03*
X85833Y1669317D03*
X108643Y526800D03*
X96774Y1529077D03*
X108800Y1611883D03*
X117597Y494374D03*
X113597D03*
X114720Y1683345D03*
X120910Y1726530D03*
X130317Y483296D03*
X135317D03*
X138489Y528432D03*
X134557Y1731165D03*
X149174Y483296D03*
X152470Y505846D03*
X149568Y1392653D03*
X152806Y1411442D03*
X158570Y1526488D03*
X154581Y1526447D03*
X159014Y1576892D03*
X154580D03*
X170673Y1412428D03*
X175067Y1733075D03*
X190110Y572455D03*
X187711Y1392653D03*
X181806Y1393673D03*
X177702D03*
X190949Y1411442D03*
X205320Y673045D03*
X201220D03*
X207716Y1411728D03*
X220387Y1393782D03*
X216090D03*
X212120Y1709745D03*
X237220Y65345D03*
X241220D03*
X249220D03*
X245220D03*
X251487Y107743D03*
X263580Y224085D03*
X270240Y242265D03*
X267759Y257714D03*
X271821D03*
X275797Y127026D03*
X276491Y257714D03*
X281077D03*
X286481D03*
X289274Y296371D03*
X284515D03*
X302517Y71475D03*
X301315Y98782D03*
X305315D03*
X291759Y257714D03*
X304651D03*
X298184Y296371D03*
X302765D03*
X293763D03*
X302684Y562850D03*
X303551Y1350799D03*
X322155Y235202D03*
X317995Y235232D03*
X317129Y257714D03*
X306736Y296371D03*
X316463D03*
X307019Y1369520D03*
X325617Y76846D03*
X338267Y213610D03*
X329648Y257660D03*
X329002Y296371D03*
X335679Y1328001D03*
X338917Y1346790D03*
X336205Y1353830D03*
X331773Y1351936D03*
X324656Y1369674D03*
X354672Y258151D03*
X342000Y258070D03*
X354145Y296049D03*
X341295Y295697D03*
X367306Y258269D03*
X366498Y295722D03*
X367717Y1314575D03*
X366903Y1338158D03*
X370874Y1333366D03*
X363805Y1329100D03*
X356784Y1346876D03*
X379860Y257954D03*
X379112Y295844D03*
X385797Y1398668D03*
X385123Y1634442D03*
X378497Y1634378D03*
X374500Y1645905D03*
X378509Y1685642D03*
X392616Y257944D03*
X392083Y296412D03*
X399935Y1314575D03*
X395933Y1315674D03*
X402973Y1333336D03*
X390029Y1332901D03*
X393699Y1405521D03*
X403125Y1422486D03*
X399134Y1422464D03*
X391293Y1634462D03*
X417765Y258263D03*
X404985Y257873D03*
X417218Y296732D03*
X404215Y296598D03*
X418616Y939131D03*
X410816D03*
X410795Y954148D03*
X414595D03*
X418595D03*
X414626Y968547D03*
X418626D03*
X410826D03*
X414600Y983060D03*
X410800D03*
X414600Y997375D03*
X410800D03*
X418600Y983060D03*
Y997375D03*
X418550Y1011933D03*
X410838D03*
X414550D03*
X410816Y1026543D03*
X414591D03*
X418591D03*
X409980Y1396936D03*
X431873Y258263D03*
X429702Y296221D03*
X422395Y939131D03*
Y954148D03*
X422426Y968547D03*
X422400Y983060D03*
X422350Y997375D03*
Y1011933D03*
X422391Y1026543D03*
X432063Y1314575D03*
X428061Y1315674D03*
X434983Y1333365D03*
X421224Y1332901D03*
X442265Y296397D03*
X448520Y419745D03*
X444020D03*
X442520Y473320D03*
X437520D03*
X451520D03*
X451014Y1400462D03*
X442020Y1567920D03*
X446020D03*
X452020Y1577920D03*
X437383Y1600137D03*
X458264Y263940D03*
X467736Y296881D03*
X467211Y369216D03*
X455720Y402245D03*
X462921Y427986D03*
X453020Y419745D03*
X457520D03*
X456520Y473320D03*
X461520D03*
X466704Y954148D03*
X462704D03*
X458904D03*
X462704Y968547D03*
X466704D03*
X458904D03*
X466704Y997375D03*
Y983060D03*
X458904D03*
X462704D03*
Y997375D03*
X458904D03*
X466704Y1011933D03*
X458904D03*
X462704D03*
X458904Y1026543D03*
X466704D03*
X462704D03*
X464191Y1314575D03*
X460189Y1315674D03*
X467644Y1333383D03*
X452961Y1332893D03*
X460020Y1577920D03*
X466320Y1599212D03*
X483500Y237845D03*
X474720Y366345D03*
X485020Y419745D03*
X480520D03*
X479169Y473179D03*
X474169D03*
X470504Y954148D03*
Y968547D03*
Y983060D03*
Y997375D03*
Y1011933D03*
Y1026543D03*
X485296Y1332893D03*
X478460Y1445562D03*
X501136Y296181D03*
X490720Y366345D03*
X498720D03*
X486720D03*
X499570Y427845D03*
X489520Y419745D03*
X494020D03*
X498169Y473179D03*
X493169D03*
X488169D03*
X492317Y1315674D03*
X496319Y1328001D03*
X499458Y1346822D03*
X510830Y109155D03*
X507750Y296066D03*
X506720Y366345D03*
X517720Y395845D03*
X505720D03*
X517020Y483935D03*
X517424Y1346876D03*
X506096Y1418300D03*
X518720Y366345D03*
X531720D03*
X523720D03*
X533720Y395845D03*
X521720D03*
X524445Y1329100D03*
X528447Y1350799D03*
X531610Y1369632D03*
X547330Y366225D03*
X548300Y411390D03*
X549552Y1369674D03*
X564698Y366185D03*
X554300Y411390D03*
X564300D03*
X559300D03*
X560969Y1351951D03*
X556586D03*
X557720Y1452845D03*
X552000D03*
X571556Y378032D03*
X578582Y366140D03*
X573460Y366185D03*
X569340D03*
X569152Y419470D03*
X598795Y146135D03*
X594220Y433845D03*
X606079Y124875D03*
X604725Y278113D03*
X607675Y323882D03*
X615635Y323938D03*
X618460Y124875D03*
X621536Y211559D03*
X618115Y278113D03*
X631146Y323973D03*
X623365Y323958D03*
X634500Y82845D03*
X638500D03*
X646815Y515367D03*
X642225Y1705677D03*
X646225D03*
X648320Y87245D03*
X659000Y94845D03*
X654895Y521077D03*
X650794Y521090D03*
X650845Y528163D03*
X663187Y1392678D03*
X651725Y1649177D03*
X654225Y1660677D03*
X650225Y1698677D03*
X667610Y113395D03*
X680220Y514345D03*
X675220Y527845D03*
X680220D03*
X666425Y1411467D03*
X684643Y111868D03*
X688470Y394645D03*
X685220Y501345D03*
X695220Y514345D03*
Y527845D03*
X691321Y1393698D03*
X695425D03*
X684292Y1411553D03*
X708953Y131151D03*
X708720Y383845D03*
X713220Y393845D03*
X705220Y501345D03*
X711220D03*
X705220Y527845D03*
X701330Y1392678D03*
X704568Y1411467D03*
X711719Y1642834D03*
X728220Y393845D03*
Y383845D03*
X718220Y393845D03*
X717220Y501345D03*
X723220D03*
X729220D03*
X717220Y514345D03*
X723220D03*
X729220D03*
X722435Y1411553D03*
X715780Y1620413D03*
X719770Y1620403D03*
X723820D03*
X718830Y1652953D03*
X737093Y90960D03*
X737340Y118718D03*
X741270Y118642D03*
X740200Y371208D03*
X738220Y393845D03*
X733220D03*
Y383845D03*
X745220Y514345D03*
X735220D03*
X735173Y527820D03*
X734006Y1393807D03*
X729709D03*
X743462Y1670228D03*
X739538Y1674238D03*
X760193Y96331D03*
X753089Y501360D03*
X749179Y501340D03*
X755859Y1692078D03*
X759359Y1726578D03*
X755359D03*
X764130Y116163D03*
X777220Y441345D03*
X763859Y1692078D03*
X794220Y428345D03*
X782800Y508545D03*
X783450Y519965D03*
X794600Y366183D03*
X802200D03*
X809800D03*
X809600Y386083D03*
X800498Y401509D03*
Y416109D03*
X831539Y65826D03*
X834615Y107264D03*
X835114Y120681D03*
X833715Y228051D03*
X832500Y270197D03*
X832400Y424383D03*
X828300D03*
X840200D03*
X856629Y65976D03*
X850015Y93234D03*
X858783Y227466D03*
X844200Y424383D03*
X863294Y269019D03*
X863571Y296868D03*
X867571D03*
X886503Y274390D03*
X880772Y879818D03*
X909293Y464911D03*
X913293D03*
X920747Y470710D03*
X921720Y1009845D03*
X924747Y470710D03*
X937747D03*
X933747D03*
X931496Y967670D03*
X927220Y1009845D03*
X941747Y470710D03*
X945747D03*
X947275Y979890D03*
X943750Y983135D03*
X985500Y151282D03*
X989605Y178536D03*
X985445Y178566D03*
X988835Y190936D03*
X1005735Y156926D03*
X1001395Y217406D03*
X1019939Y300396D03*
X1031270Y306545D03*
X1033268Y505285D03*
X1052705Y366178D03*
X1095457Y1644333D03*
X1099457D03*
X1115802Y1620753D03*
X1109287Y1672923D03*
X1122879Y1428982D03*
X1126117Y1447771D03*
X1120472Y1620743D03*
X1120432Y1628403D03*
X1151013Y1430002D03*
X1143984Y1447857D03*
X1160720Y186345D03*
X1155117Y1430002D03*
X1161022Y1428982D03*
X1164260Y1447771D03*
X1164830Y1651198D03*
X1159930D03*
X1163576Y1680532D03*
X1181476Y166789D03*
X1182127Y1447857D03*
X1175830Y1651198D03*
X1181930D03*
X1170930D03*
X1174576Y1680532D03*
X1195278Y139032D03*
X1193260Y1430002D03*
X1189156D03*
X1185080Y1621972D03*
X1197400Y1651508D03*
X1186830Y1651198D03*
X1192500Y1651508D03*
X1196146Y1680842D03*
X1185576Y1680532D03*
X1197240Y1696988D03*
X1192340D03*
X1195986Y1726322D03*
X1212202Y120600D03*
X1208010Y1697033D03*
X1203110D03*
X1213910Y1697298D03*
X1206756Y1726367D03*
X1220500Y210345D03*
X1218810Y1697298D03*
X1217556Y1726632D03*
X1263040Y106605D03*
X1258539Y106410D03*
X1259150Y302999D03*
X1255150D03*
X1274520Y84345D03*
X1281913Y82382D03*
X1271150Y302999D03*
X1279812Y1351035D03*
X1291823Y90752D03*
X1287913Y90702D03*
X1295767Y95199D03*
X1298407Y107950D03*
X1294937Y752448D03*
X1283280Y1369756D03*
X1311960Y55491D03*
X1309790Y65283D03*
X1311636Y75489D03*
X1307578Y75487D03*
X1308792Y94284D03*
X1310906Y103672D03*
X1314906D03*
X1311820Y1328001D03*
X1312346Y1353830D03*
X1308140Y1351897D03*
X1315058Y1346790D03*
X1300917Y1369910D03*
X1325902Y65340D03*
X1330102D03*
X1317831Y65283D03*
X1321869Y65265D03*
X1315649Y75488D03*
X1319721D03*
X1324120Y91391D03*
X1329891Y96806D03*
X1322906Y100186D03*
X1318906Y103666D03*
X1329646Y110452D03*
X1322906Y107216D03*
X1324093Y250945D03*
X1345083Y96826D03*
X1336549Y111428D03*
X1343858Y1314575D03*
X1339946Y1329100D03*
X1343044Y1338158D03*
X1347015Y1333366D03*
X1332925Y1346876D03*
X1349621Y109705D03*
X1358277Y1399078D03*
X1366124Y107012D03*
X1378550Y121644D03*
X1372074Y1315674D03*
X1376076Y1314575D03*
X1366170Y1332901D03*
X1379114Y1333336D03*
X1377075Y1422464D03*
X1394757Y939130D03*
X1386957D03*
X1394736Y954147D03*
X1390736D03*
X1386936D03*
X1390767Y968546D03*
X1394767D03*
X1386967D03*
X1390741Y997374D03*
X1386941D03*
X1394812Y983059D03*
X1390812D03*
X1387012D03*
X1394741Y997374D03*
X1394691Y1011932D03*
X1390691D03*
X1386891D03*
X1390732Y1026542D03*
X1386869D03*
X1394732D03*
X1386181Y1397136D03*
X1381066Y1422486D03*
X1385720Y1433345D03*
X1398557Y939130D03*
X1398536Y954147D03*
X1398567Y968546D03*
X1398612Y983059D03*
X1398541Y997374D03*
X1398491Y1011932D03*
X1398532Y1026542D03*
X1408204Y1314575D03*
X1404202Y1315674D03*
X1411124Y1333365D03*
X1397365Y1332901D03*
X1398700Y1603265D03*
X1427155Y1400462D03*
X1442845Y954147D03*
X1438845D03*
X1435045D03*
X1438845Y968546D03*
X1442845D03*
X1435045D03*
X1438845Y983059D03*
X1442845D03*
X1435045D03*
X1442845Y997374D03*
X1438845D03*
X1435045D03*
X1438845Y1011932D03*
X1442845D03*
X1435045D03*
X1438845Y1026542D03*
X1435045D03*
X1442845D03*
X1436330Y1315674D03*
X1440332Y1314575D03*
X1429102Y1332893D03*
X1443785Y1333383D03*
X1442573Y1655452D03*
X1451700Y294183D03*
X1445777Y367479D03*
X1449600Y399795D03*
X1446645Y954147D03*
Y968546D03*
Y983059D03*
Y997374D03*
Y1011932D03*
Y1026542D03*
X1461437Y1332893D03*
X1454938Y1445436D03*
X1454207Y1631048D03*
X1459117Y1631028D03*
X1462777Y367479D03*
X1477384Y416771D03*
X1468458Y1315674D03*
X1472460Y1328001D03*
X1475599Y1346822D03*
X1463747Y1631028D03*
X1467840Y1631085D03*
X1473527Y1661032D03*
X1489564Y367181D03*
X1493874D03*
X1481484Y367271D03*
X1489384Y416771D03*
X1493565Y1346876D03*
X1482237Y1418300D03*
X1500904Y385751D03*
X1500586Y1329100D03*
X1504588Y1350799D03*
X1507751Y1369632D03*
X1526118Y116088D03*
X1525693Y1369674D03*
X1539720Y587345D03*
X1532727Y1351951D03*
X1537110D03*
X1543779Y124261D03*
X1556747Y592398D03*
X1552720Y587345D03*
X1546312Y640699D03*
X1550162D03*
X1619515Y117542D03*
X1624353Y1426274D03*
X1627591Y1445063D03*
X1654110Y431685D03*
X1654032Y656992D03*
Y690992D03*
X1652487Y1427294D03*
X1656591D03*
X1645458Y1445149D03*
X1659610Y400185D03*
X1663610D03*
X1663376Y521071D03*
X1667376D03*
X1657632Y553397D03*
X1665706Y589039D03*
X1661506D03*
X1661132Y623492D03*
X1661120Y616945D03*
X1658085Y645094D03*
Y679094D03*
Y713094D03*
X1662496Y1426274D03*
X1665734Y1445063D03*
X1688504Y404543D03*
X1683601Y1445149D03*
X1694314Y431638D03*
X1690154Y431668D03*
X1693648Y469259D03*
X1697648D03*
X1703960Y546986D03*
X1690080Y555240D03*
X1703768Y701889D03*
X1695446Y707001D03*
X1695172Y1427403D03*
X1690875D03*
X1716875Y65452D03*
X1711832Y65216D03*
X1720895Y65452D03*
X1711832Y78704D03*
X1716965Y78692D03*
X1710426Y410646D03*
X1717686Y502460D03*
X1725520Y65345D03*
X1726608Y108867D03*
X1750918Y128150D03*
X1752324Y203475D03*
X1738290Y420323D03*
X1767638Y72599D03*
X1767891Y100303D03*
X1771891D03*
X1779226Y281087D03*
X1778810Y447045D03*
X1790738Y77970D03*
X1802150Y1502463D03*
X1797722Y1502526D03*
X1790011Y1514481D03*
X1813955Y146003D03*
X1849191Y166358D03*
X1836750Y379466D03*
G54D81*
X108909Y648926D03*
X126225Y510368D03*
X1676004Y537065D03*
X1702760Y484207D03*
G54D246*
X956404Y1558189D03*
X951404D03*
X946404D03*
X961404D03*
X969770D03*
X984770D03*
X979770D03*
X974770D03*
X1003136D03*
X998136D03*
X993136D03*
X1008136D03*
X1021502D03*
X1016502D03*
X1031502D03*
X1026502D03*
X1054868D03*
X1049868D03*
X1044868D03*
X1039868D03*
X1068234D03*
X1063234D03*
X1078234D03*
X1073234D03*
X1086600D03*
X1101600D03*
X1096600D03*
X1091600D03*
X1735111Y1467176D03*
X1730111D03*
X1745111D03*
X1740111D03*
G36*
G01X791285Y1719440D02*
G02X791280Y1690339I-5J-14550D01*
G02X791275Y1719440I0J14551D01*
G01Y1712890D01*
G03X791280Y1696889I5J-8000D01*
G03X791285Y1712890I0J8001D01*
G01Y1719440D01*
G37*
G36*
G01X1066285D02*
G02X1066280Y1690339I-5J-14550D01*
G02X1066275Y1719440I0J14551D01*
G01Y1712890D01*
G03X1066280Y1696889I5J-8000D01*
G03X1066285Y1712890I0J8001D01*
G01Y1719440D01*
G37*
G54D147*
X322500Y1391830D03*
X537477Y1395413D03*
X1133779Y1653543D03*
X1298642Y1391830D03*
X1513618Y1395413D03*
G54D165*
X402220Y160951D03*
Y155833D03*
X394780D03*
Y158392D03*
Y160951D03*
X1796768Y150744D03*
X1789328D03*
X1796768Y155862D03*
X1789328Y153303D03*
Y155862D03*
G54D192*
X542554Y462744D03*
Y491680D03*
X565586Y462744D03*
Y491680D03*
X1790546Y438156D03*
Y467092D03*
X1813578Y438156D03*
Y467092D03*
G54D183*
X482720Y375319D03*
Y382405D03*
X496120Y375426D03*
Y382512D03*
X512220Y375319D03*
Y382405D03*
X510220Y404819D03*
Y411905D03*
X529220Y375819D03*
Y382905D03*
X526220Y404819D03*
Y411905D03*
G54D228*
X842470Y407020D03*
Y410760D03*
Y414500D03*
X853100Y410760D03*
Y407020D03*
Y414500D03*
G54D36*
X61280Y380803D03*
X59311D03*
X57342D03*
X55374D03*
X53406D03*
X51437D03*
X49468D03*
Y399799D03*
X51437D03*
X53406D03*
X55374D03*
X57342D03*
X59311D03*
X61280D03*
X614707Y139283D03*
X612738D03*
Y158279D03*
X614707D03*
X624550Y139283D03*
X622581D03*
X620612D03*
X618644D03*
X616676D03*
Y158279D03*
X618644D03*
X620612D03*
X622581D03*
X624550D03*
G54D90*
X163677Y1344383D03*
Y1370367D03*
X201777Y1344383D03*
Y1370367D03*
X677296Y1344408D03*
Y1370392D03*
X715396Y1344408D03*
Y1370392D03*
X1136988Y1380712D03*
Y1406696D03*
X1175088Y1380712D03*
Y1406696D03*
X1638462Y1378004D03*
Y1403988D03*
X1676562Y1378004D03*
Y1403988D03*
G54D237*
X913386Y167579D03*
Y184114D03*
Y181752D03*
Y179390D03*
Y177027D03*
Y174665D03*
Y172303D03*
Y169941D03*
Y200649D03*
Y198287D03*
Y195925D03*
Y193563D03*
Y191201D03*
Y188838D03*
Y186476D03*
Y217185D03*
Y214823D03*
Y212461D03*
Y210098D03*
Y207736D03*
Y205374D03*
Y203012D03*
Y231358D03*
Y228996D03*
Y226634D03*
Y224272D03*
Y221909D03*
Y219547D03*
X931496Y167579D03*
Y184114D03*
Y181752D03*
Y179390D03*
Y177027D03*
Y174665D03*
Y172303D03*
Y169941D03*
Y200649D03*
Y198287D03*
Y195925D03*
Y193563D03*
Y191201D03*
Y188838D03*
Y186476D03*
Y217185D03*
Y214823D03*
Y212461D03*
Y210098D03*
Y207736D03*
Y205374D03*
Y203012D03*
Y231358D03*
Y228996D03*
Y226634D03*
Y224272D03*
Y221909D03*
Y219547D03*
G54D156*
X347876Y148462D03*
Y152202D03*
Y155942D03*
X357324Y148462D03*
Y155942D03*
X548670Y442656D03*
Y446396D03*
Y450136D03*
X558118Y442656D03*
Y450136D03*
X1079225Y55682D03*
Y59422D03*
Y63162D03*
X1088673Y55682D03*
Y63162D03*
X1223507Y54100D03*
X1232955D03*
X1223507Y61580D03*
X1232955D03*
Y57840D03*
X1516776Y122122D03*
Y129602D03*
X1526224D03*
Y125862D03*
Y122122D03*
G54D129*
X256978Y107835D03*
Y111771D03*
X464818Y303145D03*
Y305114D03*
Y307082D03*
Y309051D03*
X470654D03*
Y307082D03*
Y305114D03*
X498218Y302445D03*
Y304414D03*
Y306382D03*
Y308351D03*
X504054D03*
Y306382D03*
Y304414D03*
X690134Y111960D03*
Y115896D03*
X993943Y190419D03*
Y192387D03*
Y194356D03*
Y196325D03*
Y198293D03*
Y200261D03*
X1004967D03*
Y198293D03*
Y196325D03*
Y194356D03*
Y192387D03*
X993943Y202230D03*
Y204199D03*
Y206167D03*
X1004967D03*
Y204199D03*
Y202230D03*
X1732099Y108959D03*
Y112895D03*
G54D309*
X1745799Y1516211D03*
X1779963D03*
G54D291*
X1302744Y148170D03*
X1306683D03*
X1310621D03*
X1298805D03*
X1302744Y233328D03*
X1306683D03*
X1310621D03*
X1298805D03*
X1314560Y148170D03*
X1318499D03*
X1322438D03*
X1326377D03*
X1330316D03*
X1314560Y233328D03*
X1318499D03*
X1322438D03*
X1326377D03*
X1330316D03*
X1334255Y148170D03*
X1338194D03*
X1342133D03*
X1346071D03*
X1334255Y233328D03*
X1338194D03*
X1342133D03*
X1346071D03*
X1350010Y148170D03*
X1353949D03*
X1350010Y233328D03*
X1353949D03*
G54D72*
X95132Y1541244D03*
G54D54*
X87225Y704442D03*
X1700657Y708568D03*
G54D18*
X27737Y216362D03*
Y224362D03*
X36517Y200862D03*
Y192862D03*
X36237Y216362D03*
Y208362D03*
Y232362D03*
Y224342D03*
Y240362D03*
X33197Y302472D03*
X59291Y1520094D03*
Y1536094D03*
Y1540094D03*
Y1560094D03*
X62823Y302926D03*
X65625Y421746D03*
X78008Y424319D03*
Y420319D03*
X77707Y648574D03*
Y644564D03*
Y652564D03*
X79657Y278798D03*
Y295798D03*
Y286262D03*
Y303262D03*
X81908Y376026D03*
X81891Y386502D03*
X88318Y438519D03*
Y442519D03*
X85657Y644564D03*
Y648564D03*
Y656564D03*
Y652564D03*
X86536Y685488D03*
X85525Y694209D03*
X86525Y690644D03*
X93205Y1581852D03*
Y1597867D03*
X84155Y1589872D03*
X93280Y1601867D03*
Y1615821D03*
Y1619821D03*
X93190Y1630362D03*
Y1642362D03*
X88762Y1683071D03*
X88737Y1694362D03*
X88747Y1686622D03*
X109092Y186362D03*
X108032Y216596D03*
X111029Y282995D03*
Y278875D03*
Y274800D03*
Y300354D03*
Y306236D03*
X104967Y517925D03*
X107112Y685490D03*
X95767Y718880D03*
X107291Y1524594D03*
Y1544594D03*
Y1548594D03*
Y1536594D03*
Y1540594D03*
Y1560594D03*
Y1564594D03*
X127499Y404571D03*
X112831Y523785D03*
X125255Y656603D03*
X124255Y647103D03*
X125255Y652603D03*
X122691Y665515D03*
Y661515D03*
X122667Y669400D03*
X116250Y1535767D03*
X116352Y1541935D03*
X116423Y1548027D03*
X121737Y1678362D03*
Y1670362D03*
Y1674362D03*
X114737Y1696362D03*
X121737Y1692362D03*
Y1688362D03*
Y1708362D03*
Y1700362D03*
Y1704362D03*
X127574Y1727182D03*
Y1731182D03*
X128698Y643603D03*
X143562Y688207D03*
X142634Y1396275D03*
Y1392745D03*
X158417Y409362D03*
X143913Y415062D03*
Y423383D03*
Y427383D03*
Y419383D03*
Y431383D03*
Y435383D03*
Y439383D03*
Y443383D03*
X144014Y498810D03*
Y502810D03*
X143979Y506533D03*
X144014Y522810D03*
X157075Y1412173D03*
X148237Y1708362D03*
Y1712362D03*
X155237Y1716362D03*
X172413Y421383D03*
Y425383D03*
Y443383D03*
Y430883D03*
X165628Y1443390D03*
X180999Y393071D03*
Y385071D03*
Y389071D03*
Y405071D03*
X192068Y681291D03*
X191159Y693623D03*
X179999Y1535462D03*
X179885Y1544028D03*
X179965Y1548486D03*
X179988Y1539723D03*
X179956Y1552874D03*
Y1557874D03*
X182084Y1723592D03*
X201641Y420255D03*
Y414755D03*
Y425755D03*
Y436755D03*
Y431255D03*
Y442255D03*
Y447755D03*
Y453255D03*
Y458755D03*
Y462755D03*
Y468255D03*
X196618Y570901D03*
X197090Y588879D03*
X196618Y604901D03*
X197090Y622879D03*
X196618Y638901D03*
X197090Y656879D03*
X195218Y1412173D03*
X193385Y1719697D03*
X205135Y1718017D03*
X199142Y1733022D03*
X212071Y452735D03*
X215408Y567981D03*
X214309Y596107D03*
X215408Y601981D03*
X214309Y630107D03*
X215408Y635981D03*
X214309Y664107D03*
X211558Y673737D03*
X230537Y154126D03*
X242237Y71862D03*
X247314Y111743D03*
X256787Y458617D03*
X273784Y99183D03*
X270017Y136962D03*
X267067Y142892D03*
X267070Y159203D03*
Y155203D03*
X262737Y214022D03*
X266571Y422735D03*
X266553Y418579D03*
X266571Y426735D03*
X266603Y431039D03*
X266571Y443735D03*
X276917Y136962D03*
X277797Y210802D03*
X289137Y637809D03*
X295434Y71513D03*
X295464Y75673D03*
X296570Y151703D03*
Y156203D03*
X306236Y595318D03*
X322559Y69863D03*
X317074Y91803D03*
X320322Y563176D03*
X314732Y599926D03*
X312163Y1369807D03*
X340017Y161862D03*
X353237Y221862D03*
X346750Y709995D03*
X343186Y1347521D03*
X363717Y130162D03*
X363617Y156202D03*
X376237Y128452D03*
X376257Y124312D03*
X385677Y124322D03*
X385592Y128491D03*
X375314Y1334095D03*
X384867Y1627062D03*
X396113Y1330142D03*
X403421Y1404207D03*
Y1400684D03*
X403348Y1397038D03*
X403416Y1407727D03*
X394842Y1413619D03*
X396435Y1432571D03*
Y1427569D03*
X399438Y1541810D03*
Y1556810D03*
X419854Y67465D03*
Y62665D03*
X417714Y149373D03*
X408376Y161162D03*
X417714Y157466D03*
Y161466D03*
Y153477D03*
X409060Y1334095D03*
X415494Y1390306D03*
X408832Y1390325D03*
X405235Y1427569D03*
Y1432571D03*
X411217Y1611300D03*
Y1607400D03*
X409949Y1680267D03*
X423592Y117491D03*
X428981Y128515D03*
Y124015D03*
X428237Y214862D03*
Y209862D03*
X423237Y225362D03*
X423937Y232562D03*
Y236562D03*
Y240562D03*
X427672Y1330042D03*
X429938Y1543810D03*
Y1555810D03*
X427062Y1579466D03*
X451510Y75985D03*
X446838Y149864D03*
X436835Y498733D03*
Y504233D03*
Y509733D03*
Y515233D03*
Y520733D03*
Y526233D03*
Y542733D03*
X445345Y537483D03*
X436835Y547769D03*
Y552769D03*
X439570Y1334095D03*
X451106Y1393959D03*
X450118Y1420625D03*
Y1409125D03*
Y1413125D03*
Y1417125D03*
Y1427632D03*
Y1424125D03*
X450107Y1431134D03*
X450097Y1611923D03*
X456656Y115948D03*
X455838Y149864D03*
Y154864D03*
X460597Y1330533D03*
X466430Y1614682D03*
X466387Y1618626D03*
X472270Y66575D03*
X472244Y61129D03*
X472200Y55935D03*
X481338Y158864D03*
X480237Y391362D03*
X471698Y1334095D03*
X477983Y1400385D03*
X476588Y1411144D03*
X485167Y1631038D03*
X472447Y1643242D03*
Y1659242D03*
Y1651242D03*
Y1667242D03*
X472377Y1673462D03*
Y1685462D03*
X499597Y93582D03*
X501017Y228362D03*
X489353Y305398D03*
X489327Y313582D03*
X493237Y391362D03*
X491135Y547947D03*
X492757Y1319592D03*
X503967Y86422D03*
X507017Y209862D03*
X502517Y237862D03*
X505517Y288862D03*
X505274Y315404D03*
X508237Y420862D03*
X504035Y507819D03*
Y511819D03*
Y519819D03*
Y515819D03*
Y523819D03*
Y527819D03*
Y539819D03*
X503826Y1347521D03*
X523237Y420862D03*
X522897Y478492D03*
X526917Y489112D03*
Y495112D03*
X525355Y1338837D03*
X536337Y103352D03*
X536407Y108062D03*
X547487Y149802D03*
X535467Y442376D03*
Y450330D03*
Y446396D03*
X535954Y1370319D03*
X552487Y131756D03*
X559237Y167112D03*
Y161362D03*
X559737Y184862D03*
X554581Y253202D03*
Y257202D03*
X566706Y305247D03*
X565057Y442656D03*
X565034Y451710D03*
X570737Y167112D03*
X581967Y190092D03*
X581973Y198378D03*
Y210378D03*
Y202378D03*
Y206378D03*
X581737Y225362D03*
Y221362D03*
X575451Y262632D03*
X568932Y498546D03*
X579017Y514362D03*
X588337Y129642D03*
X595237Y174612D03*
X596331Y257532D03*
X586581Y252202D03*
X585062Y296657D03*
Y311571D03*
Y304052D03*
X591322Y363354D03*
X588087Y488212D03*
X591517Y524862D03*
X601737Y164612D03*
X611473Y202878D03*
Y207378D03*
X599947Y458688D03*
X599737Y482362D03*
X600737Y514862D03*
X618324Y184022D03*
X627081Y249202D03*
Y260202D03*
X631737Y411362D03*
X631517Y406862D03*
X631737Y426362D03*
Y421362D03*
Y441862D03*
Y431362D03*
X616737Y442862D03*
X631740Y436650D03*
X631737Y457862D03*
Y452862D03*
Y447862D03*
X616737Y457862D03*
X631737Y462862D03*
X631717Y482662D03*
X638570Y88035D03*
X638530Y92085D03*
X646517Y93362D03*
X645178Y134506D03*
X645161Y144982D03*
X646237Y161862D03*
Y166362D03*
Y171362D03*
X637237Y230362D03*
X637662Y298297D03*
Y315587D03*
Y310962D03*
Y302247D03*
X633017Y392862D03*
X646017D03*
X646517Y406862D03*
Y402362D03*
X646737Y416362D03*
Y441862D03*
Y431362D03*
Y452862D03*
Y457862D03*
Y447862D03*
Y467862D03*
Y462862D03*
X643742Y1653194D03*
X642242Y1695694D03*
X642237Y1718362D03*
Y1722362D03*
X652127Y120412D03*
X652762Y290371D03*
X656253Y1392770D03*
Y1396300D03*
X663737Y1720362D03*
X680470Y115868D03*
X670147Y391602D03*
X670694Y1412198D03*
X665589Y1642667D03*
X665610Y1655557D03*
X665535Y1651557D03*
X665637Y1672862D03*
Y1668862D03*
X668737Y1708362D03*
Y1724362D03*
Y1716362D03*
Y1732362D03*
X681917Y1442245D03*
X691664Y1632667D03*
X691739Y1644667D03*
X691749Y1648843D03*
X692137Y1658862D03*
X687137Y1670862D03*
X692137Y1666862D03*
Y1674862D03*
Y1682862D03*
X706940Y103308D03*
X710237Y161862D03*
Y157362D03*
X708837Y1412198D03*
X704659Y1563733D03*
X704629Y1583683D03*
X703597Y1607102D03*
Y1611022D03*
X704589Y1601963D03*
X718287Y1644550D03*
X718850Y1676500D03*
X730040Y95158D03*
X730010Y90998D03*
X745752Y142050D03*
X745172Y1674362D03*
X757135Y89348D03*
X751650Y111288D03*
X748217Y167537D03*
X748177Y276322D03*
X760737Y393212D03*
Y418212D03*
Y423212D03*
Y428212D03*
X759857Y464862D03*
Y469862D03*
Y488862D03*
Y483862D03*
Y479862D03*
X759867Y497659D03*
X762037Y1388562D03*
Y1392762D03*
Y1406062D03*
X761937Y1410262D03*
X754629Y1579183D03*
Y1587183D03*
Y1592183D03*
X774806Y158026D03*
X774820Y153728D03*
X777559Y299279D03*
X763759D03*
X763660Y311249D03*
X763187Y317432D03*
X775737Y413212D03*
Y408212D03*
Y403212D03*
Y398212D03*
Y418212D03*
Y423212D03*
X774857Y464862D03*
Y469862D03*
Y488862D03*
X765669Y1594893D03*
X779677Y267822D03*
Y281822D03*
X789937Y393462D03*
Y402500D03*
X789857Y464862D03*
Y474862D03*
X788417Y483262D03*
X802979Y269800D03*
X805357Y469862D03*
Y474862D03*
X807169Y1577793D03*
Y1593793D03*
Y1601793D03*
Y1609793D03*
X821625Y274885D03*
Y279885D03*
X824280Y494000D03*
X824287Y498082D03*
Y502082D03*
Y523082D03*
Y515082D03*
X831478Y58632D03*
X828237Y166862D03*
Y176362D03*
X833152Y275045D03*
Y280045D03*
X827495Y389012D03*
Y397276D03*
X827517Y384400D03*
X827494Y413260D03*
X835517Y446800D03*
X838737Y495362D03*
X848837Y162762D03*
X848427Y185812D03*
X856350Y273217D03*
X856320Y269057D03*
X849417Y476900D03*
X857137Y503162D03*
Y499062D03*
X857287Y515582D03*
Y519582D03*
X849169Y1577793D03*
Y1593793D03*
Y1601793D03*
Y1609793D03*
X871237Y166362D03*
X865003Y394620D03*
Y390620D03*
Y382415D03*
X865055Y406812D03*
Y418836D03*
X864837Y431462D03*
X879237Y176862D03*
Y171362D03*
X881232Y183169D03*
X881242Y187449D03*
X883445Y267407D03*
X877932Y289439D03*
X884839Y874405D03*
X885409Y920325D03*
X891169Y1577793D03*
Y1593793D03*
Y1601793D03*
Y1609793D03*
X933169Y1581393D03*
Y1585393D03*
Y1589393D03*
X955362Y484271D03*
X955337Y480262D03*
X955388Y540727D03*
X955389Y536806D03*
X958307Y997496D03*
X961496Y1551855D03*
X981641Y185347D03*
X981366Y276394D03*
X977811Y356910D03*
X986274Y363660D03*
X984862Y1551855D03*
X994429Y217233D03*
Y221233D03*
X993540Y363155D03*
X1015744Y195114D03*
X1015737Y199076D03*
X1013712Y203423D03*
Y210423D03*
Y214423D03*
Y218423D03*
Y222423D03*
X1008255Y363356D03*
X1018286Y517728D03*
Y512574D03*
X1008228Y1551855D03*
X1034350Y264130D03*
X1024350Y297264D03*
Y305313D03*
Y301313D03*
X1031594Y1551855D03*
X1041044Y291105D03*
X1042505Y502161D03*
X1069722Y382141D03*
X1054960Y1551855D03*
X1079206Y78553D03*
X1073681Y509645D03*
X1078326Y1551855D03*
X1076474Y1663950D03*
X1094736Y65262D03*
X1091627Y379251D03*
X1091507Y369061D03*
X1091567Y374131D03*
X1101692Y1551855D03*
X1098547Y1679870D03*
Y1675970D03*
X1097067Y1672030D03*
X1104149Y55505D03*
X1115945Y1429074D03*
Y1432604D03*
X1119127Y1612320D03*
X1119097Y1608420D03*
X1121620Y60545D03*
X1121520Y56545D03*
X1121620Y64545D03*
X1130386Y1448502D03*
X1148887Y211231D03*
X1137407Y377011D03*
X1150527Y373231D03*
X1142050Y1479313D03*
X1149487Y1618960D03*
X1168529Y1448502D03*
X1156178Y1622340D03*
Y1626220D03*
Y1630090D03*
X1160942Y1642600D03*
X1156178Y1633880D03*
X1182588Y61311D03*
X1182488Y65811D03*
X1182508Y57111D03*
X1175762Y202174D03*
Y198174D03*
Y186174D03*
Y218174D03*
Y214174D03*
X1172397Y1601100D03*
Y1609100D03*
Y1605100D03*
X1172277Y1612960D03*
X1179088D03*
X1182942Y1642600D03*
X1171942D03*
X1195317Y93200D03*
X1193493Y127804D03*
X1197492Y236592D03*
X1193512Y1642910D03*
X1193352Y1688390D03*
X1204278Y57130D03*
X1217110Y140962D03*
Y185462D03*
X1207737Y189362D03*
X1210922Y1673963D03*
X1203598Y1677873D03*
X1210852Y1681773D03*
X1204122Y1688435D03*
X1214922Y1688700D03*
X1228517Y94200D03*
Y98400D03*
X1228610Y168162D03*
Y172962D03*
X1242399Y98785D03*
X1239077Y191279D03*
X1248110Y201562D03*
X1239110Y197462D03*
X1248110Y211762D03*
Y205362D03*
Y215762D03*
Y219662D03*
X1248195Y245442D03*
X1259110Y217462D03*
Y233462D03*
Y221462D03*
Y229462D03*
Y225462D03*
Y243562D03*
Y238662D03*
Y247562D03*
X1259310Y251562D03*
X1267271Y88572D03*
Y96768D03*
X1278808Y98828D03*
X1266610Y233462D03*
X1296182Y81169D03*
X1288424Y1370043D03*
X1302551Y64572D03*
X1305280Y81775D03*
X1325081Y261514D03*
X1319327Y1347521D03*
X1351455Y1334095D03*
X1368769Y81111D03*
X1372254Y1330142D03*
X1379562Y1400684D03*
Y1404207D03*
X1370143Y1417374D03*
X1370983Y1413019D03*
X1379557Y1407727D03*
X1385201Y1334095D03*
X1391635Y1390306D03*
X1384193Y1390335D03*
X1408900Y227948D03*
X1403813Y1330042D03*
X1406925Y1565037D03*
X1406865Y1576197D03*
X1406925Y1570037D03*
X1399417Y1586400D03*
Y1590200D03*
X1402517Y1626362D03*
X1410992Y1622200D03*
X1402517Y1634362D03*
Y1638362D03*
X1415711Y1334095D03*
X1427247Y1393959D03*
X1426259Y1417125D03*
Y1413125D03*
Y1409125D03*
Y1420625D03*
Y1427632D03*
Y1424125D03*
X1426287Y1431150D03*
X1417350Y1516435D03*
X1417590Y1532255D03*
X1417350Y1521335D03*
X1417590Y1537155D03*
X1417740Y1548375D03*
Y1543475D03*
X1420787Y1603262D03*
X1424287Y1608442D03*
X1424227Y1616932D03*
X1445017Y211862D03*
Y215862D03*
X1436738Y1330533D03*
X1440197Y1590382D03*
X1440917Y1606800D03*
Y1602600D03*
X1436317Y1632900D03*
Y1620300D03*
X1441250Y1665495D03*
X1441160Y1673955D03*
X1441164Y1669629D03*
X1447839Y1334095D03*
X1454124Y1400385D03*
X1452729Y1411144D03*
X1452425Y1560037D03*
Y1565037D03*
X1450147Y1586262D03*
X1454482Y1612800D03*
X1471400Y225448D03*
Y233448D03*
X1463900Y242448D03*
X1471602Y263378D03*
Y255378D03*
X1463602Y271378D03*
X1468898Y1319592D03*
X1481425Y281456D03*
X1488917Y421982D03*
X1484897Y431972D03*
X1479967Y1347521D03*
X1495926Y280027D03*
X1508418Y288030D03*
X1501496Y1338837D03*
X1516517Y116462D03*
X1515517Y136162D03*
X1517085Y243362D03*
Y235116D03*
Y258616D03*
Y254616D03*
X1516775Y284956D03*
X1512895Y1369919D03*
X1542469Y152873D03*
X1543254Y634165D03*
X1563096Y655416D03*
Y659416D03*
X1565973Y735691D03*
Y732165D03*
X1589095Y219526D03*
Y227526D03*
X1588856Y248008D03*
X1588876Y243890D03*
X1588836Y252126D03*
X1604297Y654542D03*
X1602477Y722582D03*
X1597433Y1420169D03*
Y1433669D03*
Y1438169D03*
Y1452071D03*
X1611337Y586762D03*
X1617419Y1426366D03*
Y1429896D03*
X1626550Y117627D03*
Y129627D03*
Y121627D03*
X1631860Y1445794D03*
X1654746Y544622D03*
X1653925Y635791D03*
X1646099Y652601D03*
X1653925Y669791D03*
X1646099Y686601D03*
X1653925Y703791D03*
X1646099Y720601D03*
X1643124Y1476695D03*
X1661820Y550382D03*
X1662877Y598522D03*
X1670003Y1445794D03*
X1668615Y1493362D03*
Y1501362D03*
Y1516862D03*
Y1533862D03*
Y1520862D03*
Y1545862D03*
X1668690Y1561557D03*
X1668615Y1557557D03*
X1668690Y1581321D03*
X1684448Y495290D03*
Y499290D03*
X1701811Y369773D03*
Y373773D03*
X1699901Y401485D03*
X1693793Y525507D03*
Y529507D03*
Y533507D03*
Y549507D03*
X1703544Y655141D03*
X1700937Y688130D03*
Y691730D03*
Y695330D03*
X1701977Y726552D03*
X1711734Y174970D03*
X1714707Y364962D03*
X1719946Y474859D03*
Y478869D03*
X1722435Y112867D03*
X1736218Y486837D03*
X1722672Y688211D03*
X1748905Y100307D03*
X1751237Y372452D03*
X1741452Y1451841D03*
X1760585Y76797D03*
X1760555Y72637D03*
X1763527Y164362D03*
X1757158Y433221D03*
X1760258Y461393D03*
X1760368Y465893D03*
X1757773Y692742D03*
X1754542Y1475951D03*
X1782195Y92927D03*
X1771892Y169903D03*
X1779945Y291876D03*
X1779960Y295643D03*
Y299243D03*
X1784816Y403932D03*
Y410432D03*
Y418932D03*
Y425432D03*
X1787680Y70987D03*
X1799782Y165565D03*
X1792288Y367866D03*
X1791586Y390252D03*
X1795544Y1527366D03*
X1803307Y156557D03*
X1810267Y179897D03*
X1817249Y371329D03*
X1817086Y395552D03*
X1816316Y407932D03*
Y403225D03*
X1815816Y421432D03*
Y427932D03*
X1815758Y472521D03*
X1806658Y1494318D03*
Y1498318D03*
X1815231Y1504241D03*
X1823568Y363731D03*
Y367701D03*
X1823186Y379552D03*
Y383952D03*
X1832458Y459121D03*
X1835852Y182712D03*
X1842972Y176722D03*
G54D138*
X286253Y154803D03*
X601156Y205978D03*
X823514Y136898D03*
X847479Y214391D03*
X1174681Y1625220D03*
X1734992Y370384D03*
G54D174*
X450000Y278543D03*
X460000D03*
X470000D03*
X483500Y246362D03*
X480000Y278543D03*
X493500Y246362D03*
X490000Y278543D03*
X500000D03*
X510000D03*
X518563Y607067D03*
X508563D03*
X559236Y1441207D03*
X569236D03*
X688500Y1601900D03*
Y1611900D03*
X1041435Y143357D03*
Y153357D03*
X1056225Y143131D03*
Y153131D03*
X1099970Y1702570D03*
Y1712570D03*
X1689646Y115669D03*
X1679646D03*
X1689646Y125669D03*
Y135669D03*
X1679646Y125669D03*
Y135669D03*
X1689646Y145669D03*
Y155669D03*
X1679646Y145669D03*
Y155669D03*
X1689646Y165669D03*
X1679646D03*
X1689646Y175669D03*
X1771457Y1634646D03*
Y1644646D03*
G54D264*
X1025609Y286776D03*
X1027183D03*
X1028758D03*
X1030333D03*
X1031908D03*
X1033483D03*
X1035057D03*
X1802550Y1510568D03*
X1800975D03*
X1799400D03*
X1797826D03*
X1807274D03*
X1805700D03*
X1804125D03*
G54D255*
X1003672Y376725D03*
X1001704D03*
X999735D03*
X997767D03*
X995798D03*
X993830D03*
Y407237D03*
X995798D03*
X997767D03*
X999735D03*
X1001704D03*
X1003672D03*
X1019420Y376725D03*
X1017452D03*
X1015483D03*
X1013515D03*
X1011546D03*
X1009578D03*
X1007609D03*
X1005641D03*
Y407237D03*
X1007609D03*
X1009578D03*
X1011546D03*
X1013515D03*
X1015483D03*
X1017452D03*
X1019420D03*
G54D63*
X84430Y1334666D03*
X1093936Y1616149D03*
X1769097Y1332916D03*
G54D318*
X1795857Y1510765D03*
G54D346*
G01X272361Y120243D02*
X272333Y120215D01*
Y115315D01*
G01X270364D02*
Y118415D01*
G01X703520Y119440D02*
Y122540D01*
G01X706673Y122762D02*
X705489Y121578D01*
Y119440D01*
G01X1009895Y192359D02*
X1009867Y192387D01*
X1004967D01*
G01Y194356D02*
X1008067D01*
G01X1702959Y401485D02*
Y404243D01*
G01D02*
X1699130Y408072D01*
Y408769D01*
G01X1747482Y121367D02*
X1747454Y121339D01*
Y116439D01*
G01X1745485D02*
Y119539D01*
G54D337*
G01X79187Y1533173D02*
Y1532419D01*
X78524Y1531756D01*
G01X79187Y1543015D02*
X75683Y1546519D01*
X75274D01*
G01X103397Y639477D02*
Y638213D01*
X102402Y637218D01*
X99556D01*
X98600Y636262D01*
G01X99460Y649713D02*
X97552D01*
X97201Y649362D01*
X94590D01*
X94250Y649702D01*
G01D02*
X91500Y652452D01*
Y655563D01*
X90499Y656564D01*
X88715D01*
G01X93361Y1533173D02*
Y1532582D01*
X94074Y1531869D01*
G01X93361Y1543015D02*
X94463Y1545675D01*
G01X112480Y507792D02*
X109607D01*
G01X110220Y502069D02*
X112366D01*
X115153Y504856D01*
X116776D01*
G01X111467Y505374D02*
X113323D01*
X114380Y506431D01*
X116776D01*
G01X110060Y515279D02*
X110115Y515334D01*
X112449D01*
X115053Y512730D01*
X116776D01*
G01X108025Y513374D02*
X108604Y512795D01*
X113085D01*
X114725Y511155D01*
X116776D01*
G01X110607Y517932D02*
X111690D01*
X112578Y517044D01*
G01X104972Y639477D02*
Y637169D01*
X102269Y634466D01*
G01X101822Y639477D02*
Y638954D01*
X101346Y638478D01*
X97216D01*
G01X114311Y509581D02*
X116776D01*
G01Y508006D02*
X112634D01*
X112480Y507852D01*
Y507792D01*
G01X119138Y521005D02*
Y519817D01*
G01X112578Y517044D02*
X115317Y514305D01*
X116776D01*
G01Y515880D02*
X115582D01*
X114472Y516990D01*
Y518928D01*
G01X118358Y646564D02*
X119869D01*
X122170Y644263D01*
Y642179D01*
X124163Y640186D01*
Y640103D01*
G01Y636153D02*
X124254Y636244D01*
Y640012D01*
X124163Y640103D01*
G01X121400Y638062D02*
X120518Y638944D01*
Y644007D01*
X119536Y644989D01*
X118358D01*
G01X124163Y647103D02*
Y645890D01*
X125890Y644163D01*
G01X118358Y648139D02*
X119402D01*
X121903Y647103D01*
X124163D01*
G01X125163Y656603D02*
X124272D01*
X122329Y654660D01*
G01D02*
X121294Y653625D01*
X119455Y652863D01*
X118358D01*
G01Y651288D02*
X121634D01*
X122280Y651934D01*
G01X118358Y649713D02*
X124278D01*
X124422Y649569D01*
X124430D01*
X124431Y649570D01*
G01X122599Y661515D02*
X122120Y661036D01*
Y659141D01*
X120585Y655435D01*
X119588Y654438D01*
X118358D01*
G01X141462Y507600D02*
X139481Y509581D01*
X135674D01*
G01X129762Y531942D02*
X130162Y531542D01*
Y530014D01*
X129590Y529442D01*
Y524162D01*
X130162Y523590D01*
Y519817D01*
G01X133160Y532002D02*
Y532652D01*
X131650Y534162D01*
X128810D01*
X127530Y532882D01*
Y523822D01*
X128587Y522765D01*
Y519817D01*
G01X133312Y521783D02*
Y519817D01*
G01X131737D02*
Y522181D01*
G01X159858Y1409361D02*
Y1406376D01*
X161122Y1405112D01*
Y1403338D01*
G01X199164Y582481D02*
X199664Y582688D01*
X201629Y583079D01*
X204723D01*
G01Y617079D02*
X201629D01*
X199664Y616688D01*
X199164Y616481D01*
G01X204723Y651079D02*
X201629D01*
X199664Y650688D01*
X199164Y650481D01*
G01X198001Y1409361D02*
Y1406371D01*
X199265Y1405107D01*
Y1403338D01*
G01X305157Y1360134D02*
X305839Y1358488D01*
X307076Y1357251D01*
G01D02*
X308175D01*
G01X318649Y1361484D02*
Y1365600D01*
X318051Y1367043D01*
G01X340304Y1334454D02*
X339211D01*
X337847Y1335818D01*
Y1336954D01*
X335673Y1339128D01*
G01X347029Y847081D02*
Y844972D01*
X347028Y844971D01*
G01X347461Y1132154D02*
Y1134264D01*
G01X350179Y1344245D02*
X350777Y1342802D01*
Y1338686D01*
G01X372432Y1321028D02*
X371333D01*
X371332Y1321027D01*
X370095Y1322264D01*
X369413Y1323910D01*
G01X382307Y1330819D02*
X382905Y1329376D01*
Y1325260D01*
G01X404560Y1321028D02*
X403096D01*
X402109Y1322015D01*
Y1322993D01*
X399935Y1325167D01*
G01X397900Y1413619D02*
X398085Y1413434D01*
X399991D01*
X401767Y1415210D01*
G01D02*
X402428Y1415871D01*
X406162D01*
X410201Y1411832D01*
X414197D01*
X414367Y1412002D01*
X416155D01*
G01X414435Y1330819D02*
X415033Y1329376D01*
Y1325260D01*
G01X418320Y1383862D02*
X421962Y1387504D01*
Y1401470D01*
G01X418813D02*
Y1396063D01*
X417920Y1395170D01*
G01X420387Y1401470D02*
Y1392141D01*
X418552Y1390306D01*
G01X410912Y1418177D02*
Y1418049D01*
X413810Y1415151D01*
X416155D01*
G01X412416Y1431645D02*
X414547D01*
X420387Y1425805D01*
Y1424108D01*
G01X419302Y1434700D02*
X423537Y1430465D01*
Y1424108D01*
G01X436688Y1321028D02*
X435587D01*
X434351Y1322264D01*
X433669Y1323910D01*
G01X422320Y1383862D02*
X423537Y1385079D01*
Y1401470D01*
G01X426320Y1383862D02*
Y1383870D01*
X425112Y1385078D01*
Y1401470D01*
G01X430320Y1383862D02*
X426687Y1387495D01*
Y1401470D01*
G01X439030Y1383692D02*
X435445D01*
X428261Y1390876D01*
Y1401470D01*
G01X436780Y1387387D02*
X436520D01*
X432243Y1391664D01*
Y1391779D01*
G01X441369Y1394260D02*
X439254D01*
X434561Y1398953D01*
Y1401470D01*
G01X432243Y1391779D02*
X429836Y1394186D01*
Y1401470D01*
G01X436467Y1391687D02*
X431411Y1396743D01*
Y1401470D01*
G01X443842Y1389106D02*
X442168D01*
X432986Y1398288D01*
Y1401470D01*
G01X440164Y1433982D02*
X439050Y1432868D01*
Y1430757D01*
X434561Y1426268D01*
Y1424108D01*
G01X437299Y1436774D02*
Y1431615D01*
X432986Y1427302D01*
Y1424108D01*
G01X433539Y1430613D02*
X431411Y1428485D01*
Y1424108D01*
G01X419861Y1429718D02*
X421962Y1427617D01*
Y1424108D01*
G01X425030Y1434292D02*
X425112Y1434210D01*
Y1424108D01*
G01X422708Y1437560D02*
X425383D01*
X427390Y1435553D01*
Y1433013D01*
X426687Y1432310D01*
Y1424108D01*
G01X433954Y1439029D02*
X431542D01*
X430291Y1437778D01*
G01D02*
X429040Y1436527D01*
Y1432621D01*
X428261Y1431842D01*
Y1424108D01*
G01X433897Y1434670D02*
X429836Y1430609D01*
Y1424108D01*
G01X446563Y1330819D02*
X446788Y1330277D01*
X447161Y1328401D01*
Y1325260D01*
G01X443424Y1397869D02*
Y1399269D01*
X440960Y1401733D01*
Y1404633D01*
X440776Y1405077D01*
X440151Y1405702D01*
X438793D01*
G01X438458Y1402169D02*
X438793Y1402504D01*
Y1404128D01*
G01X439391Y1398266D02*
X437897D01*
X436135Y1400028D01*
Y1401470D01*
G01X447110Y1403812D02*
X447010Y1403912D01*
X446931D01*
X444475Y1406368D01*
X444059Y1407372D01*
X441004Y1410427D01*
X438793D01*
G01X448114Y1396939D02*
Y1399690D01*
X443630Y1404174D01*
Y1405010D01*
X442970Y1406602D01*
X440720Y1408852D01*
X438793D01*
G01Y1407277D02*
X440455D01*
X441850Y1405882D01*
X442290Y1404820D01*
Y1403192D01*
X446150Y1399332D01*
Y1393732D01*
X448020Y1391862D01*
G01X438793Y1415151D02*
X442557D01*
X443157Y1415751D01*
X445339D01*
G01X446230Y1407722D02*
X441950Y1412002D01*
X438793D01*
G01X445230Y1411719D02*
X444844D01*
X442987Y1413576D01*
X438793D01*
G01Y1416726D02*
X441617D01*
X444621Y1419730D01*
X445723D01*
G01D02*
X447421D01*
X450026Y1417125D01*
G01X438793Y1419876D02*
X440190D01*
X440955Y1420641D01*
Y1424497D01*
X445294Y1428836D01*
Y1430415D01*
G01X438793Y1418301D02*
X440644D01*
X442467Y1420124D01*
Y1422021D01*
X443850Y1423404D01*
G01D02*
X445577D01*
X447019Y1421962D01*
X449421D01*
X450026Y1421357D01*
Y1420625D01*
G01X438645Y1426890D02*
X437478D01*
X436135Y1425547D01*
Y1424108D01*
G01X450026Y1427632D02*
Y1424125D01*
G01Y1427632D02*
Y1431123D01*
X450015Y1431134D01*
G01D02*
X446013D01*
X445294Y1430415D01*
G01X443715Y1436052D02*
Y1434067D01*
X441127Y1431479D01*
Y1426569D01*
X438793Y1424235D01*
Y1421450D01*
G01X443715Y1436052D02*
X446254D01*
X446258Y1436056D01*
G01D02*
X449778D01*
G01X468816Y1321028D02*
X467715D01*
X466479Y1322264D01*
X465797Y1323910D01*
G01X478691Y1330819D02*
X479289Y1329376D01*
Y1325260D01*
G01X472701Y1404395D02*
X477368D01*
G01D02*
X481468D01*
G01X468620Y1404387D02*
X472693D01*
X472701Y1404395D01*
G01X485141Y1405430D02*
X482503D01*
X481468Y1404395D01*
G01X489429Y1414412D02*
X487253D01*
X484971Y1415339D01*
X484294D01*
G01X489429Y1411262D02*
X483821D01*
G01X500944Y1334454D02*
X499843D01*
X498607Y1335690D01*
X497925Y1337336D01*
G01X489429Y1408112D02*
X487823D01*
X485141Y1405430D01*
G01X489429Y1412837D02*
X486117D01*
X484921Y1413246D01*
G01X510819Y1344245D02*
X511417Y1342802D01*
Y1338686D01*
G01X531972Y1357251D02*
X530735Y1358488D01*
X530053Y1360134D01*
G01X533071Y1357251D02*
X531972D01*
G01X542947Y1367043D02*
X543545Y1365600D01*
Y1361484D01*
G01X673477Y1409386D02*
Y1406400D01*
X674741Y1405136D01*
Y1403363D01*
G01X711620Y1409386D02*
Y1406400D01*
X712884Y1405136D01*
Y1403363D01*
G01X986400Y383123D02*
X991369D01*
G01X1033483Y286776D02*
Y289751D01*
X1034380Y290648D01*
Y291448D01*
G01X1027183Y286776D02*
Y288108D01*
X1027180Y288111D01*
Y289163D01*
X1025862Y290481D01*
Y291727D01*
G01D02*
X1024258Y293331D01*
G01X1030333Y286776D02*
Y291567D01*
G01D02*
Y292180D01*
G01X1031908Y286776D02*
Y290875D01*
X1032317Y291284D01*
G01X1133169Y1445690D02*
Y1442705D01*
X1134433Y1441441D01*
Y1439667D01*
G01X1171342Y1445650D02*
Y1442675D01*
X1172576Y1441441D01*
Y1439667D01*
G01X1281418Y1360370D02*
X1282100Y1358724D01*
X1283337Y1357487D01*
G01X1293802Y187049D02*
X1292303Y184841D01*
G01X1293802Y183349D02*
X1292303Y184841D01*
G01Y180902D02*
X1293802Y183349D01*
G01X1292303Y180902D02*
X1290669Y178932D01*
G01X1293802Y190749D02*
X1292303Y188780D01*
G01X1293802Y198149D02*
X1292303Y196657D01*
G01X1293802Y194449D02*
X1292303Y196657D01*
G01Y188780D02*
X1293802Y187049D01*
G01X1292303Y192718D02*
X1293802Y190749D01*
G01X1292303Y192718D02*
X1293802Y194449D01*
G01X1283337Y1357487D02*
X1284436D01*
X1284437Y1357488D01*
G01X1294312Y1367279D02*
X1294910Y1365836D01*
Y1361720D01*
G01X1326320Y1344245D02*
X1326918Y1342802D01*
Y1338686D01*
G01X1332854Y1103316D02*
Y1105425D01*
X1332853Y1105426D01*
G01X1358865Y182484D02*
X1360451Y184841D01*
G01Y180902D02*
X1358865Y178544D01*
G01X1358371Y188778D02*
X1360451Y188780D01*
G01X1358865Y195240D02*
X1360451Y192718D01*
G01X1358865Y199180D02*
X1360451Y196657D01*
G01Y200596D02*
X1358865Y199180D01*
G01X1360451Y200596D02*
X1358865Y203120D01*
G01X1360451Y192718D02*
X1358371Y188778D01*
G01X1360451Y196657D02*
X1358865Y195240D01*
G01Y207060D02*
X1360451Y204535D01*
G01X1358865Y203120D02*
X1360451Y204535D01*
G01X1358865Y217934D02*
X1360451Y216352D01*
G01Y212413D02*
X1358865Y213994D01*
G01D02*
X1359906Y215542D01*
X1360310Y216142D01*
X1360451Y216352D01*
G01X1358448Y1330819D02*
X1359046Y1329376D01*
Y1325260D01*
G01X1374041Y1413019D02*
X1375671D01*
X1375879Y1413227D01*
X1385055D01*
X1386280Y1412002D01*
X1392296D01*
G01X1390576Y1330819D02*
X1391174Y1329376D01*
Y1325260D01*
G01X1382347Y1397178D02*
X1382687D01*
X1382737Y1397228D01*
X1386181D01*
G01X1392296Y1404128D02*
Y1397235D01*
X1390513Y1395452D01*
G01D02*
X1388737Y1397228D01*
X1386181D01*
G01X1391543Y1390306D02*
X1388759D01*
X1388730Y1390335D01*
X1387251D01*
G01X1394954Y1401470D02*
Y1396075D01*
X1393957Y1395078D01*
G01D02*
X1391543Y1392664D01*
Y1390306D01*
G01X1394693D02*
Y1391114D01*
X1396528Y1392949D01*
Y1401470D01*
G01X1393630Y1426562D02*
Y1426422D01*
X1394954Y1425098D01*
Y1424108D01*
G01X1388557Y1431645D02*
X1388677Y1431765D01*
X1391044D01*
X1396528Y1426281D01*
Y1424108D01*
G01X1395443Y1434700D02*
X1399678Y1430465D01*
Y1424108D01*
G01X1408270Y847081D02*
Y844972D01*
X1408269Y844971D01*
G01X1396311Y1385712D02*
X1398103Y1387504D01*
Y1401470D01*
G01X1398680Y1380582D02*
Y1384081D01*
X1399678Y1385079D01*
Y1401470D01*
G01X1401655Y1384676D02*
X1401253Y1385078D01*
Y1401470D01*
G01X1406461Y1383862D02*
X1402828Y1387495D01*
Y1401470D01*
G01X1415171Y1383692D02*
X1411586D01*
X1404402Y1390876D01*
Y1401470D01*
G01X1412961Y1387387D02*
X1412661D01*
X1408384Y1391664D01*
Y1391779D01*
G01X1419055Y1392497D02*
X1417292Y1394260D01*
X1414883D01*
X1410702Y1398441D01*
Y1401470D01*
G01X1408384Y1391779D02*
X1405977Y1394186D01*
Y1401470D01*
G01X1412608Y1391687D02*
X1407552Y1396743D01*
Y1401470D01*
G01X1418990Y1387452D02*
Y1388273D01*
X1409127Y1398136D01*
Y1401470D01*
G01X1416272Y1433949D02*
X1415191Y1432868D01*
Y1430757D01*
X1410702Y1426268D01*
Y1424108D01*
G01X1413440Y1436774D02*
Y1431615D01*
X1409127Y1427302D01*
Y1424108D01*
G01X1409680Y1430613D02*
X1407552Y1428485D01*
Y1424108D01*
G01X1395907Y1430227D02*
X1398103Y1428031D01*
Y1424108D01*
G01X1401371Y1434592D02*
Y1424226D01*
X1401253Y1424108D01*
G01X1398569Y1437860D02*
X1401692D01*
X1403750Y1435802D01*
Y1433232D01*
X1402828Y1432310D01*
Y1424108D01*
G01X1410477Y1440117D02*
X1408771D01*
X1405181Y1436527D01*
Y1432621D01*
X1404402Y1431842D01*
Y1424108D01*
G01X1410038Y1434670D02*
X1405977Y1430609D01*
Y1424108D01*
G01X1415670Y847081D02*
Y844972D01*
X1415669Y844971D01*
G01X1422704Y1330819D02*
X1422911Y1330319D01*
X1423302Y1328354D01*
Y1325260D01*
G01X1419995Y1397492D02*
X1417101Y1400386D01*
Y1404633D01*
X1416917Y1405077D01*
X1416292Y1405702D01*
X1414934D01*
G01X1414362Y1402191D02*
X1414934Y1402763D01*
Y1404128D01*
G01X1415620Y1396652D02*
X1412276Y1399996D01*
Y1401470D01*
G01X1423256Y1403728D02*
X1420616Y1406368D01*
X1420200Y1407372D01*
X1417145Y1410427D01*
X1414934D01*
G01X1424255Y1396612D02*
Y1399878D01*
X1419771Y1404362D01*
Y1405010D01*
X1419111Y1406602D01*
X1416861Y1408852D01*
X1414934D01*
G01Y1407277D02*
X1416596D01*
X1417991Y1405882D01*
X1418431Y1404820D01*
Y1402852D01*
X1422360Y1398923D01*
Y1393663D01*
X1424161Y1391862D01*
G01X1414934Y1415151D02*
X1418698D01*
X1419298Y1415751D01*
X1421480D01*
G01X1422371Y1407722D02*
X1418091Y1412002D01*
X1414934D01*
G01X1421371Y1411719D02*
X1420985D01*
X1419128Y1413576D01*
X1414934D01*
G01Y1416726D02*
X1417758D01*
X1420762Y1419730D01*
X1421864D01*
G01D02*
X1423562D01*
X1426167Y1417125D01*
G01X1414934Y1419876D02*
X1416331D01*
X1417096Y1420641D01*
Y1424131D01*
X1419604Y1426639D01*
Y1428584D01*
X1421435Y1430415D01*
G01X1426167Y1420625D02*
Y1421357D01*
X1425562Y1421962D01*
X1423160D01*
X1421718Y1423404D01*
X1419991D01*
G01D02*
X1418608Y1422021D01*
Y1420124D01*
X1416785Y1418301D01*
X1414934D01*
G01X1414786Y1426890D02*
X1413619D01*
X1412276Y1425547D01*
Y1424108D01*
G01X1426167Y1424125D02*
Y1427632D01*
G01X1426195Y1431150D02*
X1422170D01*
X1421435Y1430415D01*
G01X1426167Y1427632D02*
Y1431122D01*
X1426195Y1431150D01*
G01X1427349Y1436566D02*
X1423529D01*
X1423519Y1436576D01*
G01X1419746Y1435932D02*
Y1433957D01*
X1417268Y1431479D01*
Y1426569D01*
X1414934Y1424235D01*
Y1421450D01*
G01X1423519Y1436576D02*
X1420390D01*
X1419746Y1435932D01*
G01X1454832Y1330819D02*
X1455430Y1329376D01*
Y1325260D01*
G01X1465570Y1408112D02*
X1463774D01*
G01X1465570Y1411262D02*
X1460166D01*
G01X1465570Y1414412D02*
X1462925D01*
X1461519Y1415333D01*
X1460804D01*
G01X1465570Y1412837D02*
X1462397D01*
X1461062Y1413246D01*
G01X1486960Y1344245D02*
X1487558Y1342802D01*
Y1338686D01*
G01X1511624Y291175D02*
X1512244Y291795D01*
Y294071D01*
G01X1519088Y1367043D02*
X1519686Y1365600D01*
Y1361484D01*
G01X1634643Y1442982D02*
Y1439997D01*
X1635907Y1438733D01*
Y1436959D01*
G01X1654809Y638101D02*
X1654309Y637894D01*
X1652344Y637503D01*
X1649250D01*
G01X1654809Y672101D02*
X1654309Y671894D01*
X1652344Y671503D01*
X1649250D01*
G01X1654809Y706101D02*
X1654309Y705894D01*
X1652344Y705503D01*
X1649250D01*
G01X1663468Y536278D02*
X1666555D01*
G01X1659740Y542222D02*
X1662037D01*
X1664832Y539427D01*
X1666555D01*
G01Y537852D02*
X1664504D01*
X1662864Y539492D01*
X1658383D01*
X1657804Y540071D01*
G01X1666555Y534703D02*
X1661872D01*
G01D02*
X1659172D01*
G01X1659999Y528766D02*
X1661541D01*
X1664328Y531553D01*
X1666555D01*
G01X1661246Y532071D02*
X1662406D01*
X1663463Y533128D01*
X1666555D01*
G01X1662285Y543813D02*
X1665096Y541002D01*
X1666555D01*
G01Y542577D02*
X1665361D01*
X1664251Y543687D01*
Y545625D01*
G01X1668917Y548575D02*
Y546514D01*
G01X1660386Y544629D02*
X1661469D01*
X1662285Y543813D01*
G01X1687506Y495290D02*
Y493680D01*
X1689536Y491650D01*
Y488833D01*
X1691800Y486569D01*
X1693311D01*
G01X1687506Y488290D02*
X1689981Y485815D01*
X1691963Y484994D01*
X1693311D01*
G01X1683063Y491790D02*
X1685219D01*
X1685779Y491230D01*
G01X1687506Y488290D02*
Y489503D01*
X1685779Y491230D01*
G01X1687238Y485496D02*
Y485473D01*
X1692196Y483420D01*
X1693311D01*
G01X1687506Y495290D02*
Y499290D01*
G01X1691445Y535011D02*
X1689043D01*
X1687776Y536278D01*
X1685453D01*
G01X1679941Y546514D02*
Y552222D01*
G01X1678860Y556752D02*
X1677870Y555762D01*
Y549992D01*
X1678366Y549496D01*
Y546514D01*
G01X1683091D02*
Y547012D01*
G01X1681516Y546514D02*
Y549707D01*
G01X1672786Y1442982D02*
Y1439996D01*
X1674050Y1438732D01*
Y1436959D01*
G01X1689070Y473878D02*
Y475812D01*
X1691953Y478695D01*
X1693311D01*
G01X1689070Y473878D02*
Y469878D01*
G01D02*
Y465965D01*
X1689095Y465940D01*
G01D02*
Y462640D01*
G01X1691151Y493678D02*
Y489126D01*
X1692133Y488144D01*
X1693311D01*
G01Y480270D02*
X1692214D01*
X1690669Y479630D01*
X1690343Y479304D01*
X1689943D01*
G01X1690229Y481845D02*
X1693311D01*
G01X1707200Y498962D02*
X1706697Y498459D01*
Y493656D01*
G01X1719854Y482869D02*
X1719003Y483720D01*
X1716148D01*
G01D02*
X1715848Y483420D01*
X1712209D01*
G01X1709847Y493656D02*
Y495704D01*
X1713555Y499412D01*
X1713655D01*
G01X1710505D02*
Y499329D01*
X1708272Y497096D01*
Y493656D01*
G01X1797826Y1510568D02*
Y1508942D01*
X1796627Y1506049D01*
X1795223Y1504645D01*
Y1502745D01*
G01X1799400Y1510568D02*
Y1508830D01*
G01X1802550Y1510568D02*
Y1504331D01*
X1802150Y1503931D01*
Y1502555D01*
G01X1800975Y1510568D02*
Y1507705D01*
G01X1804125Y1510568D02*
Y1507505D01*
X1804410Y1507220D01*
Y1505801D01*
G01X1805700Y1510568D02*
Y1508630D01*
X1807150Y1507180D01*
Y1506354D01*
G54D328*
G01X1194713Y123920D02*
Y118101D01*
G54D139*
X285803Y243637D03*
X301551D03*
X312693Y59753D03*
X328441D03*
X747269Y79238D03*
X763017D03*
X890259Y256240D03*
X906007D03*
X1655999Y385598D03*
X1671747D03*
X1784364Y61037D03*
X1800112D03*
G54D283*
X1280249Y133513D03*
G54D292*
X1316569Y268316D03*
Y275008D03*
X1325231Y268316D03*
Y275008D03*
G54D37*
X55374Y390301D03*
X618644Y148781D03*
G54D73*
X95132Y1539669D03*
Y1538094D03*
Y1536519D03*
G54D175*
X451062Y364503D03*
X448503D03*
X445944D03*
Y387503D03*
X448503D03*
X451062D03*
X451421Y434003D03*
X448862D03*
X446303D03*
X443744D03*
Y457003D03*
X446303D03*
X448862D03*
X451421D03*
X461298Y364503D03*
X458739D03*
X456180D03*
X453621D03*
Y387503D03*
X456180D03*
X458739D03*
X461298D03*
X459098Y434003D03*
X456539D03*
X453980D03*
Y457003D03*
X456539D03*
X459098D03*
X482952Y433862D03*
X480393D03*
Y456862D03*
X482952D03*
X495747Y433862D03*
X493188D03*
X490629D03*
X488070D03*
X485511D03*
Y456862D03*
X488070D03*
X490629D03*
X493188D03*
X495747D03*
X550024Y373573D03*
Y396573D03*
X565378Y373573D03*
X562819D03*
X560260D03*
X557701D03*
X555142D03*
X552583D03*
Y396573D03*
X555142D03*
X557701D03*
X560260D03*
X562819D03*
X565378D03*
X842596Y58448D03*
X840037D03*
Y81448D03*
X842596D03*
X847715Y58448D03*
X845156D03*
Y81448D03*
X847715D03*
X1460718Y378996D03*
X1458159D03*
X1455600D03*
Y401996D03*
X1458159D03*
X1460718D03*
X1470954Y378996D03*
X1468395D03*
X1465836D03*
X1463277D03*
Y401996D03*
X1465836D03*
X1468395D03*
X1470954D03*
X1492002Y378788D03*
X1489443D03*
X1486884D03*
X1484325D03*
X1481766D03*
X1479207D03*
Y401788D03*
X1481766D03*
X1484325D03*
X1486884D03*
X1489443D03*
X1492002D03*
X1494561Y378788D03*
Y401788D03*
G54D166*
X393415Y209949D03*
Y212508D03*
Y215067D03*
Y217626D03*
Y220185D03*
Y222744D03*
Y225303D03*
X416415Y217626D03*
Y215067D03*
Y212508D03*
Y209949D03*
Y225303D03*
Y222744D03*
Y220185D03*
X471000Y212685D03*
Y215244D03*
Y217803D03*
Y220362D03*
Y222921D03*
Y225480D03*
Y228039D03*
X494000Y217803D03*
Y215244D03*
Y212685D03*
Y228039D03*
Y225480D03*
Y222921D03*
Y220362D03*
X598416Y222287D03*
Y224846D03*
Y227406D03*
Y229965D03*
X616014D03*
Y227406D03*
Y224846D03*
Y222287D03*
X1436383Y222771D03*
Y225330D03*
Y227889D03*
Y230448D03*
Y233007D03*
Y235566D03*
Y238125D03*
X1435880Y251265D03*
Y253824D03*
Y256383D03*
Y258942D03*
Y261501D03*
Y264060D03*
Y266619D03*
X1459383Y233007D03*
Y230448D03*
Y227889D03*
Y225330D03*
Y222771D03*
Y238125D03*
Y235566D03*
X1458880Y266619D03*
Y264060D03*
Y261501D03*
Y258942D03*
Y256383D03*
Y253824D03*
Y251265D03*
G54D229*
X839035Y512888D03*
Y515447D03*
Y518006D03*
X845483D03*
Y515447D03*
Y512888D03*
G54D193*
X542554Y465696D03*
Y468255D03*
Y470814D03*
Y473373D03*
Y475932D03*
Y478492D03*
Y481051D03*
Y483610D03*
Y486169D03*
Y488728D03*
X565586Y478492D03*
Y475932D03*
Y473373D03*
Y470814D03*
Y468255D03*
Y465696D03*
Y488728D03*
Y486169D03*
Y483610D03*
Y481051D03*
X1790546Y441108D03*
Y443667D03*
Y446226D03*
Y448785D03*
Y451344D03*
Y453904D03*
Y456463D03*
Y459022D03*
Y461581D03*
Y464140D03*
X1813578Y443667D03*
Y441108D03*
Y461581D03*
Y459022D03*
Y456463D03*
Y453904D03*
Y451344D03*
Y448785D03*
Y446226D03*
Y464140D03*
G54D157*
X354428Y846881D03*
X353011Y1135559D03*
X371079Y843677D03*
X356279D03*
X359979D03*
X363679D03*
X367379D03*
X356712Y1135559D03*
X358561Y1138763D03*
X362261D03*
X365961D03*
X369661D03*
X378479Y843677D03*
X382179D03*
X385879D03*
X374779D03*
X377061Y1138763D03*
X380761D03*
X384461D03*
X373361D03*
X389579Y843677D03*
X393279D03*
X396979D03*
X400679D03*
X388161Y1138763D03*
X391861D03*
X395561D03*
X399261D03*
X402961D03*
X408079Y843677D03*
X411779D03*
X415479D03*
X419179D03*
X404379D03*
X406661Y1138763D03*
X410361D03*
X414061D03*
X417761D03*
X422879Y843677D03*
X426579D03*
X428428Y846881D03*
X432128D03*
X435829D03*
X421461Y1138763D03*
X425161D03*
X428861D03*
X430711Y1135559D03*
X434412D03*
X452479Y843677D03*
X439528Y846881D03*
X443228D03*
X446928D03*
X450629D03*
X438112Y1135559D03*
X441812D03*
X445511D03*
X449212D03*
X467279Y843677D03*
X456179D03*
X459879D03*
X463579D03*
X452912Y1135559D03*
X454761Y1138763D03*
X458461D03*
X462161D03*
X465861D03*
X470979Y843677D03*
X474679D03*
X478379D03*
X482079D03*
X469561Y1138763D03*
X473261D03*
X476961D03*
X480661D03*
X484361D03*
X496879Y843677D03*
X500579D03*
X485779D03*
X489479D03*
X493179D03*
X499161Y1138763D03*
X488061D03*
X491761D03*
X495461D03*
X504279Y843677D03*
X507979D03*
X511679D03*
X515379D03*
X502861Y1138763D03*
X506561D03*
X510261D03*
X513961D03*
X517661D03*
X519079Y843677D03*
X522779D03*
X528329Y846881D03*
X524628D03*
X526912Y1135559D03*
X521361Y1138763D03*
X525061D03*
X1330570Y846881D03*
X1329153Y1135559D03*
X1347221Y843677D03*
X1332421D03*
X1336121D03*
X1339821D03*
X1343521D03*
X1332854Y1135559D03*
X1334703Y1138763D03*
X1338403D03*
X1342103D03*
X1345803D03*
X1354621Y843677D03*
X1358321D03*
X1362021D03*
X1350921D03*
X1353203Y1138763D03*
X1356903D03*
X1360603D03*
X1349503D03*
X1365721Y843677D03*
X1369421D03*
X1373121D03*
X1376821D03*
X1364303Y1138763D03*
X1368003D03*
X1371703D03*
X1375403D03*
X1379103D03*
X1384221Y843677D03*
X1387921D03*
X1391621D03*
X1395321D03*
X1380521D03*
X1382803Y1138763D03*
X1386503D03*
X1390203D03*
X1393903D03*
X1399021Y843677D03*
X1402721D03*
X1404570Y846881D03*
X1408270D03*
X1411971D03*
X1397603Y1138763D03*
X1401303D03*
X1405003D03*
X1406853Y1135559D03*
X1410554D03*
X1428621Y843677D03*
X1415670Y846881D03*
X1419370D03*
X1423070D03*
X1426771D03*
X1414254Y1135559D03*
X1417954D03*
X1421653D03*
X1425354D03*
X1443421Y843677D03*
X1432321D03*
X1436021D03*
X1439721D03*
X1429054Y1135559D03*
X1430903Y1138763D03*
X1434603D03*
X1438303D03*
X1442003D03*
X1447121Y843677D03*
X1450821D03*
X1454521D03*
X1458221D03*
X1445703Y1138763D03*
X1449403D03*
X1453103D03*
X1456803D03*
X1460503D03*
X1473021Y843677D03*
X1476721D03*
X1461921D03*
X1465621D03*
X1469321D03*
X1475303Y1138763D03*
X1464203D03*
X1467903D03*
X1471603D03*
X1480421Y843677D03*
X1484121D03*
X1487821D03*
X1491521D03*
X1479003Y1138763D03*
X1482703D03*
X1486403D03*
X1490103D03*
X1493803D03*
X1495221Y843677D03*
X1498921D03*
X1504471Y846881D03*
X1500770D03*
X1503054Y1135559D03*
X1497503Y1138763D03*
X1501203D03*
G54D247*
X963586Y1595126D03*
Y1612842D03*
X995198Y1595142D03*
Y1612858D03*
X1026798Y1595142D03*
Y1612858D03*
X1058398Y1595142D03*
Y1612858D03*
G54D274*
X1209735Y79660D03*
Y87140D03*
X1208885Y100060D03*
Y103800D03*
Y107540D03*
X1219065Y83400D03*
X1219515Y100060D03*
Y107540D03*
G54D28*
X44967Y416860D03*
Y413710D03*
Y416860D03*
Y420010D03*
X60189Y410770D03*
Y413920D03*
Y417070D03*
Y413920D03*
X50339Y416945D03*
Y413795D03*
Y416945D03*
Y420095D03*
X65533Y410890D03*
Y414040D03*
Y417190D03*
Y414040D03*
X75585Y1517581D03*
Y1514431D03*
Y1517581D03*
Y1520731D03*
X78456Y1560677D03*
Y1557527D03*
Y1560677D03*
Y1563827D03*
X73389Y1560672D03*
Y1563822D03*
Y1560672D03*
Y1557522D03*
X80652Y1514436D03*
Y1517586D03*
D03*
X93571Y1517237D03*
Y1514087D03*
Y1517237D03*
X88426D03*
Y1514087D03*
Y1517237D03*
X80652Y1520736D03*
X93571Y1520387D03*
X88426D03*
X102250Y1560978D03*
Y1564128D03*
Y1567278D03*
Y1564128D03*
X97183Y1567273D03*
Y1564123D03*
Y1560973D03*
Y1564123D03*
X238297Y123968D03*
Y127118D03*
X499680Y85717D03*
Y88867D03*
X612740Y177372D03*
Y180522D03*
X612736Y177350D03*
Y174200D03*
X631025Y174144D03*
Y170994D03*
Y177294D03*
Y174144D03*
X625596D03*
Y170994D03*
Y177294D03*
Y174144D03*
X618352Y177412D03*
Y180562D03*
Y177412D03*
Y174262D03*
X680600Y369837D03*
Y366687D03*
Y372987D03*
Y369837D03*
X695600D03*
Y366687D03*
Y372987D03*
Y369837D03*
X690600D03*
Y366687D03*
Y372987D03*
Y369837D03*
X685600D03*
Y366687D03*
Y372987D03*
Y369837D03*
X710600D03*
Y366687D03*
Y372987D03*
Y369837D03*
X705600D03*
Y366687D03*
Y372987D03*
Y369837D03*
X700600D03*
Y366687D03*
Y372987D03*
Y369837D03*
X715600D03*
Y366687D03*
Y372987D03*
Y369837D03*
X1016770Y229573D03*
Y226423D03*
X1713418Y125092D03*
Y128242D03*
G54D148*
X336240Y147638D03*
X332500D03*
X328760D03*
Y157086D03*
X336240D03*
X442900Y117195D03*
X450380D03*
Y107747D03*
X446640D03*
X442900D03*
X513444Y460733D03*
Y470181D03*
X517184D03*
X520924Y460733D03*
Y470181D03*
X762013Y1703816D03*
X754533D03*
Y1713264D03*
X758273D03*
X762013D03*
X1531917Y116180D03*
X1539397D03*
Y106732D03*
X1535657D03*
X1531917D03*
X1542401Y147711D03*
Y138263D03*
X1549881Y147711D03*
Y138263D03*
X1546141D03*
X1729954Y411578D03*
X1737434D03*
Y402130D03*
X1733694D03*
X1729954D03*
X1765670Y444538D03*
Y453986D03*
X1769410D03*
X1773150Y444538D03*
Y453986D03*
G54D184*
X500453Y1410179D03*
X1476594D03*
G54D319*
X1803633Y1521592D03*
G54D238*
X928739Y321653D03*
G54D64*
X95132Y1534944D03*
G54D55*
X89981Y714088D03*
X1703413Y718214D03*
G54D91*
X159474Y1328627D03*
X183847Y1328652D03*
X208247D03*
X275289Y583576D03*
Y607735D03*
Y631889D03*
Y656043D03*
X270252Y676260D03*
Y700414D03*
X387897Y1242785D03*
X412297D03*
X436619D03*
X461019D03*
X485419D03*
X673093Y1328652D03*
X697466Y1328677D03*
X721866D03*
X1100800Y259362D03*
X1100700Y283662D03*
X1131100Y1364962D03*
X1155500D03*
X1179900D03*
X1364038Y1242785D03*
X1388438D03*
X1412760D03*
X1437160D03*
X1461560D03*
X1577000Y599762D03*
Y624262D03*
Y648762D03*
Y673162D03*
Y697662D03*
Y722162D03*
X1634259Y1362248D03*
X1658632Y1362273D03*
X1683032D03*
G54D82*
X109608Y707039D03*
X132638D03*
X1473922Y298220D03*
X1496952D03*
X1723150Y708355D03*
X1746180D03*
G54D46*
X77416Y1536519D03*
Y1538094D03*
Y1539669D03*
G54D19*
X19360Y304152D03*
X46720Y200787D03*
Y192913D03*
X46745Y208661D03*
X46720Y216535D03*
Y232283D03*
X46359Y240157D03*
X36000Y295952D03*
X39600Y378562D03*
X44700Y375262D03*
X49357Y406260D03*
X40800Y400962D03*
X34356Y412914D03*
X34440Y406562D03*
X47940Y1635504D03*
X43450Y1638102D03*
X59410Y57052D03*
X56370Y66552D03*
X60220Y80860D03*
X63048Y78031D03*
X49594Y304848D03*
X50200Y375262D03*
X63350Y371362D03*
X57342Y375262D03*
X53500Y371362D03*
X52185Y409088D03*
X64922Y405732D03*
X60522D03*
X60333Y1623834D03*
X50333D03*
X55333D03*
X62075Y1661030D03*
X65088Y1666334D03*
X62833Y1671334D03*
X65710Y376042D03*
X70500Y381562D03*
X76200Y395865D03*
X71136Y390398D03*
X76600Y386364D03*
X71480Y399442D03*
X72274Y1530094D03*
X68274Y1533594D03*
X70250Y1544094D03*
X69274Y1539094D03*
X77040Y1601102D03*
X65120Y1609909D03*
X65520Y1615972D03*
X66000Y1623800D03*
X76000D03*
X81000D03*
X71000D03*
X78333Y1661334D03*
X73333D03*
X68088Y1660691D03*
X77833Y1678902D03*
X73833Y1674252D03*
X69833Y1678582D03*
X94585Y164327D03*
X96880Y216535D03*
X96540Y232283D03*
X96396Y416383D03*
X96496Y430383D03*
X96396Y425383D03*
X97496Y446519D03*
X97096Y436383D03*
X97396Y441383D03*
X95250Y637848D03*
X94250Y649702D03*
X94408Y644740D03*
X94160Y657130D03*
X86050Y1527962D03*
X85487Y1556594D03*
X92928Y1556094D03*
X86000Y1623800D03*
X90100Y1650862D03*
X83333Y1661214D03*
X87600Y1655562D03*
X81833Y1674526D03*
X99480Y177165D03*
X106045Y303798D03*
X98896Y420883D03*
X113700Y536792D03*
X108550D03*
X102310Y685500D03*
X112270Y1518907D03*
X102070Y1524694D03*
X101274Y1535594D03*
X100236Y1549531D03*
X100274Y1540594D03*
X101363Y1600667D03*
X101558Y1619821D03*
X104500Y1655800D03*
X109960Y1677362D03*
X118820Y274800D03*
X116482Y409571D03*
X129480Y536662D03*
X124435Y536727D03*
X118880Y536862D03*
X125620Y631065D03*
X119263Y1601131D03*
X123750Y1616882D03*
X119058Y1637862D03*
X117100Y1651800D03*
X121645Y1683362D03*
X114720Y1691362D03*
X114991Y1702633D03*
X138482Y384071D03*
Y392881D03*
X135482Y388571D03*
Y404385D03*
X134896Y429883D03*
X138896Y426608D03*
X134896Y422883D03*
Y443383D03*
X138896Y433383D03*
Y439883D03*
X134896Y436383D03*
X143922Y531783D03*
X133160Y532002D03*
X138793Y1535926D03*
X139453Y1548920D03*
X139247Y1542048D03*
X142884Y1555204D03*
X138300Y1625200D03*
X152877Y411530D03*
X147800Y1414500D03*
X158307Y1531330D03*
X154685Y1558156D03*
X159794Y1558238D03*
X175982Y383071D03*
X173482Y387571D03*
X175982Y392071D03*
X173482Y396571D03*
Y405571D03*
X175982Y401071D03*
X166690Y427733D03*
X166917Y421148D03*
X167359Y443845D03*
X166580Y433115D03*
X171570Y1535141D03*
X174501Y1539847D03*
X175121Y1545985D03*
X172623Y1551715D03*
X169754Y1542489D03*
X175064Y1557874D03*
X181266Y234993D03*
X220054Y462235D03*
X223554Y458235D03*
X220200Y454162D03*
X237220Y57362D03*
X242220D03*
X242200Y119302D03*
X237933Y107835D03*
X239740Y134102D03*
X236920Y146829D03*
X237400Y163962D03*
X228024Y316772D03*
X252220Y57362D03*
X247220D03*
X253090Y87362D03*
X246297Y132012D03*
X254825Y151937D03*
X254940Y146879D03*
X259500Y162662D03*
X260300Y304762D03*
X275000Y153862D03*
X275053Y148703D03*
X275000Y159203D03*
X276234Y165350D03*
X276190Y215532D03*
X270740Y215582D03*
X262140Y234282D03*
X269740D03*
X271620Y266602D03*
X267759Y262672D03*
X274600Y305762D03*
X265824Y305962D03*
X271877Y750415D03*
X272208Y768516D03*
X282000Y143962D03*
X277000D03*
X287200D03*
X292500Y144013D03*
X286234Y165350D03*
X281234D03*
X277340Y234282D03*
X291754Y266962D03*
X281120Y267002D03*
X276620Y262572D03*
X286320Y262752D03*
X279400Y296463D03*
X277046Y735442D03*
X283350Y728483D03*
X285046Y737964D03*
X297700Y144162D03*
X302290Y191222D03*
X307640Y234652D03*
X304354Y263002D03*
X299120Y302112D03*
X304500Y303862D03*
X294760Y553672D03*
X293027Y755985D03*
X316900Y139962D03*
X314249Y223352D03*
X316954Y262752D03*
X316224Y305762D03*
X321100Y360422D03*
X309573Y567704D03*
X319590Y567906D03*
X339195Y131052D03*
X337464Y137082D03*
X335000Y162862D03*
X329648Y262677D03*
X341295Y300452D03*
X332000Y302862D03*
X332808Y357484D03*
X327310Y363143D03*
X327470Y374917D03*
X327550Y388243D03*
X327060Y400371D03*
X327150Y409452D03*
X331020Y594362D03*
X342500Y155942D03*
X342000Y263087D03*
X354672Y263068D03*
X354145Y300892D03*
X355671Y364133D03*
X354100Y720743D03*
X367341Y151303D03*
X373720Y214862D03*
X367326Y263050D03*
X366498Y300723D03*
X364667Y357923D03*
X359000Y359762D03*
X360680Y383412D03*
X357946Y369798D03*
X360140Y375392D03*
X361040Y389478D03*
X360880Y400628D03*
X359669Y686744D03*
X371850Y1534062D03*
X369000Y1639500D03*
X386720Y212508D03*
X386690Y229142D03*
X386540Y223342D03*
X379954Y263232D03*
X379107Y300712D03*
X386670Y297482D03*
X387070Y359122D03*
X385780Y352352D03*
X386540Y367222D03*
X388811Y383335D03*
X386750Y394832D03*
X388735Y388879D03*
X388692Y401745D03*
X385700Y1609400D03*
X389690Y1650552D03*
X381640Y1651162D03*
X375914Y1659005D03*
X378509Y1677584D03*
X394210Y133422D03*
X392554Y263232D03*
X405154Y263472D03*
X392083Y301160D03*
X404215Y301544D03*
X394100Y357592D03*
X403260Y1391142D03*
X394367Y1421475D03*
X396824Y1650332D03*
X409900Y155833D03*
X417754Y263642D03*
X417219Y301637D03*
X417390Y359132D03*
X415630Y374921D03*
X415970Y386252D03*
X415830Y396152D03*
X416498Y402729D03*
X415710Y412972D03*
X414333Y1385292D03*
X417920Y1395170D03*
X411121Y1405157D03*
X422708Y1437560D03*
X413697Y1428315D03*
X416999Y1441908D03*
X407296Y1543686D03*
X407260Y1556810D03*
X407810Y1675512D03*
X423500Y123647D03*
X423580Y129222D03*
X429780Y149373D03*
X423220Y209949D03*
X425780Y220022D03*
X432054Y263264D03*
X429708Y301092D03*
X433956Y381770D03*
X433996Y394722D03*
X437520Y464837D03*
X430320Y1383862D03*
X432243Y1391779D03*
X430291Y1437778D03*
X433897Y1434670D03*
X424921Y1546310D03*
X436383Y1591964D03*
X438749Y1611713D03*
X431500Y1610300D03*
X426510Y1620392D03*
X433021Y1647466D03*
X426968Y1646026D03*
X426728Y1636495D03*
X431035Y1641851D03*
X442650Y101912D03*
X450380Y123012D03*
X442224Y301142D03*
X455000Y340362D03*
X446416Y394306D03*
X454513Y394372D03*
X442802Y424850D03*
X447552Y427100D03*
X452552Y425100D03*
X442520Y464837D03*
X451520D03*
X453423Y505483D03*
X455423Y510983D03*
X453423Y526167D03*
X454885Y539483D03*
X453423Y547519D03*
X445339Y1415731D03*
X443850Y1423404D03*
X445294Y1430415D03*
X445520Y1547437D03*
X447740Y1591180D03*
X445225Y1613427D03*
X446920Y1644280D03*
X465455Y69991D03*
Y64991D03*
Y59991D03*
X464321Y149864D03*
X463821Y154864D03*
X465000Y340362D03*
X467500Y399187D03*
X458052Y427100D03*
X456520Y464837D03*
X461520D03*
X466520D03*
X457423Y529983D03*
Y543899D03*
X461239Y1420649D03*
X471530Y1414650D03*
X459520Y1557437D03*
X457220Y1594495D03*
X459900Y1614582D03*
X460710Y1619602D03*
X465500Y1632442D03*
X466910Y1643242D03*
X467430Y1661242D03*
Y1666242D03*
X464586Y1674991D03*
X486370Y262952D03*
X474310Y293022D03*
X474460Y382405D03*
X485673Y370314D03*
X480174Y370316D03*
X482720Y387370D03*
X479451Y424709D03*
X484201Y426959D03*
X474169Y464696D03*
X479169D03*
X487110Y1399562D03*
X478180Y1454892D03*
X504040Y374320D03*
X500670Y370180D03*
X494720Y370337D03*
X504040Y385560D03*
X490810Y387640D03*
X500220Y391362D03*
X502040Y411905D03*
X492970Y409252D03*
X489201Y424959D03*
X494701Y426959D03*
X493169Y464696D03*
X498169D03*
X488169D03*
X503169D03*
X498423Y511249D03*
X493950Y523893D03*
X498923Y517983D03*
X494423Y514983D03*
X493987Y530097D03*
X499215Y527188D03*
X499123Y538283D03*
X500070Y1424140D03*
X513260Y78242D03*
X518250Y370250D03*
X510720Y370361D03*
X508690Y399850D03*
X517460Y399960D03*
X510220Y416970D03*
X517184Y475952D03*
X522228Y78079D03*
X534565Y139862D03*
X526730Y178803D03*
X536489Y264692D03*
X520830Y376860D03*
X535910Y370450D03*
X527720Y370430D03*
X520890Y387900D03*
X525670Y399850D03*
X533720Y400160D03*
X520760Y417110D03*
X529960Y417620D03*
X530630Y478492D03*
X534990Y481051D03*
X531400Y465696D03*
X535810Y468255D03*
X531380Y470814D03*
X530490Y483610D03*
X535080Y491292D03*
X534890Y486169D03*
X535444Y498578D03*
X546900Y127788D03*
X546461Y135734D03*
X547600Y155028D03*
X544720Y171362D03*
X544820Y161362D03*
X544720Y183921D03*
X549306Y179934D03*
X544390Y236512D03*
X550390Y231742D03*
X542050Y231722D03*
X537720Y278212D03*
X552760Y300922D03*
X552583Y366842D03*
X546830Y403292D03*
X543240Y445136D03*
Y450136D03*
X567520Y87362D03*
X567507Y81049D03*
X562820Y84262D03*
X562783Y78299D03*
X564200Y135562D03*
X567500Y184862D03*
X554306Y179934D03*
X562440Y253826D03*
X562564Y259202D03*
X558240Y300872D03*
X557490Y361932D03*
X553210Y403652D03*
X564170Y403477D03*
X558590Y403597D03*
X572220Y83562D03*
X572231Y77862D03*
X578765Y152912D03*
X578720Y167112D03*
X585031Y215378D03*
X580320Y252173D03*
X575050Y383602D03*
X580629Y370896D03*
X576907Y374655D03*
X570700Y397162D03*
X569600Y403562D03*
X572430Y459232D03*
X576950Y462552D03*
X572400Y466192D03*
X576920Y469832D03*
X572379Y473373D03*
X576970Y475932D03*
X572540Y478492D03*
X577000Y481051D03*
X572520Y483532D03*
X572400Y488682D03*
X572380Y493802D03*
X583150Y509262D03*
X598190Y83462D03*
X592265Y77757D03*
X586068Y134531D03*
X585986Y124754D03*
X600071Y138202D03*
X596720Y164717D03*
X589956Y200878D03*
X596576Y195237D03*
X590900Y195562D03*
X589956Y206962D03*
X601230Y216482D03*
X595900Y216612D03*
X591420Y213922D03*
X592936Y298082D03*
X593265Y311693D03*
X593311Y304016D03*
X599661Y421362D03*
X601820Y439362D03*
X599900Y524862D03*
X617585Y97257D03*
X613020Y94162D03*
X603880Y93902D03*
X605090Y137542D03*
X603410Y132682D03*
X614000Y133862D03*
X617500Y129862D03*
X617660Y168965D03*
X613660Y168966D03*
X603981Y158281D03*
X607940Y173930D03*
Y178930D03*
X602000Y195162D03*
X607200Y194062D03*
X611200Y197262D03*
X612531Y212721D03*
X608995Y216257D03*
X604230Y257532D03*
X616790Y283292D03*
X608920D03*
X602795Y477362D03*
X610700Y485320D03*
X603779Y502082D03*
X629684Y77928D03*
X623290Y78482D03*
X629500Y134362D03*
X626699Y129862D03*
X620612Y133862D03*
X633500Y147862D03*
Y141362D03*
X626929Y163506D03*
X624101Y166335D03*
X629430Y200710D03*
X622064Y250202D03*
X621893Y259030D03*
X629870Y296338D03*
X631861Y290182D03*
X628603Y304016D03*
X624460Y465262D03*
Y470362D03*
X624470Y475462D03*
X626680Y525972D03*
X648258Y79502D03*
X643387Y83184D03*
X645230Y116302D03*
X640000Y154345D03*
X639982Y144844D03*
X637055Y159515D03*
X635820Y180570D03*
X641766Y180757D03*
X635820Y185570D03*
Y190570D03*
X634880Y249202D03*
X634820Y260202D03*
X640720Y423062D03*
X639545Y445195D03*
X639428Y480474D03*
X657165Y79131D03*
X658490Y139140D03*
X654390Y152972D03*
X654156Y169197D03*
X654370Y158572D03*
X654470Y163972D03*
X654310Y186192D03*
X654325Y174437D03*
X653210Y199320D03*
Y206320D03*
Y213320D03*
X655620Y410662D03*
Y415662D03*
Y430662D03*
Y425662D03*
Y420662D03*
X655820Y442662D03*
Y437662D03*
Y447662D03*
X655700Y464664D03*
X655820Y472662D03*
X655557Y477064D03*
X655500Y481862D03*
X662000Y1416500D03*
X663720Y1715362D03*
Y1726362D03*
X673987Y87662D03*
X672520Y121560D03*
X678520Y130640D03*
X682140Y393432D03*
X672820Y396522D03*
X676720Y493562D03*
X668647Y1637403D03*
X673593Y1655557D03*
X686210Y91492D03*
X683500Y381200D03*
X693300Y395362D03*
X687500Y399402D03*
X697930Y391282D03*
X695257Y499926D03*
X699174Y519473D03*
X686647Y1636667D03*
X691593Y1653972D03*
X687120Y1665862D03*
Y1676862D03*
X710450Y152512D03*
X702705Y379398D03*
X707220Y399362D03*
X708400Y392000D03*
X700185Y385010D03*
X711187Y493470D03*
X705220Y493362D03*
X714162Y1574333D03*
X713052Y1579683D03*
X713102Y1601307D03*
X714380Y1589960D03*
X712512Y1596338D03*
X711558Y1675700D03*
X719600Y105062D03*
X718053Y165297D03*
X729460Y399052D03*
X723350Y388952D03*
X722187Y493470D03*
X727187D03*
X717187D03*
X723450Y597072D03*
X731960Y1634110D03*
X731040Y1652930D03*
X738186Y398695D03*
X732187Y493470D03*
X738070Y493833D03*
X737600Y500178D03*
X759350Y116180D03*
X763740Y108400D03*
X753600Y143438D03*
X753500Y151312D03*
X764342Y162084D03*
X755900Y170562D03*
X756160Y267322D03*
X755960Y274322D03*
X750020Y410662D03*
X750120Y415712D03*
X750020Y420712D03*
X750080Y430712D03*
X750010Y425712D03*
X750020Y435792D03*
X750220Y447162D03*
X750290Y452162D03*
Y457162D03*
X750220Y472162D03*
Y467162D03*
Y477162D03*
X749880Y482202D03*
X749612Y1583023D03*
X749662Y1590733D03*
X755859Y1697330D03*
X758273Y1718740D03*
X780180Y133460D03*
X780260Y124600D03*
X779100Y142760D03*
X773900Y170064D03*
X774660Y267722D03*
Y282922D03*
Y275322D03*
X771490Y354942D03*
X765000Y354862D03*
X768720Y459862D03*
X769985Y525724D03*
X774152Y1576893D03*
Y1594893D03*
X793879Y194881D03*
X789942Y204724D03*
X793879Y214567D03*
X796800Y266800D03*
X794057Y301569D03*
X793896Y309026D03*
X789140Y380540D03*
X784278Y403212D03*
X786830Y411600D03*
X784730Y432682D03*
X787520Y510512D03*
Y524802D03*
X810810Y135132D03*
X810640Y128262D03*
X810480Y141762D03*
X805690Y188976D03*
Y220472D03*
X798204Y279146D03*
X811600Y378200D03*
X801800Y388800D03*
X799220Y423862D03*
X807530Y502232D03*
X807640Y519957D03*
X801652Y1578393D03*
X801653Y1598793D03*
X801652Y1604293D03*
X814114Y120773D03*
X822530Y125698D03*
X828614D03*
X817501Y194881D03*
Y214567D03*
X821438Y204724D03*
X814800Y264580D03*
X815060Y280072D03*
X813490Y273862D03*
X819500Y418300D03*
X819220Y425425D03*
X815310Y436050D03*
X827100Y471682D03*
Y479200D03*
X815902Y1578643D03*
X815509Y1600536D03*
X831539Y70643D03*
X834114Y135698D03*
X833614Y129198D03*
X839460Y146042D03*
X833320Y145912D03*
X831295Y171632D03*
X845220Y192862D03*
X839220D03*
X834920Y220303D03*
X843510Y228962D03*
X839080Y233252D03*
X838680Y224752D03*
X840063Y285022D03*
X840850Y278948D03*
X836064Y396620D03*
X835564Y389140D03*
X836290Y415562D03*
X836330Y405972D03*
X836260Y410760D03*
X829800Y429300D03*
X844500Y447100D03*
X844570Y469130D03*
X832620Y506082D03*
X832125Y521156D03*
X843652Y1578393D03*
X843653Y1598793D03*
X843652Y1604293D03*
X856629Y70793D03*
X846190Y145262D03*
X856430Y182260D03*
X849320Y196532D03*
X853340Y199932D03*
X855400Y204772D03*
X853842Y225002D03*
X849600Y228152D03*
X859564Y389140D03*
X859621Y395261D03*
X859876Y414276D03*
Y406812D03*
X854820Y437422D03*
X848900Y433400D03*
X851941Y503082D03*
X857902Y1578643D03*
X857509Y1600536D03*
X864967Y60983D03*
X866190Y163822D03*
X866220Y170862D03*
X866451Y175862D03*
X869900Y209562D03*
X868020Y264232D03*
X872820Y430963D03*
X863925Y737697D03*
X889350Y195489D03*
X893700Y201799D03*
X887142Y879195D03*
X892408Y879200D03*
X885652Y1578393D03*
X885653Y1598793D03*
X885652Y1604293D03*
X899500Y201899D03*
X897640Y915099D03*
X899902Y1578643D03*
X899509Y1600536D03*
X916545Y309459D03*
X911494Y321653D03*
X916545Y333847D03*
X923897Y445545D03*
X912288Y472430D03*
X920273Y972460D03*
X925723Y972420D03*
X921868Y999472D03*
X926464Y1001808D03*
X940933Y309459D03*
X928739Y304408D03*
Y338898D03*
X940933Y333847D03*
X938980Y980382D03*
X931083Y972420D03*
X939942Y991629D03*
X932220Y1001862D03*
X928152Y1579393D03*
Y1589893D03*
Y1594893D03*
X933979Y1661327D03*
X942100Y1671100D03*
X955430Y180139D03*
X945984Y321653D03*
X956920Y490462D03*
X950820Y489762D03*
X974120Y194129D03*
X967239Y320073D03*
X975720Y386862D03*
X975330Y396132D03*
X970788Y501230D03*
X964347Y501262D03*
X977479Y171040D03*
X977070Y211709D03*
X988500Y224653D03*
X991934Y368443D03*
X979559Y399362D03*
X983970Y392562D03*
X997460Y226019D03*
X1000009Y368081D03*
X1003293Y371455D03*
X997394Y415578D03*
X1001721Y421758D03*
X996154Y422700D03*
X1007249Y426399D03*
X1003235Y430097D03*
X1003220Y512862D03*
X1010388Y189009D03*
X1010976Y195562D03*
X1017163Y367963D03*
X1019300Y371830D03*
X1023762Y370425D03*
X1010736Y371866D03*
X1013168Y368145D03*
X1023330Y413692D03*
X1016520Y414362D03*
X1036278Y303993D03*
X1029239Y371893D03*
X1037334Y383729D03*
X1039952Y398756D03*
X1036659Y388000D03*
Y393000D03*
X1028330Y413692D03*
X1038330D03*
X1033330D03*
X1039065Y418999D03*
X1031065D03*
X1026065D03*
X1045847Y194881D03*
X1041910Y204724D03*
X1045847Y214567D03*
X1042334Y383729D03*
X1044952Y398756D03*
X1042687Y404063D03*
X1043330Y413692D03*
X1053410Y503402D03*
X1045720Y591672D03*
X1069469Y194881D03*
X1057658Y188976D03*
X1069469Y214567D03*
X1057658Y220472D03*
X1063330Y382062D03*
X1061470Y585862D03*
X1071957Y1659450D03*
X1075430Y68192D03*
X1079240Y72682D03*
X1087316Y78461D03*
X1073406Y204724D03*
X1077582Y390962D03*
X1078102Y1586860D03*
X1086457Y1644450D03*
X1084457Y1663950D03*
X1096272Y60182D03*
X1105316Y72266D03*
X1105423Y77559D03*
X1101500Y379235D03*
Y374235D03*
Y369235D03*
X1104902Y1586660D03*
X1105557Y1649250D03*
X1105457Y1664450D03*
X1096680Y1667260D03*
X1111970Y1607740D03*
Y1613140D03*
X1130163Y59940D03*
X1124858Y197309D03*
X1133720Y642862D03*
X1131715Y1532913D03*
X1131220Y1599140D03*
X1138530Y1612150D03*
X1126940Y1612030D03*
X1138530Y1606750D03*
X1126940Y1606230D03*
X1129620Y1620851D03*
X1147722Y206345D03*
X1144620Y221652D03*
X1145500Y374235D03*
X1150140Y610362D03*
X1142187Y1582738D03*
X1152187D03*
X1144899Y1630878D03*
X1170665Y71388D03*
X1155823Y192102D03*
X1157445Y216982D03*
X1159460Y366025D03*
X1158300Y585862D03*
X1170740Y602132D03*
X1161595Y1574738D03*
Y1582738D03*
X1165100Y1633450D03*
X1163970Y1620600D03*
X1164000Y1625720D03*
X1169825Y1678062D03*
X1158825D03*
X1177310Y65769D03*
X1177234Y59978D03*
X1174545Y106767D03*
X1184510Y188962D03*
X1183460Y205342D03*
X1177570Y602052D03*
X1175217Y595762D03*
X1175215Y1532913D03*
X1171595Y1582738D03*
X1174595Y1590738D03*
X1186790Y1613820D03*
X1180825Y1678062D03*
X1203700Y89400D03*
X1203050Y100750D03*
X1200590Y231532D03*
X1188810Y296088D03*
X1198436Y1546492D03*
Y1556192D03*
X1187720Y1558682D03*
X1202200Y1661580D03*
X1191395Y1678372D03*
X1203040Y1671240D03*
X1191235Y1723852D03*
X1202005Y1723897D03*
X1215070Y61580D03*
X1218220Y199862D03*
X1212805Y1724162D03*
X1225700Y108962D03*
X1227074Y119962D03*
X1236300Y168362D03*
X1229720Y197302D03*
X1233282Y201875D03*
X1221330Y216000D03*
X1231720Y217862D03*
Y209862D03*
X1232720Y377862D03*
X1243653Y59957D03*
X1240700Y89700D03*
X1251107Y98785D03*
X1238148Y138705D03*
X1245784Y155522D03*
X1239664Y164272D03*
X1249166Y176737D03*
X1248064Y185012D03*
X1242383Y177862D03*
X1237910Y173375D03*
X1242378Y222323D03*
X1261969Y169722D03*
X1255848Y178605D03*
X1262332Y192601D03*
X1262300Y207572D03*
X1255954Y212694D03*
X1256615Y205266D03*
X1258883Y280558D03*
X1264146Y277191D03*
Y282191D03*
X1266227Y764045D03*
X1284648Y265431D03*
X1283346Y281903D03*
X1270646Y277191D03*
Y282191D03*
X1280675Y277013D03*
X1284794Y272284D03*
X1279987Y287375D03*
X1297710Y68562D03*
X1297785Y63033D03*
X1298270Y76142D03*
X1296253Y100049D03*
X1286750Y101712D03*
X1300964Y91012D03*
X1291257Y105595D03*
X1287793Y95682D03*
X1296929Y116962D03*
X1288693Y283769D03*
X1308440Y86532D03*
X1305422Y100454D03*
X1312792Y113732D03*
X1313405Y108420D03*
X1302060Y113852D03*
X1311241Y125232D03*
X1304714Y265246D03*
X1304930Y278552D03*
X1305090Y284722D03*
X1305164Y272652D03*
X1329891Y87412D03*
X1317901Y95732D03*
X1318146Y110924D03*
X1323546Y113188D03*
X1325641Y118859D03*
X1321810Y125106D03*
X1331593Y125262D03*
X1347082Y120593D03*
X1337731Y121164D03*
X1381940Y104063D03*
X1368124Y114039D03*
X1377470Y1391032D03*
X1378660Y1428340D03*
X1388340Y104132D03*
X1394550Y104022D03*
X1391038Y178871D03*
X1395773Y177016D03*
X1396781Y182349D03*
X1392025Y184062D03*
X1391443Y223513D03*
X1394493Y230962D03*
X1398984Y234392D03*
X1390474Y1385142D03*
X1393957Y1395078D03*
X1387262Y1405157D03*
X1395907Y1430227D03*
X1398569Y1437860D03*
X1411875Y121234D03*
X1411837Y126967D03*
X1411685Y133004D03*
X1401640Y158194D03*
X1407290Y160650D03*
X1410833Y249912D03*
X1412194Y242692D03*
X1411094Y255322D03*
X1406461Y1383862D03*
X1408384Y1391779D03*
X1410477Y1440117D03*
X1410038Y1434670D03*
X1409483Y1593883D03*
X1403250Y1608192D03*
X1410500Y1633862D03*
X1414400Y1627200D03*
X1418034Y244822D03*
X1416694Y252432D03*
X1421480Y1415731D03*
X1419991Y1423404D03*
X1416272Y1433949D03*
X1421435Y1430415D03*
X1425850Y1516362D03*
X1426090Y1532182D03*
X1426240Y1543402D03*
X1415368Y1569131D03*
X1422680Y1593382D03*
X1428700Y1600600D03*
X1415730Y1611422D03*
X1431600Y1630300D03*
Y1625300D03*
X1428500Y1642362D03*
X1435013Y153882D03*
X1435220Y141942D03*
X1435013Y147636D03*
X1435060Y159212D03*
X1447340Y157402D03*
X1447200Y286400D03*
X1436270Y312592D03*
X1437666Y1421828D03*
X1447617Y1416417D03*
X1445530Y1524094D03*
X1445970Y1539914D03*
X1446210Y1551134D03*
X1447408Y1569037D03*
Y1564037D03*
X1442499Y1585323D03*
X1434220Y1595900D03*
X1446380Y1660462D03*
X1450270Y143022D03*
X1450720Y153362D03*
X1448820Y148092D03*
X1450720Y161862D03*
X1449740Y166912D03*
X1450720Y173862D03*
X1449700Y299067D03*
X1453900Y286400D03*
X1455692Y731401D03*
X1462194Y1399885D03*
X1462421Y1609800D03*
X1458890Y1648942D03*
X1452757Y1649112D03*
X1466356Y64062D03*
X1466383Y220108D03*
Y225330D03*
X1476070Y1423740D03*
X1464880Y1649112D03*
X1511200Y131862D03*
X1504360Y244592D03*
X1512244Y311522D03*
X1509420Y316192D03*
X1525940Y108192D03*
X1526930Y203740D03*
X1524853Y235376D03*
X1528860Y239792D03*
X1524840Y244842D03*
X1529150Y251402D03*
X1524810Y254652D03*
X1533630Y57052D03*
X1530910Y64900D03*
X1534367Y75003D03*
X1531429Y77832D03*
X1532500Y130362D03*
X1542230Y292732D03*
X1541568Y594020D03*
X1535007Y608685D03*
X1543895Y629286D03*
X1545610Y116180D03*
X1546813Y132712D03*
X1548938Y593832D03*
X1549590Y629295D03*
X1577365Y1417315D03*
X1576407Y1438525D03*
X1588550Y185702D03*
X1588720Y193962D03*
X1582340Y200611D03*
X1581830Y217482D03*
X1588100Y205442D03*
X1591830Y232482D03*
X1586830D03*
X1581830D03*
Y227482D03*
Y222482D03*
X1580240Y242232D03*
X1581810Y247902D03*
X1586647Y1433669D03*
X1595730Y205662D03*
X1604200Y234642D03*
X1596830Y232482D03*
Y237482D03*
X1613466Y114472D03*
X1634339Y121224D03*
Y116224D03*
Y131224D03*
X1654900Y195935D03*
X1654610Y405002D03*
X1646010Y423702D03*
X1653610D03*
X1672596Y220541D03*
X1664866Y225162D03*
X1661610Y405202D03*
X1661210Y423702D03*
X1674630Y521222D03*
X1672401Y556845D03*
X1668975Y559364D03*
X1669563Y552923D03*
X1678994Y217231D03*
X1680020Y420132D03*
X1685935Y504815D03*
X1681910Y559380D03*
X1675706Y559419D03*
X1676453Y1561557D03*
X1706100Y57052D03*
X1705798Y154052D03*
X1704625Y165909D03*
X1704600Y171656D03*
X1705920Y159812D03*
X1698592Y561310D03*
X1702130Y1385722D03*
X1705960Y1377442D03*
X1694248Y1500862D03*
Y1520362D03*
Y1541362D03*
X1694453Y1560821D03*
X1721240Y57422D03*
X1716230Y57202D03*
X1711140D03*
X1716910Y120432D03*
X1716600Y113622D03*
X1717100Y377962D03*
X1709590Y374282D03*
Y369282D03*
X1709680Y545432D03*
X1717880Y687680D03*
X1726600Y57232D03*
X1728310Y88442D03*
X1731470Y358022D03*
X1738480Y358082D03*
X1735870Y387082D03*
X1728860Y387032D03*
X1731150Y427410D03*
X1734420Y475672D03*
X1731120Y495912D03*
X1735010Y500178D03*
X1741886Y123728D03*
X1751222Y291276D03*
X1745910Y363112D03*
X1745490Y357002D03*
X1746120Y368132D03*
X1745910Y373522D03*
X1742770Y387112D03*
X1742947Y413323D03*
X1743170Y400460D03*
X1766490Y169122D03*
X1759220Y382952D03*
Y377452D03*
X1761720Y438342D03*
X1777598Y308286D03*
X1780667Y303994D03*
X1783608Y464140D03*
X1779740Y459942D03*
X1784010Y453904D03*
X1778430Y466699D03*
X1795346Y372732D03*
X1800030Y390411D03*
X1800980Y433132D03*
X1795060Y433182D03*
X1795161Y472622D03*
X1797720Y477852D03*
X1819450Y145070D03*
X1808110Y161427D03*
X1818274Y362293D03*
Y385293D03*
X1811404Y403225D03*
X1806460Y433002D03*
X1818700Y433182D03*
X1820790Y439462D03*
X1820650Y446226D03*
X1821580Y464140D03*
X1820790Y451344D03*
X1820840Y456463D03*
X1825210Y153961D03*
X1826080Y163660D03*
X1836657Y177243D03*
X1830080Y188482D03*
X1826308Y374586D03*
X1824404Y403225D03*
X1823904Y427432D03*
X1826525Y439697D03*
X1826340Y445972D03*
X1826200Y456482D03*
X1827430Y461581D03*
X1826520Y451292D03*
X1843830Y159800D03*
X1889250Y1843218D03*
X1906004Y1851586D03*
X1913834Y1850536D03*
X1924795Y1842075D03*
X1924635Y1852355D03*
X1937505Y1842525D03*
X1937655Y1853285D03*
X1958420Y1842549D03*
X1964170Y1842429D03*
X1955295Y1853985D03*
X1962935Y1853905D03*
X1978235Y1848699D03*
G54D265*
X1030333Y291567D03*
X1288040Y1365989D03*
X1320136Y1343344D03*
X1512904Y1365814D03*
G54D256*
X991369Y379186D03*
Y381154D03*
Y383123D03*
Y385091D03*
Y387060D03*
Y389028D03*
Y390997D03*
Y392965D03*
Y394934D03*
Y396902D03*
Y398871D03*
Y400839D03*
Y402808D03*
Y404776D03*
X1021881Y379186D03*
Y394934D03*
Y392965D03*
Y390997D03*
Y389028D03*
Y387060D03*
Y385091D03*
Y383123D03*
Y381154D03*
Y404776D03*
Y402808D03*
Y400839D03*
Y398871D03*
Y396902D03*
G54D347*
G01X330224Y962754D02*
X331531D01*
X331849Y962436D01*
X335928D01*
G01X329957Y1022319D02*
X330871D01*
X331570Y1021620D01*
X334898D01*
X336514Y1020004D01*
X338211D01*
G01X335928Y866307D02*
X334900Y865285D01*
X334118D01*
X332204Y863371D01*
G01X337779Y863103D02*
X334574Y862333D01*
X333908Y861667D01*
G01X334079Y869511D02*
X333726Y869864D01*
X333032D01*
X332574Y869406D01*
X332411Y869011D01*
X331814Y868413D01*
Y867912D01*
X331266Y867364D01*
X330763D01*
X328937Y865538D01*
Y865360D01*
X328876Y865299D01*
G01X335928Y872716D02*
X331343Y872720D01*
X330549Y871926D01*
G01X337779Y869511D02*
X337625Y869449D01*
X334634Y870720D01*
X334430Y870839D01*
X333189D01*
X332777Y870669D01*
X331938Y869830D01*
X331775Y869435D01*
X331283Y868943D01*
X331282D01*
X328407Y866068D01*
X328229D01*
X328168Y866007D01*
G01X335928Y904759D02*
X335767Y904920D01*
X331734D01*
X330052Y904223D01*
X328652Y902823D01*
G01X337779Y901555D02*
X335657Y900723D01*
X334466Y900134D01*
X333368Y899565D01*
X331523D01*
G01X337779Y875920D02*
X336281Y875519D01*
X335820Y875253D01*
X335246Y874921D01*
X334404Y874627D01*
X334132Y874573D01*
X333460Y874595D01*
X331712Y875151D01*
G03X331274Y875219I-440J-1386D01*
G01X330446D01*
X328851Y873624D01*
G01X328823Y911805D02*
X331132D01*
X331770Y911167D01*
X335928D01*
G01X334079Y907963D02*
Y908272D01*
X333724Y908627D01*
X332192D01*
X331849Y908284D01*
X330654D01*
X330528Y908158D01*
X330441D01*
G01X337779Y907963D02*
X335012Y909110D01*
X334562Y909370D01*
X333730Y909376D01*
X331881D01*
X331538Y909033D01*
X330653D01*
X330528Y909158D01*
X330441D01*
G01X337779Y920780D02*
X335614Y919966D01*
X334811Y919503D01*
G02X334074Y919305I-738J1277D01*
G01X333479Y919249D01*
X331449D01*
X330787Y919419D01*
X330524D01*
G01X337779Y914372D02*
X336039Y913812D01*
X334816Y913095D01*
G02X334079Y912898I-736J1277D01*
G01X332670D01*
X331164Y914404D01*
X328824D01*
G01X335928Y923985D02*
X335793Y924120D01*
X331169D01*
X330180Y923131D01*
X328824D01*
G01X334079Y927189D02*
Y927447D01*
X333661Y927865D01*
X331482D01*
X330754Y927137D01*
X328836D01*
X328711Y927012D01*
X328624D01*
G01X337779Y927189D02*
X336355Y927571D01*
X334788Y928479D01*
G03X334286Y928614I-502J-864D01*
G01X331171D01*
X330443Y927886D01*
X328837D01*
X328711Y928012D01*
X328624D01*
G01X337779Y933598D02*
G03X336256Y933190I-2J-3041D01*
G01X334754Y932322D01*
G02X333590Y932019I-1164J2083D01*
G01X330919D01*
X329929Y933009D01*
X328824D01*
G01Y930609D02*
X329729D01*
X329945Y930393D01*
X335928D01*
G01Y943210D02*
X335786Y943352D01*
X331074D01*
X329449Y941727D01*
G01X337779Y940006D02*
X339002D01*
X339235Y939773D01*
G02X338551Y938749I-1457J232D01*
G02X337779Y938531I-772J1258D01*
G02X337042Y938728I-1J1475D01*
G03X337021Y938739I-132J-226D01*
G03X334878Y938763I-1093J-1937D01*
G03X334354Y938376I1046J-1964D01*
G01X333792Y937813D01*
X331524D01*
G01X335928Y949619D02*
X332199Y949655D01*
X331467D01*
X331096Y949284D01*
X327862D01*
X327259Y949887D01*
G01X334079Y946414D02*
G03X333722Y946562I-357J-357D01*
G01X331877D01*
X331492Y946485D01*
X330400Y946034D01*
X329210Y946035D01*
X328148Y945595D01*
X326736D01*
X326611Y945470D01*
X326524D01*
G01Y946470D02*
X326611D01*
X326737Y946344D01*
X327996D01*
X329061Y946785D01*
X330252Y946784D01*
X331274Y947206D01*
X331803Y947311D01*
X332658D01*
X333006Y947659D01*
G02X333337Y947796I331J-331D01*
G01X333359Y947802D01*
G02X333930Y947835I365J-1361D01*
G01X334409Y947764D01*
G02X334942Y947614I-320J-2158D01*
G01X334976Y947599D01*
G02X335629Y947159I-806J-1901D01*
G03X337428Y946414I1799J1799D01*
G01X337779D01*
G01Y952823D02*
G03X336360Y952441I1J-2829D01*
G01X334986Y951644D01*
G02X334437Y951497I-549J951D01*
G01X329047D01*
X328808Y951736D01*
G01X337779Y959232D02*
X336766Y960245D01*
X335138D01*
X334216Y960627D01*
X332370D01*
X331448Y960245D01*
X330224D01*
G01X335928Y968845D02*
X334272Y969174D01*
X330224D01*
G01X334079Y965640D02*
X333109Y966610D01*
X331224D01*
G01X343328Y962436D02*
G02X341930Y962810I-1J2797D01*
G01X340366Y963713D01*
G03X338892I-737J-1277D01*
G01X338851Y963689D01*
G02X336665Y963713I-1072J1951D01*
G03X335191I-737J-1277D01*
G02X334899Y963561I-1843J3184D01*
G01X334785Y963447D01*
X333061D01*
X331664Y964026D01*
X331224D01*
G01X341479Y978457D02*
G03X340081Y978083I0J-2799D01*
G01X338515Y977180D01*
G02X336800Y977406I-710J1230D01*
G01X336317Y977889D01*
Y979217D01*
X333955Y981579D01*
X330325D01*
G01X337779Y972049D02*
X334931Y973259D01*
X334383Y973578D01*
X333161Y974800D01*
X331350D01*
X330461Y975689D01*
G01X335928Y981662D02*
X336539Y980603D01*
X336858Y980518D01*
G03X337403Y981662I-930J1145D01*
G01X337404Y981663D01*
G03X336588Y983069I-1621J-1D01*
G01X336332Y983198D01*
G03X335414Y983415I-919J-1838D01*
G01X334447D01*
G02X333469Y983820I1J1385D01*
G01X332524Y984765D01*
X331005D01*
X330735Y984495D01*
X330625D01*
G01X337779Y978457D02*
X337168Y979516D01*
X337267Y979882D01*
G03X337333Y979934I-1345J1775D01*
G03X338154Y981606I-1405J1727D01*
G01Y981662D01*
X338153D01*
G03X336941Y983731I-2371J1D01*
G01X336667Y983868D01*
G03X335413Y984164I-1254J-2508D01*
G01X334448D01*
G02X333999Y984350I0J635D01*
G01X332835Y985514D01*
X331006D01*
X330735Y985785D01*
X330625D01*
G01X338211Y1000778D02*
X336219Y999819D01*
X333317D01*
X328305Y1004831D01*
G01X341912Y1000778D02*
X340253Y999119D01*
X337419D01*
X336319Y998619D01*
X332819D01*
X327456Y1003982D01*
G01X332225Y1010891D02*
X334739D01*
X335239Y1010391D01*
X336361D01*
G01X338211Y1007187D02*
G03X336818Y1006814I1J-2790D01*
G01X334456Y1005453D01*
X334060Y1005057D01*
X332928Y1004588D01*
X331944D01*
X329853Y1006679D01*
G01X336361Y1016800D02*
X335260Y1015699D01*
X329323D01*
X329171Y1015851D01*
G01X341912Y1020004D02*
X341268Y1019360D01*
X340030D01*
X338948Y1018727D01*
G02X337474I-737J1277D01*
G03X335290Y1018751I-1113J-1927D01*
G01X334839Y1018487D01*
X333691Y1017339D01*
X331079D01*
X329796Y1018622D01*
G01X325626Y1029798D02*
X327084D01*
X327521Y1030235D01*
X328317D01*
X328754Y1029798D01*
X329533D01*
X330162Y1030427D01*
X332034D01*
X332844Y1029617D01*
X336361D01*
G01X338211Y1026413D02*
Y1026412D01*
X336800Y1026790D01*
X334685Y1028013D01*
X331268D01*
X330651Y1027396D01*
X328325D01*
G01X325144Y1038072D02*
X325387Y1037829D01*
X330381D01*
X333702Y1036026D01*
X336361D01*
G01X334512Y1032821D02*
X333819Y1033514D01*
X332132Y1034213D01*
X331372D01*
X331022Y1033863D01*
X330233D01*
X329883Y1034213D01*
X328727D01*
X328377Y1033863D01*
X327588D01*
X327238Y1034213D01*
X325938D01*
X325813Y1034088D01*
X325726D01*
G01X338211Y1032821D02*
X335359Y1034003D01*
X334346Y1034205D01*
X334111D01*
X332282Y1034962D01*
X325939D01*
X325813Y1035088D01*
X325726D01*
G01X338211Y1039230D02*
X335906Y1038338D01*
X335231Y1037948D01*
G02X334473Y1037744I-759J1311D01*
G02X333732Y1037902I-2J1809D01*
G01X333092Y1038246D01*
X331159Y1040179D01*
X326434D01*
X325513Y1041100D01*
G01X328312Y1052638D02*
X329866Y1051084D01*
X330243D01*
X330983Y1050344D01*
Y1049989D01*
X332056Y1048916D01*
X332550D01*
X332827Y1049193D01*
X333691D01*
X334172Y1048712D01*
X334818D01*
X334948Y1048842D01*
X336361D01*
G01X338211Y1045639D02*
X337360Y1044788D01*
X336251D01*
X335839Y1045200D01*
Y1046575D01*
X335249Y1046915D01*
G03X334487Y1047124I-782J-1357D01*
G01X333122D01*
X331643Y1045645D01*
X331231Y1045474D01*
X330326D01*
G01X329709Y1061435D02*
X335893Y1055251D01*
X336361D01*
G01X334512Y1052047D02*
X333900Y1053101D01*
X333683Y1053318D01*
Y1053320D01*
X333274Y1053729D01*
X332723D01*
X332015Y1054437D01*
Y1054988D01*
X331390Y1055613D01*
X330839D01*
X330131Y1056321D01*
Y1056872D01*
X329994Y1057009D01*
X328902Y1057462D01*
X326718Y1059647D01*
X326542D01*
X326481Y1059708D01*
G01X338211Y1052047D02*
X336365Y1052559D01*
X334213Y1053850D01*
X330419Y1057645D01*
X329327Y1058098D01*
X327250Y1060175D01*
Y1060355D01*
X327189Y1060416D01*
G01X338211Y1064864D02*
X337178Y1063831D01*
X336163D01*
X334330Y1065664D01*
X334071D01*
X333205Y1066530D01*
X333204D01*
G01X338211Y1058455D02*
X336617Y1060049D01*
X334491D01*
X331407Y1063133D01*
G01X327954Y1075180D02*
X328020Y1075115D01*
X328040Y1075096D01*
X333704Y1069432D01*
X334389D01*
X334703Y1069118D01*
Y1068427D01*
X335062Y1068068D01*
X336361D01*
G01Y1074477D02*
X335692Y1073808D01*
X334987D01*
X334003Y1074792D01*
X333355D01*
X332377Y1075197D01*
X331734Y1075841D01*
X330130Y1078240D01*
X329315Y1079233D01*
X328760Y1079788D01*
X328584D01*
X328523Y1079849D01*
G01X338211Y1071273D02*
X337886Y1072058D01*
Y1074008D01*
G03X337307Y1075449I-2078J2D01*
G03X336463Y1075807I-844J-815D01*
G01X335187D01*
X334560Y1075548D01*
X334545Y1075541D01*
X333505D01*
X333153Y1075687D01*
X332802Y1075832D01*
X332317Y1076319D01*
X330733Y1078687D01*
X329871Y1079737D01*
X329292Y1080316D01*
Y1080496D01*
X329231Y1080557D01*
G01X336361Y1080885D02*
X334864Y1081872D01*
X333055Y1083681D01*
G01X341912Y1077681D02*
G03X340653Y1078535I-2859J-2859D01*
G01X339409Y1079071D01*
G03X337474Y1078958I-855J-1985D01*
G02X336925Y1078811I-549J951D01*
G01X335441D01*
X334731Y1079105D01*
X332833Y1081003D01*
X331984Y1081355D01*
X331357Y1081982D01*
G01X329099Y1096824D02*
X330454Y1095469D01*
X330564D01*
X332676Y1093357D01*
Y1092798D01*
X334976Y1090498D01*
X338211D01*
G01X340061Y1087294D02*
X340000Y1087355D01*
G03X338207Y1088208I-7213J-12851D01*
G03X337869Y1088298I-571J-1466D01*
G02X337239Y1088495I342J2199D01*
G03X336268Y1088719I-973J-2001D01*
G01X334966D01*
G02X334570Y1088808I-4J908D01*
G02X334485Y1088869I137J281D01*
G01X331146Y1092208D01*
Y1092739D01*
X330043Y1093842D01*
X328604D01*
X327360Y1095086D01*
G01X336361Y1100111D02*
X335795Y1100677D01*
Y1101427D01*
G01X336361Y1093703D02*
X337585D01*
X337817Y1093935D01*
G03X337179Y1094930I-1456J-232D01*
G03X336844Y1095031I-334J-501D01*
G01X334320D01*
X333529Y1095822D01*
X333114Y1096830D01*
Y1097893D01*
X332750Y1098767D01*
X331746Y1099771D01*
X331568D01*
X331507Y1099832D01*
G01X332215Y1100540D02*
X332276Y1100479D01*
Y1100301D01*
X333385Y1099192D01*
X333863Y1098043D01*
Y1096979D01*
X334165Y1096246D01*
X334631Y1095780D01*
X336843D01*
G02X337595Y1095553I2J-1351D01*
G02X338559Y1094055I-1233J-1853D01*
G02X338571Y1093969I-2198J-350D01*
G01X338837Y1093703D01*
X340061D01*
G01X341479Y863103D02*
X340031Y862716D01*
X337947Y861512D01*
G02X337412Y861368I-536J926D01*
G01X335307D01*
X334757Y860818D01*
G01X343328Y866307D02*
X344196Y866303D01*
X344467Y866029D01*
X344460Y865066D01*
X343943Y864549D01*
X336158D01*
X335454Y863845D01*
X334384D01*
X333154Y862615D01*
X333146D01*
X333053Y862522D01*
G01X345179Y869511D02*
G02X343717Y869908I0J2890D01*
G01X342216Y870788D01*
G03X340742I-737J-1277D01*
G03X340023Y869749I738J-1279D01*
G01X339997Y869399D01*
X339698Y868816D01*
X338555Y868244D01*
G02X338218Y868164I-338J672D01*
G01X337164D01*
G02X336826Y868237I0J817D01*
G01X336427Y868419D01*
G03X335755Y868548I-599J-1304D01*
G03X335010Y868339I116J-1845D01*
G01X334978Y868322D01*
X334968Y868317D01*
X334961Y868313D01*
X334958Y868311D01*
X334949Y868307D01*
X334946Y868305D01*
X334945D01*
X334937Y868301D01*
X334927Y868295D01*
X334849Y868252D01*
X334838Y868246D01*
G03X334355Y867880I1090J-1940D01*
G01X334058Y867583D01*
X333330Y867584D01*
X330810Y865064D01*
X330632D01*
X330571Y865003D01*
G01X331279Y864295D02*
X331340Y864356D01*
Y864534D01*
X333640Y866834D01*
X334368Y866833D01*
X334885Y867350D01*
G02X335191Y867585I1044J-1043D01*
G01X335201Y867590D01*
X335204Y867592D01*
X335294Y867640D01*
X335297Y867642D01*
X335302Y867644D01*
X335320Y867654D01*
X335323Y867655D01*
X335326Y867657D01*
Y867658D01*
X335329Y867660D01*
X335361Y867677D01*
G02X335771Y867797I508J-975D01*
G02X336116Y867737I59J-683D01*
G01X336540Y867544D01*
G03X337164Y867415I622J1437D01*
G01X338219D01*
G03X338891Y867574I0J1501D01*
G01X340253Y868256D01*
X340719Y869164D01*
X341066Y869511D01*
X341479D01*
G01Y875920D02*
X340778Y875225D01*
X339345D01*
X338482Y874362D01*
Y873859D01*
X338128Y873505D01*
X337626D01*
X337143Y873988D01*
Y874171D01*
X336782Y874532D01*
X336167D01*
G03X335992Y874485I0J-349D01*
G01X335245Y874054D01*
X334105Y873788D01*
X333119Y873733D01*
X331333Y873991D01*
G03X330451Y873526I311J-1659D01*
G01X329700Y872775D01*
G01X343328Y872716D02*
X343452Y872592D01*
X344325D01*
X345069Y871848D01*
Y871288D01*
X344703Y870922D01*
X343916D01*
X342278Y871602D01*
X341816Y872064D01*
X341397D01*
X340322Y871442D01*
G02X339819Y871263I-738J1277D01*
G01X339561Y871005D01*
X338673D01*
X338239Y871439D01*
X336665D01*
G02X334930I-868J1503D01*
G01X334427Y871729D01*
G03X334093Y871819I-335J-578D01*
G01X332140D01*
X331398Y871077D01*
G01X343328Y904759D02*
X340554Y903157D01*
G02X338704I-925J1602D01*
G03X336854I-925J-1602D01*
G02X335618Y902934I-927J1602D01*
G01X335532Y902979D01*
X334795Y903716D01*
G03X334379Y903887I-416J-420D01*
G01X334103D01*
X333860Y904130D01*
X331877D01*
X330860Y903709D01*
X330170Y903019D01*
Y902642D01*
X329502Y901974D01*
G01X341479Y901555D02*
G03X339359Y900469I624J-3830D01*
G01X338759Y899887D01*
G02X337855Y899693I-607J624D01*
G01X337069Y899979D01*
G03X336050Y899985I-518J-1424D01*
G01X335719Y899869D01*
X335096Y899541D01*
X333828Y898325D01*
X331523D01*
G01X343328Y911167D02*
X343736Y910759D01*
X345227D01*
X345416Y910570D01*
Y909806D01*
X345071Y909461D01*
X344172D01*
G02X342589Y909890I0J3135D01*
G01X342548Y909914D01*
G03X340364Y909890I-1071J-1951D01*
G02X339204Y909579I-1160J2009D01*
G01X338659D01*
X337972Y910266D01*
X337476D01*
X336789Y909579D01*
X336367D01*
G02X335215Y909877I0J2377D01*
G01X334414Y910321D01*
X331370D01*
X331087Y910604D01*
X328823D01*
G01X345179Y907963D02*
G02X343717Y908360I0J2890D01*
G01X342216Y909240D01*
G03X340742I-737J-1277D01*
G01X340741Y909239D01*
G03X340023Y908201I736J-1276D01*
G01X340000Y907891D01*
X340001D01*
X339996Y907835D01*
X339714Y907281D01*
X338513Y906681D01*
X338510Y906680D01*
X338503Y906676D01*
X338490Y906669D01*
G02X337041Y906685I-710J1294D01*
G01X337042Y906686D01*
G03X334874Y906720I-1114J-1927D01*
G01X334816Y906686D01*
G02X334173Y906490I-740J1276D01*
G02X334079Y906487I-94J1472D01*
G01X333070D01*
X332942Y906615D01*
X330654D01*
X330528Y906741D01*
X330441D01*
G01Y905741D02*
X330528D01*
X330653Y905866D01*
X332631D01*
X332759Y905738D01*
X334080D01*
G03X334223Y905742I9J2225D01*
G03X335191Y906036I-146J2220D01*
G02X336665I737J-1277D01*
G03X338846Y906009I1115J1927D01*
G01X338848Y906011D01*
X340269Y906721D01*
X340734Y907631D01*
X341066Y907963D01*
X341479D01*
G01X343328Y923985D02*
G02X343316Y923976I-40J41D01*
G01X340554Y922382D01*
G02X338704I-925J1603D01*
G03X336854I-925J-1602D01*
G02X335057Y922351I-926J1603D01*
G01X334049Y923359D01*
X331583D01*
X330155Y921931D01*
X328824D01*
G01X341479Y920780D02*
G03X339781Y920079I-6J-2393D01*
G01X338746Y919044D01*
G02X337144I-801J801D01*
G01X336993Y919195D01*
G03X336742Y919299I-251J-251D01*
G01X336673D01*
G03X335368Y918956I-1J-2652D01*
G01X335186Y918853D01*
G02X334380Y918576I-1113J1927D01*
G01X333299Y918436D01*
X332572D01*
X331955Y917819D01*
X330924D01*
G01X341479Y914372D02*
X340472Y913365D01*
X339993D01*
X339744Y913614D01*
X339038D01*
X338462Y913038D01*
Y912343D01*
X338042Y911923D01*
X337450D01*
X336728Y912645D01*
X335944D01*
G03X335191Y912444I0J-1510D01*
G03X334885Y912210I735J-1278D01*
G01X334606Y911931D01*
X332470D01*
X331372Y913029D01*
X328823D01*
G01X343328Y930393D02*
X343939Y929334D01*
X343823Y928906D01*
G02X343308Y928695I-338J91D01*
G01X342593Y929114D01*
G03X342581Y929121I-1127J-1918D01*
G02X342576Y929124I756J1266D01*
G03X342552Y929138I-1133J-1914D01*
G01X342548Y929141D01*
G03X340366Y929116I-1069J-1952D01*
G01X339807Y928793D01*
X336704D01*
X336688Y928809D01*
X336159D01*
G02X335334Y929031I1J1648D01*
G01X335186Y929116D01*
G03X334640Y929363I-1506J-2603D01*
G03X334499Y929400I-345J-1029D01*
G03X334402Y929409I-96J-508D01*
G01X328824D01*
G01X345179Y927189D02*
G02X343717Y927586I0J2890D01*
G01X342216Y928466D01*
G03X340742I-737J-1277D01*
G03X340023Y927427I738J-1279D01*
G01X340000Y927117D01*
X340001D01*
X339996Y927061D01*
X339714Y926507D01*
X338513Y925907D01*
X338510Y925906D01*
X338503Y925902D01*
X338490Y925895D01*
G02X337041Y925911I-710J1294D01*
G01X337042Y925912D01*
G03X336958Y925958I-1111J-1929D01*
G03X334874Y925946I-1031J-1973D01*
G01X334816Y925912D01*
G02X334173Y925716I-740J1276D01*
G02X334080Y925713I-94J1472D01*
G01X330603D01*
X330252Y925362D01*
X328837D01*
X328711Y925488D01*
X328624D01*
G01Y924488D02*
X328711D01*
X328836Y924613D01*
X330563D01*
X330914Y924964D01*
X334081D01*
G03X334222Y924968I7J2225D01*
G03X335194Y925264I-145J2220D01*
G01X335240Y925292D01*
G02X336611Y925294I687J-1307D01*
G01X336666Y925262D01*
G03X338850Y925237I1114J1927D01*
G01X340270Y925947D01*
X340664Y926720D01*
X340734Y926857D01*
X341066Y927189D01*
X341479D01*
G01Y933598D02*
X338704Y931996D01*
G02X336854I-925J1602D01*
G01X336318D01*
G03X335146Y931682I0J-2345D01*
G02X333418Y931219I-1728J2994D01*
G01X330520D01*
X329930Y931809D01*
X328824D01*
G01X343328Y943210D02*
X340554Y941608D01*
G02X338704I-925J1602D01*
G03X336854I-925J-1602D01*
G02X334536Y941913I-961J1661D01*
G01X333846Y942603D01*
X331481D01*
X331011Y942133D01*
X330623Y941197D01*
X330301Y940875D01*
G01X331524Y936612D02*
X333651D01*
X334884Y937845D01*
G02X335191Y938079I1040J-1047D01*
G02X336665I737J-1277D01*
G03X338851Y938055I1114J1927D01*
G01X338892Y938079D01*
G03X339989Y939739I-1112J1927D01*
G01X340256Y940006D01*
X341479D01*
G01X328040Y942490D02*
X328101Y942551D01*
Y942727D01*
X328754Y943381D01*
X329372D01*
X329969Y943977D01*
G02X331155Y944189I1189J-3229D01*
G01X334080D01*
G03X335191Y944488I-3J2224D01*
G01Y944487D01*
G02X336665I737J-1277D01*
G03X338846Y944460I1115J1927D01*
G01X338848Y944462D01*
X340269Y945172D01*
X340734Y946082D01*
X341066Y946414D01*
X341479D01*
G01Y952823D02*
X338891Y951751D01*
X338419Y951279D01*
Y950520D01*
X338069Y950170D01*
X337476D01*
X337119Y950527D01*
Y950969D01*
X336769Y951319D01*
X336396D01*
X335191Y950896D01*
G02X334223Y950602I-1305J2556D01*
G01X334168Y950547D01*
X328298D01*
X328109Y950736D01*
G01X343328Y949619D02*
X344154D01*
X344677Y949096D01*
Y948403D01*
X344373Y948099D01*
X343194D01*
G02X342842Y948194I0J699D01*
G01X342593Y948339D01*
G03X342556Y948360I-1116J-1924D01*
G01X342140Y948591D01*
G03X340366Y948342I-722J-1301D01*
G01X340102Y948190D01*
G02X339500Y948029I-602J1046D01*
G01X335988D01*
G02X335684Y948098I0J706D01*
G01X335146Y948355D01*
G03X334034Y948654I-1114J-1926D01*
G01X332036D01*
X331756Y948374D01*
X327074D01*
X326703Y948745D01*
G01X345179Y946414D02*
G02X343717Y946811I0J2890D01*
G01X342216Y947691D01*
G03X340742I-737J-1277D01*
G01Y947690D01*
G03X340004Y946414I736J-1277D01*
G01X339996Y946286D01*
X339714Y945732D01*
X338513Y945132D01*
X338510Y945131D01*
X338503Y945127D01*
X338490Y945120D01*
G02X337041Y945136I-710J1294D01*
G01X337042Y945137D01*
G03X334874Y945171I-1114J-1927D01*
G01X334816Y945137D01*
G02X334079Y944938I-740J1276D01*
G01X331154D01*
G03X329550Y944618I2J-4190D01*
G01X329062Y944130D01*
X328443D01*
X327572Y943259D01*
X327394D01*
X327333Y943198D01*
G01X341479Y959232D02*
X339702Y961009D01*
X335422D01*
X334473Y961402D01*
X331470D01*
X331324Y961548D01*
X330224D01*
G01X343328Y968845D02*
X341844Y970329D01*
X339665D01*
G03X338892Y970122I0J-1547D01*
G01X338214Y969730D01*
G03X337853Y969105I362J-626D01*
G02X336963Y967566I-1776J0D01*
G01X336843Y967497D01*
G02X335060Y967506I-884J1542D01*
G01X334786Y967655D01*
G03X334073Y967834I-713J-1330D01*
G01X334060Y967821D01*
X331224D01*
G01X345179Y965640D02*
X344176Y964637D01*
G02X342709Y964029I-1467J1466D01*
G01X341749D01*
G02X340951Y964243I1J1598D01*
G01X340090Y964739D01*
G03X339168I-461J-798D01*
G01X338516Y964363D01*
G02X337042I-737J1277D01*
G01X336382Y964745D01*
G03X335545Y964758I-430J-744D01*
G01X334816Y964363D01*
G02X334503Y964279I-313J540D01*
G01X333501D01*
X332886Y964534D01*
X332066Y965354D01*
X331224D01*
G01X343328Y981662D02*
Y978220D01*
X342067Y976959D01*
X340494D01*
G03X338892Y976530I0J-3204D01*
G01X338851Y976506D01*
G02X336665Y976530I-1072J1951D01*
G03X335978Y976828I-1642J-2845D01*
G01X335534Y977272D01*
Y978934D01*
X334090Y980378D01*
X329725D01*
G01X341479Y972049D02*
X338626Y970836D01*
X338332Y970666D01*
G02X336859I-737J1275D01*
G01X336556Y970840D01*
G03X335372Y971001I-789J-1372D01*
G01X334915Y970544D01*
X330582D01*
X330349Y970777D01*
G01X330625Y988554D02*
X330735D01*
X331005Y988824D01*
X337386D01*
X338977Y987232D01*
X339255Y986564D01*
Y984866D01*
G03X340314Y982971I2225J0D01*
G03X340367Y982939I1177J1889D01*
G03X342550Y982915I1113J1927D01*
G01X342591Y982939D01*
X342594Y982941D01*
X342615Y982953D01*
G03X343676Y984516I-1136J1913D01*
G03X343688Y984599I-2196J360D01*
G01X343955Y984866D01*
X345179D01*
G01X341479D02*
X342703D01*
X342935Y984634D01*
G02X342251Y983609I-1457J231D01*
G01X342222Y983592D01*
X342216Y983589D01*
G02X340742I-737J1277D01*
G01X340707Y983609D01*
G02X340004Y984866I772J1257D01*
G01Y986713D01*
X339613Y987657D01*
X337697Y989573D01*
X331006D01*
X330735Y989844D01*
X330625D01*
G01X345611Y1013595D02*
X344153Y1012137D01*
X342131D01*
G02X341175Y1012318I-219J1458D01*
G03X338989Y1012342I-1114J-1927D01*
G01X338948Y1012318D01*
G02X337474I-737J1277D01*
G03X335290Y1012342I-1113J-1927D01*
G01X335249Y1012318D01*
G02X334512Y1012121I-736J1277D01*
G01X333477D01*
G01X343761Y1010391D02*
X341104Y1011492D01*
X340798Y1011668D01*
G03X339325I-737J-1275D01*
G01X339324D01*
G03X338924Y1011413I2673J-4634D01*
G01X338479Y1010968D01*
Y1009579D01*
X337719Y1008819D01*
X335318D01*
X334466Y1009671D01*
X331925D01*
G01X341912Y1007187D02*
X341272Y1006547D01*
X339747D01*
X338404Y1005204D01*
X337224Y1005134D01*
X337098Y1005260D01*
G03X335739I-680J-1178D01*
G02X335639Y1005214I-260J433D01*
G01X333795Y1003769D01*
X331065D01*
X329154Y1005680D01*
G01X343761Y1016800D02*
X342232Y1018329D01*
X339760D01*
X339324Y1018077D01*
G02X337098I-1113J1927D01*
G03X335624I-737J-1277D01*
G03X335318Y1017843I735J-1278D01*
G01X334039Y1016564D01*
X330156D01*
X329597Y1017123D01*
G01X343761Y1029617D02*
Y1028397D01*
X344170Y1027988D01*
Y1027495D01*
X343859Y1027184D01*
X343364D01*
X342519Y1028029D01*
Y1028499D01*
X342155Y1028863D01*
X341659D01*
X341319Y1028523D01*
Y1028119D01*
X340819Y1027619D01*
X339342D01*
X338842Y1028119D01*
Y1028695D01*
X338492Y1029045D01*
X337997D01*
X337660Y1028708D01*
Y1028237D01*
X337310Y1027887D01*
X337308D01*
G02X335618Y1028340I0J3380D01*
G01X334884Y1028763D01*
X332444D01*
X331683Y1029524D01*
X330929D01*
X330492Y1029087D01*
G01X341912Y1026413D02*
X343606D01*
X343902Y1026117D01*
Y1024950D01*
X343590Y1024638D01*
X337719D01*
X336692Y1025665D01*
X335849D01*
X335595Y1025411D01*
Y1024988D01*
X334418Y1023811D01*
X331779D01*
X331170Y1024420D01*
Y1025226D01*
X330201Y1026195D01*
X328325D01*
G01X327026Y1031521D02*
X327113D01*
X327238Y1031646D01*
X328051D01*
X328401Y1031296D01*
X329190D01*
X329540Y1031646D01*
X330329D01*
X330679Y1031296D01*
X331468D01*
X331818Y1031646D01*
X332305D01*
X333355Y1030596D01*
X334512D01*
G03X335624Y1030894I0J2224D01*
G02X337098I737J-1277D01*
G03X339279Y1030867I1115J1927D01*
G01X339281Y1030869D01*
X340702Y1031579D01*
X341167Y1032489D01*
X341499Y1032821D01*
X341912D01*
G01Y1039230D02*
Y1038814D01*
X341699Y1038601D01*
X339592D01*
X339294Y1038303D01*
Y1037275D01*
X338538Y1036519D01*
X338019D01*
X336936Y1037602D01*
X336324D01*
G03X335618Y1037304I842J-2981D01*
G02X335239Y1037128I-1166J2014D01*
G02X334975Y1037051I-765J2131D01*
G02X334561Y1036995I-518J2268D01*
G01X334474D01*
X334471Y1036994D01*
G02X334401Y1036995I2J2559D01*
G01X333855Y1037024D01*
X332990Y1037287D01*
X332953D01*
X331479Y1038761D01*
X330758D01*
X330210Y1039309D01*
X329259D01*
X328711Y1038761D01*
X328060D01*
X327751Y1039070D01*
X327042D01*
X326761Y1038789D01*
X326126D01*
X325305Y1039610D01*
G01X343761Y1036026D02*
X344461Y1036726D01*
X345163D01*
X345892Y1035997D01*
Y1034847D01*
X345345Y1034300D01*
X344767Y1034356D01*
G02X343687Y1034552I627J6530D01*
G02X342927Y1034809I75J1474D01*
G02X342792Y1034866I2484J6071D01*
G03X341306Y1034966I-884J-2043D01*
G01X341047Y1034893D01*
G03X340722Y1034763I465J-1633D01*
G02X339954Y1034605I-660J1263D01*
G02X339949I-2J522D01*
G03X338201Y1034660I-1457J-18515D01*
G03X336475Y1034605I-286J-18144D01*
G02X335685Y1034771I-114J1421D01*
G03X335368Y1034919I-1346J-2470D01*
G03X333905Y1035208I-1551J-4004D01*
G02X333420Y1035329I21J1117D01*
G01X332385Y1035854D01*
G03X332350Y1035870I-226J-448D01*
G01X331303Y1036304D01*
X330589Y1036446D01*
X330262Y1036511D01*
X330226Y1036518D01*
G01X345611Y1032821D02*
G02X344150Y1033218I0J2887D01*
G01X342649Y1034098D01*
G03X341175I-737J-1277D01*
G03X340456Y1033059I738J-1279D01*
G01X340433Y1032749D01*
X340434D01*
X340429Y1032693D01*
X340147Y1032139D01*
X338946Y1031539D01*
X338943Y1031538D01*
X338936Y1031534D01*
X338923Y1031527D01*
G02X337474Y1031543I-710J1294D01*
G01Y1031544D01*
G03X335290Y1031568I-1113J-1927D01*
G01X335249Y1031544D01*
X335248Y1031543D01*
G02X334512Y1031346I-736J1276D01*
G01X334511Y1031345D01*
X333666D01*
X332616Y1032395D01*
X327239D01*
X327113Y1032521D01*
X327026D01*
G01X343761Y1048842D02*
Y1047562D01*
X344321Y1047002D01*
Y1046341D01*
X344074Y1046094D01*
X343480D01*
X342519Y1047055D01*
Y1047941D01*
X342111Y1048349D01*
X341593D01*
X341219Y1047975D01*
Y1047052D01*
X340257Y1046090D01*
X339814D01*
X339205Y1046699D01*
Y1047630D01*
X338376Y1048459D01*
X337998D01*
X337574Y1048035D01*
Y1047203D01*
X337388Y1047017D01*
X336932D01*
X334773Y1047962D01*
X332444D01*
X331716Y1047234D01*
X331208D01*
G01X341912Y1045639D02*
Y1044677D01*
X342222Y1044367D01*
Y1043620D01*
X341860Y1043258D01*
X341306D01*
X340519Y1044045D01*
Y1044719D01*
X340219Y1045019D01*
X339619D01*
X339001Y1044401D01*
Y1043401D01*
X338519Y1042919D01*
X337893D01*
X337310Y1043502D01*
Y1043732D01*
X337003Y1044039D01*
X335365D01*
X334201Y1042875D01*
X333630D01*
X332487Y1041732D01*
X331153D01*
X330472Y1042413D01*
Y1042875D01*
X330426Y1042921D01*
G01X343761Y1055251D02*
X345122D01*
G02X345471Y1054902I0J-349D01*
G01Y1054074D01*
G02X345122Y1053725I-349J0D01*
G01X343652D01*
G02X343313Y1053810I-2J711D01*
G02X343024Y1053974I4730J8671D01*
G01X342966Y1054008D01*
G03X340798Y1053974I-1054J-1961D01*
G01X340039Y1053529D01*
X339621D01*
X338417Y1054733D01*
X337776D01*
X336812Y1053769D01*
X335820D01*
X334848Y1054389D01*
X334576Y1054661D01*
Y1055494D01*
X333908Y1056162D01*
X333172D01*
X332595Y1056739D01*
Y1057475D01*
X331913Y1058157D01*
X331287D01*
X330559Y1058885D01*
G01X345611Y1052047D02*
X343380Y1052819D01*
X342649Y1053324D01*
G03X341175I-737J-1277D01*
G03X340811Y1053086I1928J-3346D01*
G01X340770D01*
X340143Y1052459D01*
Y1052460D01*
G03X339705Y1051815I2960J-2481D01*
G03X339662Y1051734I2015J-1122D01*
G01X339245Y1050915D01*
X338946Y1050765D01*
X338943Y1050764D01*
X338936Y1050760D01*
X338923Y1050753D01*
G02X337714Y1050658I-710J1294D01*
G02X337474Y1050769I497J1390D01*
G01X337212Y1051031D01*
X335485D01*
X335158Y1050704D01*
X333325D01*
X328367Y1055662D01*
Y1055842D01*
X328306Y1055903D01*
G01X341912Y1052047D02*
G03X340330Y1051393I-409J-1252D01*
G01X339801Y1050355D01*
X339281Y1050095D01*
X339279Y1050093D01*
G02X337461Y1049951I-1067J1954D01*
G01Y1049953D01*
G02X337006Y1050176I746J2097D01*
G01X336901Y1050282D01*
X335796D01*
X335469Y1049955D01*
X333014D01*
X332720Y1050249D01*
X332143D01*
X331648Y1050744D01*
Y1051321D01*
X331154Y1051815D01*
X330577D01*
X330082Y1052310D01*
Y1052887D01*
X329588Y1053381D01*
X329011D01*
X328516Y1053876D01*
Y1054453D01*
X327835Y1055134D01*
X327659D01*
X327598Y1055195D01*
G01X341912Y1064864D02*
Y1063306D01*
X341605Y1062999D01*
X341079D01*
X340720Y1063358D01*
Y1064068D01*
X340388Y1064400D01*
X339808D01*
X339598Y1064190D01*
Y1063368D01*
X338682Y1062452D01*
X337502D01*
X336891Y1063063D01*
X335865D01*
X334246Y1064682D01*
X333353D01*
X332505Y1065530D01*
G01X341912Y1058455D02*
X342746D01*
X343183Y1058892D01*
Y1059912D01*
X342551Y1060544D01*
X340948D01*
X339969Y1059565D01*
Y1057369D01*
X338619Y1056019D01*
X337719D01*
X336919Y1056819D01*
X336304D01*
X335804Y1057319D01*
Y1058629D01*
X335304Y1059129D01*
X333713D01*
X330558Y1062284D01*
G01X343761Y1068068D02*
Y1066179D01*
X343469Y1065887D01*
X343010D01*
X342541Y1066356D01*
Y1066996D01*
X342122Y1067415D01*
X341491D01*
X340941Y1066865D01*
Y1066005D01*
X340554Y1065618D01*
X339728D01*
X339508Y1065838D01*
X338818Y1067221D01*
X338507Y1067532D01*
X337774D01*
X336944Y1066702D01*
Y1065558D01*
X336551Y1065165D01*
X335976D01*
X335195Y1065946D01*
Y1066873D01*
X334812Y1067256D01*
X334177D01*
X332104Y1069329D01*
G01X345611Y1071273D02*
G02X344150Y1071670I0J2887D01*
G01X342649Y1072550D01*
G03X341175I-737J-1277D01*
G03X340456Y1071511I738J-1279D01*
G01X340433Y1071201D01*
X340434D01*
X340429Y1071145D01*
X340147Y1070591D01*
X338946Y1069991D01*
X338943Y1069990D01*
X338936Y1069986D01*
X338923Y1069979D01*
G02X337472Y1069995I-711J1294D01*
G02X337167Y1070230I741J1277D01*
G01Y1070229D01*
X336619Y1070777D01*
X335907D01*
X335103Y1071111D01*
X334881Y1071332D01*
X334882D01*
X329649Y1076565D01*
X329646D01*
X328977Y1077234D01*
Y1077414D01*
X328916Y1077475D01*
G01X328208Y1076767D02*
X328269Y1076706D01*
X328445D01*
X329335Y1075816D01*
X329338D01*
X329868Y1075286D01*
Y1074734D01*
X330434Y1074167D01*
X330986D01*
X331551Y1073602D01*
Y1073051D01*
X332117Y1072484D01*
X332669D01*
X333234Y1071919D01*
Y1071368D01*
X333800Y1070801D01*
X334352D01*
X334678Y1070475D01*
X335757Y1070028D01*
X336308D01*
X336637Y1069699D01*
G03X337098Y1069346I1572J1575D01*
G03X339279Y1069319I1115J1927D01*
G01X339281Y1069321D01*
X340702Y1070031D01*
X341267Y1071137D01*
X341403Y1071273D01*
X341912D01*
G01X340061Y1080885D02*
X338884Y1082062D01*
X338288Y1082076D01*
X337921Y1081743D01*
X337819Y1080719D01*
Y1080419D01*
X337619Y1080019D01*
X337147Y1079668D01*
G02X336821Y1079560I-326J439D01*
G01X335697D01*
X335210Y1079762D01*
X334174Y1080798D01*
Y1080863D01*
X332206Y1082831D01*
G01X343761Y1074477D02*
X342740Y1074096D01*
X341250Y1073461D01*
X340524Y1073042D01*
G02X340029Y1072909I-496J857D01*
G01X339149D01*
X338636Y1073422D01*
Y1074516D01*
G03X337550Y1076360I-2173J-38D01*
G01X337474Y1076404D01*
G03X336957Y1076647I-1680J-2903D01*
G03X336860Y1076664I-95J-259D01*
G01X335286D01*
X334383Y1076290D01*
X333741D01*
X333239Y1076498D01*
X332832Y1076905D01*
X332372Y1078015D01*
Y1079256D01*
X330501Y1081127D01*
G01X345611Y1090498D02*
X345217Y1090103D01*
G02X342338Y1088909I-2879J2874D01*
G01X339126D01*
G02X337710Y1089133I0J4590D01*
G02X337388Y1089269I662J2016D01*
G03X336361Y1089519I-1025J-1975D01*
G01X334895D01*
X331896Y1092518D01*
Y1093049D01*
X330267Y1094678D01*
X329487D01*
X328220Y1095945D01*
G01X343761Y1087294D02*
X341981Y1086538D01*
G03X341668Y1086381I1111J-2605D01*
G01X340525Y1085718D01*
G02X339151Y1085716I-689J1186D01*
G01X338629Y1086017D01*
G03X337098I-765J-1326D01*
G02X336361Y1085820I-736J1277D01*
G01X334402D01*
X329650Y1090572D01*
X329137D01*
X327554Y1092155D01*
Y1093153D01*
X326491Y1094216D01*
G01X343761Y1093703D02*
X344985D01*
X345217Y1093935D01*
G03X344533Y1094960I-1457J-231D01*
G01X344498Y1094980D01*
G03X343024I-737J-1277D01*
G01X343018Y1094977D01*
X342989Y1094960D01*
G03X342286Y1093703I772J-1257D01*
G01Y1093616D01*
G02X341175Y1091775I-2225J87D01*
G02X338989Y1091751I-1114J1928D01*
G01X338948Y1091775D01*
G03X337474I-737J-1277D01*
G02X336361Y1091477I-1113J1928D01*
G01X335601D01*
X334968Y1091739D01*
X334172Y1092535D01*
X333857Y1093294D01*
X332039Y1095113D01*
X331581Y1096503D01*
X331329Y1096755D01*
X331151D01*
X331090Y1096816D01*
G01X354861Y1093703D02*
X352305Y1094902D01*
X351253Y1095155D01*
X348912Y1095445D01*
X348333Y1095728D01*
X348008Y1096087D01*
X346707Y1097841D01*
X346368Y1098180D01*
X345978Y1098342D01*
X344835D01*
G02X343024Y1098834I0J3578D01*
G01X342966Y1098868D01*
G03X340798Y1098834I-1054J-1961D01*
G02X339324I-737J1277D01*
G01X339014Y1099013D01*
G02X338635Y1099422I469J814D01*
G03X338472Y1099732I-3893J-1849D01*
G01X338144Y1100219D01*
X338064Y1100323D01*
X338070Y1100365D01*
X336733Y1102158D01*
G01X333603Y1101027D02*
X334123Y1100507D01*
G02X334394Y1100017I-714J-715D01*
G03X334665Y1099525I985J222D01*
G01X335426Y1098764D01*
X336809D01*
G02X338948Y1098184I0J-4235D01*
G01X338989Y1098160D01*
G03X341175Y1098184I1072J1951D01*
G02X342896Y1097957I713J-1235D01*
G01X343816Y1097037D01*
G03X344130Y1096907I314J314D01*
G01X345611D01*
G01X331798Y1097524D02*
X331859Y1097463D01*
Y1097285D01*
X332237Y1096907D01*
X332695Y1095517D01*
X334493Y1093719D01*
X334808Y1092960D01*
X335393Y1092375D01*
X335750Y1092226D01*
X336361D01*
G03X337098Y1092426I-5J1476D01*
G02X339324I1113J-1928D01*
G03X340798I737J1277D01*
G01X340833Y1092446D01*
G03X341535Y1093645I-772J1257D01*
G03X341536Y1093703I-1474J54D01*
G02X342625Y1095616I2225J0D01*
G01X342646Y1095628D01*
X342649Y1095630D01*
X342690Y1095654D01*
G02X344874Y1095630I1071J-1951D01*
G02X345959Y1094054I-1112J-1927D01*
G02X345971Y1093969I-2197J-354D01*
G01X346237Y1093703D01*
X347461D01*
G01X524628Y981662D02*
X522764Y982368D01*
X522144Y982662D01*
X521665Y982939D01*
G02X520554Y984805I1114J1927D01*
G01Y985164D01*
X520614Y985452D01*
X520754Y985890D01*
X521067Y986322D01*
X521743Y987070D01*
X522147Y987431D01*
X522481Y987662D01*
X526439Y990049D01*
X532845Y993391D01*
X533344Y993625D01*
X535284Y994538D01*
X536801Y994989D01*
X537466Y995095D01*
G01X526479Y978457D02*
X526077Y981902D01*
X525910Y982304D01*
G03X525723Y982598I-945J-395D01*
G01X525430Y982922D01*
G03X525138Y983116I-522J-469D01*
G03X524279Y983259I-856J-2488D01*
G01X523285D01*
G02X522042Y983589I0J2505D01*
G01X522007Y983609D01*
G02X521304Y984866I772J1257D01*
G01Y985089D01*
X521417Y985487D01*
X521548Y985700D01*
X521756Y985960D01*
X522515Y986698D01*
X526379Y988939D01*
X531640Y991543D01*
X532709Y991986D01*
G01X530179Y978457D02*
Y982003D01*
G02X530459Y982679I956J0D01*
G01X530667Y982886D01*
G02X531759Y983339I1093J-1092D01*
G01X534189D01*
X534678Y983626D01*
X534705Y983641D01*
X534737Y983658D01*
X534885Y983788D01*
X535353Y984256D01*
Y984818D01*
X535355Y984851D01*
G02X535356Y984866I2342J-149D01*
G01X535355D01*
G02X537599Y987089I2345J-123D01*
G01X538273D01*
X539425Y987566D01*
X539725D01*
G01X532028Y981662D02*
G03X534885Y982847I-3914J13472D01*
G01X534957Y982919D01*
Y982920D01*
X535061Y982981D01*
X535066Y982984D01*
X535072Y982987D01*
G03X535960Y983769I-1025J2060D01*
G03X536104Y984248I-717J477D01*
G01Y984827D01*
G02X537617Y986340I1596J-83D01*
G01X544906D01*
X545626Y985620D01*
X546325D01*
G01X543129Y891942D02*
G03X545435Y890176I7817J7819D01*
G01X545716Y890014D01*
G02X546022Y889780I-735J-1278D01*
G01X547047Y888755D01*
X548207Y886959D01*
X548870Y886296D01*
G01X537579Y895146D02*
G03X538937Y895507I0J2733D01*
G01X540692Y896512D01*
G02X541619Y896759I927J-1618D01*
G01X544402D01*
G02X545888Y896313I1J-2697D01*
G01X547347Y895351D01*
X547839Y895401D01*
X548307Y895869D01*
X548789D01*
X552416Y892242D01*
G01X539428Y891942D02*
X542204Y893544D01*
G02X544054I925J-1602D01*
G01X544664Y892933D01*
G02X544919Y892319I-614J-615D01*
G01Y892282D01*
G03X545290Y891386I1267J0D01*
G01X545785Y890891D01*
G03X546240Y890616I784J783D01*
G03X546658Y890504I1776J5794D01*
G02X546975Y890354I-183J-796D01*
G01X548730Y888599D01*
X549044D01*
X550109Y887534D01*
G01X544979Y895146D02*
X546770Y893355D01*
X549293D01*
X551411Y891237D01*
G01X535729Y898350D02*
X538581Y897039D01*
G03X539319Y896910I613J1331D01*
G01X539550Y896929D01*
G03X540345Y897254I-117J1421D01*
G01X540509Y897390D01*
G03X540561Y897445I-204J245D01*
G01X541938Y899293D01*
X542089Y899430D01*
Y899431D01*
G02X543857Y899635I1025J-1123D01*
G01X543870Y899627D01*
X543871D01*
X543873Y899626D01*
X544047Y899526D01*
G03X544432Y899370I768J1343D01*
G03X546019Y899583I531J2062D01*
G01X546261Y899721D01*
X546353Y899768D01*
X547419D01*
X548538Y899305D01*
Y899303D01*
X550193Y898619D01*
X551398Y898120D01*
X552067D01*
X552882Y897305D01*
Y897129D01*
X552943Y897068D01*
G01X546828Y898350D02*
G02X546836Y898346I0J-10D01*
G01X547532Y897652D01*
X550169D01*
X552351Y895470D01*
X552529D01*
X552590Y895409D01*
G01X539428Y898350D02*
X539922Y898244D01*
X540499Y898617D01*
X541380Y899800D01*
X541583Y899985D01*
G02X544224Y900290I1532J-1677D01*
G01X544228Y900288D01*
X544420Y900178D01*
G03X544619Y900097I397J690D01*
G03X545646Y900235I343J1335D01*
G01X545884Y900371D01*
X546175Y900517D01*
X547568D01*
X548825Y899997D01*
X549321Y900203D01*
X550274Y899809D01*
X550480Y899311D01*
X551547Y898869D01*
X552378D01*
X553410Y897837D01*
X553590D01*
X553651Y897776D01*
G01X543129Y898350D02*
X543812D01*
X543843Y898319D01*
G02X544018Y898272I0J-350D01*
G01X546096Y897073D01*
X546405Y896903D01*
X549858D01*
X551821Y894939D01*
Y894763D01*
X551882Y894702D01*
G01X537579Y914372D02*
X536408D01*
X536217Y914563D01*
Y915467D01*
X536573Y915823D01*
X537982D01*
X538307Y915632D01*
X538875Y915324D01*
G03X540104Y915341I599J1103D01*
G01X541190Y915969D01*
X545006D01*
X545700Y915670D01*
X545725Y915660D01*
X546228Y915369D01*
X551273D01*
X552124Y914518D01*
G01X539428Y911167D02*
X540904D01*
X541305Y911568D01*
Y912091D01*
X542333Y913119D01*
X543919D01*
X544361Y912673D01*
X546738D01*
X547804Y913739D01*
X549507D01*
X554360Y908886D01*
G01X544979Y914372D02*
X545074Y914467D01*
G02X545162Y914503I88J-88D01*
G01X550441D01*
X555209Y909735D01*
G01X543129Y911167D02*
X546987Y909569D01*
X551979D01*
X553511Y908037D01*
G01X539428Y904759D02*
G02X541721Y906167I4090J-4090D01*
G01X541865Y906214D01*
G03X542213Y906369I-575J1759D01*
G02X544051Y906376I925J-1602D01*
G01X544063Y906369D01*
G03X545176Y906131I925J1603D01*
G02X545776Y906185I2675J-26360D01*
G01X547051Y907460D01*
X550634D01*
X551091Y907271D01*
X556969Y901393D01*
G01X537579Y901555D02*
Y902791D01*
X537071Y903299D01*
Y903877D01*
X537429Y904235D01*
X537865D01*
X538997Y903103D01*
X539992D01*
X540439Y903366D01*
G02X542255Y903374I915J-1552D01*
G01X542661Y903139D01*
X544523D01*
G02X545806Y902780I0J-2471D01*
G01X546548Y902329D01*
X550322D01*
X551168Y901979D01*
X552987D01*
X553620Y901346D01*
G01X543129Y904759D02*
G02X544300Y904460I-1J-2446D01*
G01X546105Y903476D01*
X546531Y903218D01*
X553446D01*
X556183Y900481D01*
G01X544979Y901555D02*
X547520D01*
X547870Y901205D01*
X548869D01*
X549219Y901555D01*
X549845D01*
X550092Y901308D01*
Y900943D01*
X550476Y900559D01*
X552709D01*
X554422Y898846D01*
G01X535729Y917576D02*
G02X537294Y917157I2J-3124D01*
G01X539161Y916078D01*
G03X539746Y916108I199J1832D01*
G01X540036Y916229D01*
X540485Y916470D01*
X541113Y916985D01*
X541498Y917370D01*
Y917438D01*
X541495Y917441D01*
Y918222D01*
X542269Y918801D01*
Y918802D01*
X543014Y919087D01*
X543366D01*
X544645Y918553D01*
X545827D01*
X546243Y918969D01*
X547773D01*
X548078Y918664D01*
X551204D01*
X551205Y918663D01*
X552489D01*
X552614Y918538D01*
X552701D01*
G01X546828Y917576D02*
Y917224D01*
X547179Y916873D01*
X552845D01*
X553497Y916221D01*
X553675D01*
X553736Y916160D01*
G01X543129Y917576D02*
X545242Y916757D01*
G02X545731Y916522I-1256J-3240D01*
G03X546393Y916220I1864J3209D01*
G01X546400Y916218D01*
G03X546966Y916124I566J1657D01*
G01X552534D01*
X552967Y915691D01*
Y915514D01*
X553028Y915453D01*
G01X539428Y930393D02*
X540652D01*
X540918Y930659D01*
G02X542016Y932321I2210J-266D01*
G02X544242I1113J-1928D01*
G02X545354Y930466I-1113J-1928D01*
G01Y930359D01*
G03X546091Y929116I1474J34D01*
G03X546828Y928917I740J1276D01*
G01X552472D01*
X553480Y927909D01*
X555524D01*
G01X543129Y930393D02*
X544118Y929983D01*
X545067Y929034D01*
G03X545692Y928480I1762J1358D01*
G03X546682Y928172I1138J1912D01*
G03X546827Y928168I134J2221D01*
G01X552137D01*
X553596Y926709D01*
X555524D01*
G01X539428Y923985D02*
X539057Y924881D01*
Y925413D01*
X539469Y925825D01*
X540223D01*
X540719Y925329D01*
Y924969D01*
X541069Y924619D01*
X541647D01*
X541997Y924969D01*
Y925598D01*
X542462Y926063D01*
X543587D01*
G02X544077Y925860I1J-691D01*
G03X544835Y925401I1304J1299D01*
G03X545182Y925349I345J1118D01*
G01X548215Y926605D01*
X549631D01*
X551652Y924584D01*
X552524D01*
G01X537579Y920780D02*
X537219Y921650D01*
Y922697D01*
X537568Y923046D01*
X538062D01*
X538419Y922689D01*
Y922075D01*
X539120Y921374D01*
X539504D01*
X540519Y922389D01*
X544493D01*
G02X545716Y922057I0J-2418D01*
G01X546313Y921707D01*
X550247D01*
X550626Y922086D01*
X551359D01*
X551360Y922087D01*
X552524D01*
G01X543129Y923985D02*
X544275D01*
X544815Y923445D01*
X546519Y922461D01*
X549841D01*
X550701Y923321D01*
X552524D01*
G01X544979Y920780D02*
X545086Y920887D01*
X552524D01*
G01X539428Y917576D02*
X540483D01*
X540746Y917839D01*
Y918597D01*
X541903Y919464D01*
X542875Y919836D01*
X543517D01*
X544796Y919302D01*
X545516D01*
X545932Y919718D01*
X548084D01*
X548389Y919413D01*
X549103D01*
X549530Y919840D01*
X550231D01*
X550658Y919413D01*
X551577D01*
X551578Y919412D01*
X552488D01*
X552614Y919538D01*
X552701D01*
G01X543129Y949619D02*
X547161Y947949D01*
X547696D01*
X551479Y946381D01*
X552517Y945343D01*
G01X543129Y943210D02*
X544108Y942231D01*
X544987D01*
G02X546078Y941943I-4J-2225D01*
G03X546833Y941734I757J1267D01*
G01X548267D01*
X549408Y942875D01*
X550332D01*
X554498Y938709D01*
X554924D01*
G01X544979Y940006D02*
X544988Y940015D01*
X550539D01*
X554245Y936309D01*
X554924D01*
G01X537579Y933598D02*
G03X540542Y934874I-3884J13098D01*
G01X541167Y935236D01*
G02X541739Y935389I571J-989D01*
G01X541799D01*
G02X542128Y935286I-1J-580D01*
G01X542319Y935095D01*
Y934619D01*
X542819Y934119D01*
X543419D01*
X543869Y934569D01*
Y934869D01*
X544169Y935169D01*
X544459D01*
G02X544637Y935154I0J-1065D01*
G01X545232Y935050D01*
G02X546021Y934640I-253J-1452D01*
G01X549407D01*
X553739Y930308D01*
X553740Y930309D01*
X555524D01*
G01X544979Y933598D02*
X549354D01*
X553843Y929109D01*
X555524D01*
G01X539428Y943210D02*
X540263Y943092D01*
G03X540594Y943177I63J442D01*
G01X542568Y944659D01*
G02X542894Y944768I326J-434D01*
G01X546472D01*
X547978Y946274D01*
X549420D01*
X550090Y945604D01*
X550272Y945331D01*
Y944591D01*
X554954Y939909D01*
X556224D01*
G01X537579Y940006D02*
Y941128D01*
G02X537584Y941140I17J0D01*
G01X537934Y941490D01*
X538503D01*
X539074Y940919D01*
X539903D01*
X540803Y941819D01*
X541874D01*
X542874Y940819D01*
X543573D01*
X543935Y941181D01*
X544343Y941341D01*
X544405Y941364D01*
X544408Y941365D01*
X544456Y941383D01*
X544976Y941481D01*
X544989D01*
X545698Y941296D01*
X545706Y941292D01*
X546227Y940985D01*
X550922D01*
X554398Y937509D01*
X554924D01*
G01X535729Y936801D02*
X538310Y935615D01*
G03X539550Y935380I1083J2323D01*
G03X540345Y935705I-117J1421D01*
G01X540509Y935841D01*
G03X540561Y935896I-204J245D01*
G01X540982Y936459D01*
X540980Y936460D01*
X541408Y937034D01*
X542126Y937818D01*
X542454Y938111D01*
G02X543866Y938078I676J-1310D01*
G01X544057Y937967D01*
X544058D01*
X544077Y937959D01*
G03X545882Y937958I903J1564D01*
G02X546784Y938200I903J-1563D01*
G01X548034D01*
X548946Y938052D01*
G02X549433Y937846I-1355J-3882D01*
G01X549493Y937815D01*
X549552Y937786D01*
X549553D01*
X552079Y935261D01*
Y935262D01*
X553211Y934130D01*
X554051D01*
X554172Y934009D01*
G01X546828Y936801D02*
Y936491D01*
X547178Y936141D01*
X550026D01*
X553684Y932483D01*
X555511D01*
X555637Y932609D01*
X555724D01*
G01X539428Y936801D02*
X539953Y936688D01*
X540460Y937016D01*
X540830Y937512D01*
X541598Y938351D01*
X542017Y938727D01*
G02X544240I1111J-1926D01*
G01X544242Y938729D01*
X544451Y938608D01*
G03X545508Y938607I529J915D01*
G02X546783Y938949I1277J-2212D01*
G01X548095D01*
X549128Y938782D01*
G02X549771Y938515I-1538J-4611D01*
G01X549997Y938402D01*
X550229Y938170D01*
X550784D01*
X551208Y937746D01*
Y937193D01*
X551632Y936769D01*
X552185D01*
X552609Y936345D01*
Y935792D01*
X553522Y934879D01*
X554042D01*
X554172Y935009D01*
G01X543129Y936801D02*
X543131Y936795D01*
X546572Y935392D01*
X549715D01*
X553373Y931734D01*
X555512D01*
X555637Y931609D01*
X555724D01*
G01X537579Y952823D02*
X537554Y952848D01*
Y953369D01*
X537904Y953719D01*
X539963D01*
X540903Y954263D01*
G02X541654Y954531I1103J-1905D01*
G01X541727Y954543D01*
G02X542389Y954329I122J-754D01*
G03X543699I655J655D01*
G02X544109Y954499I410J-410D01*
G01X544349D01*
G02X545229Y954330I-1J-2382D01*
G01X545532Y954210D01*
G02X545825Y954018I-322J-810D01*
G01X546802Y953049D01*
X550349D01*
X553331Y950067D01*
Y949719D01*
X553813Y949237D01*
G01X539428Y949619D02*
X540987D01*
X541357Y949989D01*
Y950785D01*
X541951Y951379D01*
X549656D01*
X550784Y950251D01*
Y948858D01*
X552108Y947534D01*
G01X544979Y952823D02*
X544981Y952824D01*
X546034Y952389D01*
G03X546788Y952239I755J1823D01*
G01X550013D01*
X552155Y950097D01*
Y949185D01*
X552957Y948383D01*
G01X539428Y962436D02*
X541167D01*
X541553Y962822D01*
Y963886D01*
X542106Y964439D01*
X543841D01*
X544341Y963939D01*
Y963331D01*
X544810Y962862D01*
X545305D01*
X545744Y963301D01*
Y964236D01*
X545959Y964451D01*
X547083D01*
X547725Y963809D01*
X548655D01*
X550083Y965237D01*
X550791D01*
X551185Y964843D01*
Y963893D01*
X551534Y963544D01*
X551762D01*
G01X537579Y959232D02*
X537219Y960102D01*
Y961445D01*
X537430Y961656D01*
X538115D01*
X538704Y961067D01*
Y960379D01*
X539054Y960029D01*
X539549D01*
X540957Y961409D01*
X541562D01*
X542776Y960195D01*
X543272D01*
X543949Y960872D01*
X543969Y960883D01*
G02X545104Y960884I568J-983D01*
G01X545726Y960525D01*
G03X547058Y960168I1332J2307D01*
G01X549176D01*
X549844Y959500D01*
X551824D01*
G01X543129Y962436D02*
X544543Y962075D01*
X546119Y961164D01*
G03X546852Y960968I732J1269D01*
G01X549576D01*
X549844Y960700D01*
X551824D01*
G01X544979Y959232D02*
X549037Y959247D01*
X549984Y958300D01*
X551824D01*
G01X546828Y956027D02*
Y955677D01*
X547776Y954729D01*
X548672D01*
X549038Y955095D01*
X549802D01*
X550168Y954729D01*
X551049D01*
X557894Y947884D01*
X558611D01*
X558737Y948010D01*
X558824D01*
G01X553687Y953910D02*
X553626Y953971D01*
Y954148D01*
X551394Y956380D01*
X549152D01*
X548029Y957503D01*
X546926D01*
X546925Y957504D01*
X546828D01*
G03X546090Y957306I0J-1474D01*
G02X543868I-1111J1926D01*
G03X542391I-739J-1279D01*
G01Y957304D01*
G03X541859Y956780I734J-1278D01*
G03X541810Y956690I1269J-749D01*
G02X541644Y956380I-5343J2662D01*
G01X541372Y955910D01*
G02X540280Y954818I-2588J1496D01*
G01X540165Y954751D01*
X540163D01*
G02X538691Y954750I-737J1275D01*
G01X538575Y954818D01*
X535729Y956028D01*
Y956027D01*
G01X543129D02*
Y956028D01*
X545424Y955155D01*
X547461Y953979D01*
X550167D01*
X550168Y953980D01*
X550738D01*
X557583Y947135D01*
X558612D01*
X558737Y947010D01*
X558824D01*
G01X539428Y956027D02*
Y955889D01*
X539622Y955695D01*
G03X539979Y955609I248J247D01*
G03X540436Y955949I-280J853D01*
G01X540924Y956648D01*
G03X541056Y956973I-672J462D01*
G02X541255Y957355I704J-124D01*
G01X541424Y957524D01*
G02X541901Y957889I1611J-1612D01*
G01X542016Y957955D01*
G02X544242I1113J-1928D01*
G03X545716I737J1277D01*
G02X546828Y958253I1112J-1926D01*
G01X547080D01*
X547081Y958252D01*
X548340D01*
X549463Y957129D01*
X551705D01*
X554155Y954679D01*
X554333D01*
X554394Y954618D01*
G01X539428Y981662D02*
X540806Y983040D01*
X544590D01*
X545970Y984420D01*
X551870D01*
X557733Y978557D01*
G01X543129Y981662D02*
X545013D01*
X546371Y983020D01*
X551570D01*
X557325Y977265D01*
G01X537579Y978457D02*
X540429Y977246D01*
X540542Y977180D01*
G03X542015I737J1275D01*
G01X542016D01*
X542017Y977181D01*
G03X542754Y978457I-736J1276D01*
G01X544378Y980105D01*
X545678Y980116D01*
X546762Y981220D01*
X551670D01*
X556484Y976406D01*
G01X546828Y975253D02*
X547228D01*
X548283Y976308D01*
X554050D01*
X555110Y975248D01*
G01X535729Y975253D02*
X536959Y976483D01*
X538519D01*
X538903Y976630D01*
G02X540165Y976530I526J-1377D01*
G03X542351Y976506I1114J1927D01*
G01X542392Y976530D01*
G02X543866I737J-1277D01*
G02X544603Y975253I-738J-1277D01*
G03X544966Y974626I724J1D01*
G01X546553Y973884D01*
X547833D01*
X549169Y975220D01*
X553038D01*
X554225Y974033D01*
G01X552425Y970788D02*
X549564D01*
X549345Y971007D01*
X546382D01*
G03X546036Y970952I-3J-1097D01*
G03X545631Y970781I909J-2719D01*
G01X544770Y970339D01*
X543479D01*
X543129Y969989D01*
Y968845D01*
G01X552424Y968388D02*
X548777D01*
X548320Y968845D01*
X546828D01*
G01X552425Y969588D02*
X549673D01*
X549012Y970249D01*
X546525D01*
G03X545986Y970118I0J-1176D01*
G01X545568Y969903D01*
X545165Y969500D01*
Y968863D01*
X543868Y967566D01*
X543129Y967368D01*
X542401Y967564D01*
X542104Y967734D01*
X541623Y968215D01*
X540949D01*
X539428Y968845D01*
G01X552424Y967188D02*
X545600D01*
X544514Y967013D01*
G03X544242Y966917I125J-788D01*
G02X542016I-1113J1928D01*
G01X541797Y967043D01*
G03X541029Y967249I-769J-1331D01*
G01X538919D01*
X538039Y968129D01*
X537579Y969949D01*
Y972049D01*
G01X543129Y975253D02*
X541839D01*
G03X541544Y975131I0J-417D01*
G03Y973888I621J-622D01*
G01X542206Y973226D01*
G03X542520Y973096I314J314D01*
G01X543271D01*
G03X543934Y973370I1J937D01*
G01X544208Y973645D01*
G02X544222Y973651I14J-14D01*
G01X544867D01*
G02X545765Y973238I-890J-3117D01*
G02X545925Y973115I-786J-1189D01*
G03X546108Y973075I184J403D01*
G01X548558D01*
X549614Y974131D01*
X551333D01*
X553476Y971988D01*
X554225D01*
G01X554625Y1001369D02*
X552160D01*
X550329Y999538D01*
X549935Y999336D01*
G02X549345Y999139I-924J1786D01*
G01X545821Y998547D01*
G02X545469Y998601I-94J559D01*
G01X545024Y998823D01*
X544675Y999501D01*
G03X542449I-1113J-1927D01*
G01Y999500D01*
X541378Y998004D01*
X540948Y997574D01*
X539861D01*
G01X543561D02*
X545367Y997575D01*
X549749Y998446D01*
X550958Y998812D01*
X552057D01*
X552672Y999068D01*
X552825Y999131D01*
G01X543561Y1003983D02*
X548236Y1006569D01*
X548859D01*
X549200Y1006228D01*
X550825D01*
G01X547261Y1003983D02*
X549782Y1005027D01*
X552325D01*
G01X536161Y1003983D02*
X537079Y1003065D01*
X538750D01*
X539089Y1002726D01*
X539124Y1002706D01*
G03X540598I737J1277D01*
G02X542824I1113J-1928D01*
G03X543885Y1002545I737J1277D01*
G01X544214Y1002714D01*
X544783Y1002969D01*
G02X546089Y1002930I589J-2146D01*
G01X547019Y1002616D01*
X547851D01*
X548805Y1003029D01*
X549534D01*
X550332Y1003827D01*
X552325D01*
G01X538012Y1000778D02*
X538991Y1001757D01*
X539888D01*
G03X540974Y1002055I-27J2226D01*
G02X542448I737J-1277D01*
G03X544149Y1001836I1113J1928D01*
G01X544559Y1002047D01*
X545060Y1002255D01*
G02X546120Y1002094I324J-1438D01*
G01X546167Y1002067D01*
X546919Y1001867D01*
X548070D01*
X549021Y1002279D01*
X549884D01*
X550232Y1002627D01*
X552325D01*
G01X551125Y1012983D02*
X547888D01*
G03X546785Y1012699I-1J-2279D01*
G01X545990Y1012259D01*
G03X545379Y1011772I910J-1769D01*
G01X543707D01*
X543459Y1011524D01*
Y1010493D01*
X543561Y1010391D01*
G01X551125D02*
X547261D01*
G01X551125Y1011729D02*
X547737D01*
X547724Y1011716D01*
X547132D01*
G03X546583Y1011713I-272J-548D01*
G01X546361Y1011601D01*
G03X545686Y1010768I609J-1183D01*
G01Y1010391D01*
G02X545019Y1009419I-918J-85D01*
G03X544298Y1009114I858J-3033D01*
G02X543075Y1008998I-738J1275D01*
G02X542761Y1009154I464J1328D01*
G01X542254Y1009490D01*
Y1009531D01*
X541827Y1009958D01*
Y1011234D01*
X540810Y1012251D01*
X538921D01*
X538162Y1011492D01*
Y1010390D01*
X538537Y1010015D01*
X538953D01*
X539861Y1010391D01*
G01X551125Y1008759D02*
X545775D01*
G03X544675Y1008464I0J-2197D01*
G02X542449I-1113J1927D01*
G01X542448D01*
G03X541767Y1008660I-736J-1277D01*
G01X539502D01*
X539254Y1008908D01*
X537075D01*
X536485Y1008318D01*
Y1007962D01*
X536727Y1007720D01*
X538012Y1007187D01*
G01X540378Y1026103D02*
X538772Y1025155D01*
X537895Y1024834D01*
X537508Y1024845D01*
X536161Y1025318D01*
G01X539861Y1029617D02*
X539866D01*
X540985Y1030736D01*
G02X541252Y1030964I1508J-1495D01*
G02X544219Y1031345I1839J-2575D01*
G03X544644Y1031169I425J425D01*
G01X545039D01*
G03X545894Y1031397I1J1715D01*
G01X546149Y1031544D01*
G03X546455Y1031778I-735J1278D01*
G01X546639Y1032003D01*
X548222Y1033130D01*
X549112Y1033456D01*
G03X549884Y1033674I0J1476D01*
G03X550253Y1033997I-774J1256D01*
G01X550481Y1034225D01*
X551465D01*
X552109Y1034869D01*
G01X538012Y1026413D02*
X537608Y1026817D01*
Y1027969D01*
X538011Y1028372D01*
X538879D01*
X539566Y1027685D01*
X540366D01*
X540687Y1028006D01*
X542395D01*
X543356Y1027045D01*
X543878D01*
X544839Y1028006D01*
X549509D01*
X552617Y1031114D01*
Y1031981D01*
X553819Y1033183D01*
G01X543561Y1029617D02*
G03X544946Y1029987I0J2779D01*
G01X546524Y1030894D01*
G03X546923Y1031187I-1109J1929D01*
G03X547041Y1031305I-1513J1631D01*
G01X548790Y1032488D01*
X549551Y1032750D01*
G03X550248Y1033018I-438J2180D01*
G03X550659Y1033332I-1136J1913D01*
G01X552270D01*
X552955Y1034017D01*
G01X545412Y1026413D02*
X546868Y1027016D01*
X549773D01*
X553531Y1030774D01*
Y1031197D01*
X554704Y1032370D01*
G01X538012Y1020004D02*
X538059Y1020117D01*
X540987Y1021330D01*
X542260Y1021583D01*
X545214D01*
G02X545561Y1021534I1J-1246D01*
G02X546131Y1021294I-742J-2560D01*
G01X546154Y1021281D01*
G02X546460Y1021047I-735J-1279D01*
G01X546524Y1020983D01*
X551314D01*
X554600Y1024269D01*
X555096D01*
X555971Y1025144D01*
G01X539861Y1016800D02*
X541089Y1017309D01*
X542239Y1018459D01*
X545150D01*
G03X546136Y1018716I0J2018D01*
G01X546774Y1019219D01*
X546974Y1019419D01*
X548874D01*
X549174Y1019119D01*
X553342D01*
X557698Y1023475D01*
G01X545412Y1020004D02*
X546435Y1019993D01*
X546681Y1020234D01*
X552680D01*
X553572Y1021126D01*
Y1021930D01*
X554819Y1023177D01*
X555702D01*
X556849Y1024324D01*
G01X543561Y1016800D02*
X544833Y1017319D01*
X545640D01*
X546219Y1017898D01*
X546529Y1018077D01*
G02X547429Y1018319I900J-1553D01*
G01X549479D01*
X551314Y1017559D01*
X553480D01*
X558497Y1022576D01*
G01X539861Y1023208D02*
X540301Y1023026D01*
X541281D01*
X541788Y1023533D01*
Y1023769D01*
X542065Y1024046D01*
G03X542124Y1024078I-401J809D01*
G01X542800Y1024469D01*
X542824Y1024485D01*
G02X544298I737J-1277D01*
G03X544301Y1024487I-545J821D01*
G03X546522Y1024486I1111J1926D01*
G02X547261Y1024684I739J-1278D01*
G01X550254Y1025095D01*
X550750Y1025338D01*
X552308Y1026896D01*
X552875D01*
X553370Y1027391D01*
Y1027958D01*
X553864Y1028452D01*
X554430D01*
X554925Y1028947D01*
Y1029513D01*
X555622Y1030210D01*
X555800D01*
G01X547261Y1023208D02*
X547219Y1023166D01*
Y1022889D01*
X547617Y1022491D01*
X547982D01*
X547983Y1022490D01*
X550239D01*
X550804Y1023055D01*
Y1023622D01*
X551370Y1024188D01*
X551937D01*
X552502Y1024753D01*
Y1025320D01*
X553068Y1025886D01*
X553635D01*
X554200Y1026451D01*
Y1027018D01*
X554766Y1027584D01*
X555333D01*
X555765Y1028016D01*
Y1028583D01*
X556146Y1028964D01*
X556710D01*
X559166Y1031413D01*
X559163Y1031592D01*
X559224Y1031653D01*
G01X536161Y1023208D02*
X539539Y1024664D01*
G02X539879Y1024734I339J-788D01*
G01X540708D01*
G02X541092Y1024690I-4J-1736D01*
G03X541887Y1024811I243J1074D01*
G01X542452Y1025137D01*
X542448Y1025136D01*
X542489Y1025160D01*
G02X544675Y1025136I1072J-1952D01*
G03X546149I737J1277D01*
G02X547205Y1025433I1112J-1928D01*
G01X550032Y1025821D01*
X550308Y1025957D01*
X555092Y1030740D01*
Y1030918D01*
G01X543561Y1023208D02*
X545498Y1022468D01*
G02X546497Y1021948I-9282J-19051D01*
G01X546525Y1021932D01*
G02X546559Y1021913I-1068J-1951D01*
G03X547024Y1021760I571J954D01*
G03X547615Y1021732I593J6264D01*
G01X547983Y1021741D01*
X550550D01*
X558145Y1029336D01*
X559704Y1030890D01*
X559879Y1030892D01*
X559940Y1030953D01*
G01X538012Y1045639D02*
X537597Y1046652D01*
X537598Y1046890D01*
X537948Y1047239D01*
X542303D01*
X543016Y1046526D01*
X544388D01*
X545101Y1047239D01*
X546063D01*
X550899Y1052075D01*
G01X545412Y1045639D02*
X546691Y1046169D01*
X553098Y1052576D01*
G01X538012Y1039230D02*
X537070Y1039620D01*
X536016D01*
X535716Y1039920D01*
Y1040596D01*
X536109Y1040989D01*
X536953D01*
G02X538754Y1040507I0J-3605D01*
G01X538954Y1040390D01*
X539624Y1039720D01*
X540120D01*
X540747Y1040347D01*
X541567Y1040819D01*
X542063Y1041315D01*
X542505D01*
X542819Y1041001D01*
Y1040171D01*
X543170Y1039820D01*
X543704D01*
X544570Y1040686D01*
X545478D01*
G02X546285Y1040467I0J-1596D01*
G01X547364Y1039835D01*
X548993D01*
X550917Y1041759D01*
G01X539861Y1036026D02*
X540995Y1036496D01*
X542381Y1037882D01*
X544156D01*
X544519Y1037519D01*
X544843D01*
G03X545880Y1037798I-1J2070D01*
G01X546149Y1037953D01*
G02X547261Y1038251I1112J-1926D01*
G01X550806D01*
X554865Y1042310D01*
G01X545412Y1039230D02*
X546505Y1039241D01*
X546731Y1039019D01*
X549875D01*
X554015Y1043159D01*
G01X543561Y1036026D02*
G03X545337Y1036546I-117J3693D01*
G01X546466Y1037269D01*
G02X547261Y1037502I796J-1243D01*
G01X548588D01*
X548970Y1037120D01*
X551374D01*
X555714Y1041460D01*
G01X536161Y1042434D02*
X538560Y1041482D01*
X539303Y1041118D01*
G03X540893Y1041375I585J1426D01*
G01X542459Y1043397D01*
G02X542789Y1043691I976J-764D01*
G01X542799Y1043696D01*
X542808Y1043702D01*
X542816Y1043706D01*
X542824Y1043711D01*
G02X544298I737J-1277D01*
G03X547159Y1044039I1209J2093D01*
G01X548191Y1044592D01*
X553287Y1049688D01*
X553465D01*
X553526Y1049749D01*
G01X547261Y1042434D02*
Y1042376D01*
X547611Y1042026D01*
X548106D01*
X548562Y1042482D01*
Y1043034D01*
X548986Y1043459D01*
X549539D01*
X549963Y1043883D01*
Y1044435D01*
X550387Y1044860D01*
X550940D01*
X551361Y1045281D01*
Y1045836D01*
X551788Y1046261D01*
X552342D01*
X554378Y1048297D01*
Y1048475D01*
X554439Y1048536D01*
G01X539861Y1042434D02*
X540511Y1042261D01*
X540988Y1042738D01*
Y1043508D01*
X541533Y1044053D01*
X542033D01*
G02X542037Y1044049I-1571J-1575D01*
G02X542398Y1044330I1395J-1419D01*
G01X542399Y1044331D01*
X542444Y1044357D01*
X542450Y1044360D01*
G02X544673I1112J-1926D01*
G03X546647Y1044586I835J1444D01*
G01X546718Y1044654D01*
X547739Y1045201D01*
X548304Y1045766D01*
Y1046049D01*
X548871Y1046616D01*
X549154D01*
X549989Y1047451D01*
Y1047734D01*
X550556Y1048301D01*
X550840D01*
X552757Y1050218D01*
Y1050396D01*
X552818Y1050457D01*
G01X543561Y1042434D02*
X546881Y1041048D01*
X547999D01*
X548323Y1041182D01*
X552873Y1045731D01*
X552872D01*
X554908Y1047767D01*
X555086D01*
X555147Y1047828D01*
G01X545412Y1058455D02*
Y1058255D01*
X545788Y1057879D01*
X546957D01*
X552404Y1063331D01*
Y1065398D01*
X553440Y1066434D01*
G01X539861Y1055251D02*
X539684Y1055298D01*
X539202Y1056134D01*
X539336Y1056628D01*
G02X540598Y1056528I526J-1377D01*
G03X542824I1113J1927D01*
G02X544457Y1056443I751J-1300D01*
G01X544519Y1056381D01*
X547580D01*
X553834Y1062635D01*
X553964Y1062948D01*
Y1063556D01*
X554341Y1063933D01*
G01X538012Y1058455D02*
X537973Y1058310D01*
X538478Y1057434D01*
X538988Y1057299D01*
G02X540974Y1057178I872J-2047D01*
G03X542448I737J1277D01*
G01X542684Y1057314D01*
G02X543509Y1057535I825J-1429D01*
G01X544065D01*
X545043Y1057130D01*
X547268D01*
X553154Y1063016D01*
Y1064444D01*
X554292Y1065582D01*
G01X543561Y1055251D02*
X544481Y1055632D01*
X546379D01*
X546888Y1055123D01*
X547382D01*
X554774Y1062513D01*
Y1062667D01*
X555191Y1063084D01*
G01X539861Y1048842D02*
X539691Y1048672D01*
X538237D01*
X537890Y1049019D01*
Y1049717D01*
X538559Y1050386D01*
X544867D01*
X546584Y1050837D01*
X547845Y1052098D01*
Y1052417D01*
X549201Y1053773D01*
G01X543561Y1048842D02*
X544543Y1049029D01*
X547198Y1050072D01*
X550050Y1052924D01*
G01X536161Y1061660D02*
X538793Y1062779D01*
X538792Y1062782D01*
G03X539566Y1063281I-778J2056D01*
G03X540209Y1064399I-1750J1750D01*
G01X540210D01*
G03X540284Y1064914I-2210J580D01*
G02X540966Y1066125I1503J-49D01*
G01X540979Y1066133D01*
X540984Y1066135D01*
G02X541147Y1066215I405J-619D01*
G02X543139Y1065220I510J-1470D01*
G01X543199Y1065030D01*
Y1065028D01*
G02X543233Y1064852I-711J-229D01*
G03X545451Y1062785I2218J157D01*
G01X545886D01*
G03X546760Y1063005I2J1838D01*
G01X546777Y1063015D01*
G03X547306Y1063421I-1157J2055D01*
G01X547308Y1063423D01*
X547307D01*
G03X547898Y1064764I-1252J1352D01*
G02X548015Y1065324I1519J-25D01*
G01X548068Y1065449D01*
X548158Y1065611D01*
X548188Y1065680D01*
X548202Y1065714D01*
X549410Y1067524D01*
X550035Y1068369D01*
X550474Y1068808D01*
X550578D01*
G01X541711Y1064864D02*
X541100Y1063805D01*
X541199Y1063439D01*
G02X541265Y1063387I-1344J-1774D01*
G02X542086Y1061699I-1404J-1726D01*
G01Y1061660D01*
G03X542471Y1060732I1313J1D01*
G01X542557Y1060645D01*
G03X543547Y1060235I990J990D01*
G01X543957D01*
G03X544228Y1060302I1J579D01*
G02X545204Y1060546I977J-1833D01*
G01X546884D01*
X547921Y1060976D01*
X550488Y1063542D01*
X550897Y1064526D01*
Y1066045D01*
X551328Y1067088D01*
X551952Y1068023D01*
Y1068201D01*
X552013Y1068262D01*
G01X539861Y1061660D02*
X540472Y1062719D01*
X540791Y1062804D01*
X540792Y1062806D01*
G02X541337Y1061686I-931J-1146D01*
G01Y1061662D01*
G03Y1061635I2224J-14D01*
G03X541939Y1060203I2062J24D01*
G01X542025Y1060116D01*
G03X543548Y1059486I1520J1519D01*
G01X543958D01*
G03X544581Y1059641I0J1328D01*
G02X545205Y1059797I624J-1171D01*
G01X547034D01*
X548346Y1060340D01*
X551123Y1063117D01*
X551180Y1063254D01*
Y1063255D01*
X551646Y1064376D01*
Y1065896D01*
X551993Y1066733D01*
X552499Y1067493D01*
X552660D01*
X552721Y1067554D01*
G01X539861Y1074477D02*
X539870D01*
X541300Y1075907D01*
X542420D01*
X543270Y1076757D01*
X543705D01*
X545707Y1075928D01*
X546281D01*
X551479Y1078081D01*
X553836Y1080438D01*
G01X539861Y1068068D02*
X538825Y1068497D01*
X538359Y1068963D01*
Y1069457D01*
X539460Y1070558D01*
X540038D01*
X541026Y1069570D01*
X543216D01*
X543753Y1070107D01*
Y1071620D01*
X544225Y1072092D01*
X545021Y1072682D01*
X545675Y1073096D01*
X547298Y1073769D01*
X548970D01*
X551690Y1074896D01*
X551985Y1075191D01*
G01X541711Y1071273D02*
X542776Y1072211D01*
X547508Y1075349D01*
X552520Y1077424D01*
X554685Y1079589D01*
G01X545412Y1064864D02*
X545616D01*
X546497Y1065745D01*
X547011Y1066986D01*
X546920Y1067206D01*
X547307Y1068139D01*
X548531Y1069363D01*
X548622Y1069582D01*
X548697Y1069830D01*
X548736Y1070025D01*
Y1070242D01*
X556384Y1077890D01*
G01X536161Y1080885D02*
G02X536228Y1080867I0J-133D01*
G01X538936Y1079283D01*
G03X540786I925J1602D01*
G02X542636I925J-1602D01*
G03X544486I925J1602D01*
G02X544522Y1079297I60J-102D01*
G01X544969Y1079386D01*
X548036D01*
X550717Y1082067D01*
Y1082409D01*
X551641Y1083333D01*
G01X545412Y1077681D02*
X547379D01*
X547912Y1077902D01*
X552492Y1082482D01*
G01X538012Y1064864D02*
X537401Y1063805D01*
X537487Y1063487D01*
G03X537985Y1063390I527J1377D01*
G03X538527Y1063483I31J1448D01*
G03X539036Y1063812I-514J1354D01*
G03X539485Y1064591I-1219J1221D01*
G03X539535Y1064937I-1485J391D01*
G02X540556Y1066752I2252J-72D01*
G01X540575Y1066764D01*
G02X540903Y1066924I812J-1249D01*
G02X543853Y1065448I754J-2179D01*
G01Y1065447D01*
X543913Y1065257D01*
G02X543981Y1064905I-1425J-458D01*
G03X545451Y1063534I1470J103D01*
G01X545886D01*
G03X546402Y1063664I0J1088D01*
G01X546413Y1063670D01*
G03X546772Y1063948I-795J1398D01*
G01X546781Y1063957D01*
G03X546789Y1063965I-1040J1048D01*
G03X547149Y1064772I-734J811D01*
G02X547324Y1065613I2268J-33D01*
G01X547392Y1065775D01*
X547481Y1065935D01*
Y1065937D01*
X547483Y1065939D01*
X547539Y1066071D01*
X548797Y1067955D01*
X549465Y1068860D01*
X549784Y1069179D01*
X549890Y1069435D01*
Y1069536D01*
G01X539861Y1093703D02*
X540237Y1094611D01*
Y1096941D01*
G02X540974Y1098184I1474J-34D01*
G02X542448I737J-1277D01*
G01X542489Y1098160D01*
G03X544675Y1098184I1072J1951D01*
G01X544708Y1098217D01*
X545481Y1098537D01*
X546203D01*
X547542Y1099092D01*
X548601Y1100151D01*
X549754Y1102933D01*
X550144Y1104892D01*
Y1106549D01*
G01X545412Y1090498D02*
X545769Y1090559D01*
X548618Y1094582D01*
X549355Y1096352D01*
X549634Y1097933D01*
Y1098742D01*
X550774Y1102499D01*
X551344Y1105351D01*
Y1106549D01*
G01X538012Y1084090D02*
G03X540146Y1082708I4299J4300D01*
G01X541053Y1082362D01*
G03X542636Y1082488I659J1729D01*
G02X543995Y1082685I926J-1602D01*
G01X546758Y1081518D01*
X547891D01*
X548519Y1082146D01*
X549431Y1084346D01*
X549818Y1084926D01*
X550884Y1085992D01*
G01X543561Y1080885D02*
X544810Y1080368D01*
X547813D01*
X549445Y1082000D01*
X550044Y1083446D01*
X551737Y1085139D01*
G01X543561Y1087294D02*
X543159Y1087402D01*
X542842Y1087952D01*
X543036Y1088671D01*
G02X544298Y1088571I526J-1377D01*
G03X545281Y1088276I1114J1927D01*
G03X545408Y1088273I116J2222D01*
G03X545410I1J2224D01*
G01X546260D01*
X547466Y1088773D01*
Y1088774D01*
X548267Y1089575D01*
Y1090361D01*
X549009Y1091103D01*
X549187D01*
X549248Y1091164D01*
G01X539861Y1087294D02*
X543083Y1085918D01*
G03X543974Y1085898I470J1100D01*
G01X546048Y1086679D01*
X547538Y1087297D01*
X549640Y1088421D01*
X550471Y1089252D01*
Y1089428D01*
X550532Y1089489D01*
G01X541711Y1090498D02*
X541610Y1090121D01*
X541946Y1089539D01*
X542687Y1089342D01*
G02X542768Y1089375I880J-2045D01*
G02X544675Y1089221I792J-2080D01*
G03X545326Y1089025I739J1276D01*
G03X545412Y1089022I94J1472D01*
G01X546110D01*
X547041Y1089409D01*
X547518Y1089886D01*
Y1090672D01*
X548479Y1091633D01*
Y1091811D01*
X548540Y1091872D01*
G01X541711Y1084090D02*
X543532Y1085044D01*
X543643Y1085074D01*
G03X544238Y1085196I-88J1943D01*
G01X546310Y1085976D01*
Y1085977D01*
X546320Y1085981D01*
X546319Y1085980D01*
X546335Y1085987D01*
X547859Y1086619D01*
X550092Y1087813D01*
X550999Y1088720D01*
X551179D01*
X551240Y1088781D01*
G01X538012Y1096907D02*
G02X540348Y1098691I7828J-7829D01*
G01X540633Y1098854D01*
G03X541336Y1100111I-772J1257D01*
G01Y1100184D01*
G02X542448Y1102039I2225J-73D01*
G01X542489Y1102063D01*
G02X544545Y1102109I1072J-1952D01*
G03X545528Y1101880I984J1997D01*
G01X546346D01*
G03X546660Y1102010I0J444D01*
G01X547259Y1102609D01*
X547744Y1103779D01*
Y1106549D01*
G01X543561Y1100111D02*
X546253Y1100403D01*
X548218Y1102368D01*
X548944Y1104120D01*
Y1106549D01*
G01X1306366Y962754D02*
X1307673D01*
X1307991Y962436D01*
X1312070D01*
G01X1306099Y1022319D02*
X1307013D01*
X1307712Y1021620D01*
X1311040D01*
X1312656Y1020004D01*
X1314353D01*
G01X1312070Y866307D02*
X1311042Y865285D01*
X1310260D01*
X1308346Y863371D01*
G01X1313921Y863103D02*
X1310716Y862333D01*
X1310050Y861667D01*
G01X1310221Y869511D02*
X1309868Y869864D01*
X1309174D01*
X1308716Y869406D01*
X1308553Y869011D01*
X1307956Y868413D01*
Y867912D01*
X1307408Y867364D01*
X1306905D01*
X1305079Y865538D01*
Y865360D01*
X1305018Y865299D01*
G01X1312070Y872716D02*
X1307485Y872720D01*
X1306691Y871926D01*
G01X1313921Y869511D02*
X1313767Y869449D01*
X1310776Y870720D01*
X1310572Y870839D01*
X1309331D01*
X1308919Y870669D01*
X1308080Y869830D01*
X1307917Y869435D01*
X1307425Y868943D01*
X1307424D01*
X1304549Y866068D01*
X1304371D01*
X1304310Y866007D01*
G01X1312070Y904759D02*
X1311909Y904920D01*
X1307876D01*
X1306194Y904223D01*
X1304794Y902823D01*
G01X1313921Y901555D02*
X1311799Y900723D01*
X1310608Y900134D01*
X1309510Y899565D01*
X1307665D01*
G01X1313921Y875920D02*
X1312423Y875519D01*
X1311962Y875253D01*
X1311388Y874921D01*
X1310546Y874627D01*
X1310274Y874573D01*
X1309602Y874595D01*
X1307854Y875151D01*
G03X1307416Y875219I-440J-1386D01*
G01X1306588D01*
X1304993Y873624D01*
G01X1304965Y911805D02*
X1307274D01*
X1307912Y911167D01*
X1312070D01*
G01X1310221Y907963D02*
Y908272D01*
X1309866Y908627D01*
X1308334D01*
X1307991Y908284D01*
X1306796D01*
X1306670Y908158D01*
X1306583D01*
G01X1313921Y907963D02*
X1311154Y909110D01*
X1310704Y909370D01*
X1309872Y909376D01*
X1308023D01*
X1307680Y909033D01*
X1306795D01*
X1306670Y909158D01*
X1306583D01*
G01X1313921Y920780D02*
X1311756Y919966D01*
X1310953Y919503D01*
G02X1310216Y919305I-738J1277D01*
G01X1309621Y919249D01*
X1307591D01*
X1306929Y919419D01*
X1306666D01*
G01X1313921Y914372D02*
X1312181Y913812D01*
X1310958Y913095D01*
G02X1310221Y912898I-736J1277D01*
G01X1308812D01*
X1307306Y914404D01*
X1304966D01*
G01X1312070Y923985D02*
X1311935Y924120D01*
X1307311D01*
X1306322Y923131D01*
X1304966D01*
G01X1310221Y927189D02*
Y927447D01*
X1309803Y927865D01*
X1307624D01*
X1306896Y927137D01*
X1304978D01*
X1304853Y927012D01*
X1304766D01*
G01X1313921Y927189D02*
X1312497Y927571D01*
X1310930Y928479D01*
G03X1310428Y928614I-502J-864D01*
G01X1307313D01*
X1306585Y927886D01*
X1304979D01*
X1304853Y928012D01*
X1304766D01*
G01X1313921Y933598D02*
G03X1312398Y933190I-2J-3041D01*
G01X1310896Y932322D01*
G02X1309732Y932019I-1164J2083D01*
G01X1307061D01*
X1306071Y933009D01*
X1304966D01*
G01Y930609D02*
X1305871D01*
X1306087Y930393D01*
X1312070D01*
G01Y943210D02*
X1311928Y943352D01*
X1307216D01*
X1305591Y941727D01*
G01X1313921Y940006D02*
X1315144D01*
X1315377Y939773D01*
G02X1314693Y938749I-1457J232D01*
G02X1313921Y938531I-772J1258D01*
G02X1313184Y938728I-1J1475D01*
G03X1313163Y938739I-132J-226D01*
G03X1311020Y938763I-1093J-1937D01*
G03X1310496Y938376I1046J-1964D01*
G01X1309934Y937813D01*
X1307666D01*
G01X1312070Y949619D02*
X1308341Y949655D01*
X1307609D01*
X1307238Y949284D01*
X1304004D01*
X1303401Y949887D01*
G01X1310221Y946414D02*
G03X1309864Y946562I-357J-357D01*
G01X1308019D01*
X1307634Y946485D01*
X1306542Y946034D01*
X1305352Y946035D01*
X1304290Y945595D01*
X1302878D01*
X1302753Y945470D01*
X1302666D01*
G01Y946470D02*
X1302753D01*
X1302879Y946344D01*
X1304138D01*
X1305203Y946785D01*
X1306394Y946784D01*
X1307416Y947206D01*
X1307945Y947311D01*
X1308800D01*
X1309148Y947659D01*
G02X1309479Y947796I331J-331D01*
G01X1309501Y947802D01*
G02X1310072Y947835I365J-1361D01*
G01X1310551Y947764D01*
G02X1311084Y947614I-320J-2158D01*
G01X1311118Y947599D01*
G02X1311771Y947159I-806J-1901D01*
G03X1313570Y946414I1799J1799D01*
G01X1313921D01*
G01Y952823D02*
G03X1312502Y952441I1J-2829D01*
G01X1311128Y951644D01*
G02X1310579Y951497I-549J951D01*
G01X1305189D01*
X1304950Y951736D01*
G01X1313921Y959232D02*
X1312908Y960245D01*
X1311280D01*
X1310358Y960627D01*
X1308512D01*
X1307590Y960245D01*
X1306366D01*
G01X1312070Y968845D02*
X1310414Y969174D01*
X1306366D01*
G01X1310221Y965640D02*
X1309251Y966610D01*
X1307366D01*
G01X1319470Y962436D02*
G02X1318072Y962810I-1J2797D01*
G01X1316508Y963713D01*
G03X1315034I-737J-1277D01*
G01X1314993Y963689D01*
G02X1312807Y963713I-1072J1951D01*
G03X1311333I-737J-1277D01*
G02X1311041Y963561I-1843J3184D01*
G01X1310927Y963447D01*
X1309203D01*
X1307806Y964026D01*
X1307366D01*
G01X1317621Y978457D02*
G03X1316223Y978083I0J-2799D01*
G01X1314657Y977180D01*
G02X1312942Y977406I-710J1230D01*
G01X1312459Y977889D01*
Y979217D01*
X1310097Y981579D01*
X1306467D01*
G01X1313921Y972049D02*
X1311073Y973259D01*
X1310525Y973578D01*
X1309303Y974800D01*
X1307492D01*
X1306603Y975689D01*
G01X1312070Y981662D02*
X1312681Y980603D01*
X1313000Y980518D01*
G03X1313545Y981662I-930J1145D01*
G01X1313546Y981663D01*
G03X1312730Y983069I-1621J-1D01*
G01X1312474Y983198D01*
G03X1311556Y983415I-919J-1838D01*
G01X1310589D01*
G02X1309611Y983820I1J1385D01*
G01X1308666Y984765D01*
X1307147D01*
X1306877Y984495D01*
X1306767D01*
G01X1313921Y978457D02*
X1313310Y979516D01*
X1313409Y979882D01*
G03X1313475Y979934I-1345J1775D01*
G03X1314296Y981606I-1405J1727D01*
G01Y981662D01*
X1314295D01*
G03X1313083Y983731I-2371J1D01*
G01X1312809Y983868D01*
G03X1311555Y984164I-1254J-2508D01*
G01X1310590D01*
G02X1310141Y984350I0J635D01*
G01X1308977Y985514D01*
X1307148D01*
X1306877Y985785D01*
X1306767D01*
G01X1314353Y1000778D02*
X1312361Y999819D01*
X1309459D01*
X1304447Y1004831D01*
G01X1318054Y1000778D02*
X1316395Y999119D01*
X1313561D01*
X1312461Y998619D01*
X1308961D01*
X1303598Y1003982D01*
G01X1308367Y1010891D02*
X1310881D01*
X1311381Y1010391D01*
X1312503D01*
G01X1314353Y1007187D02*
G03X1312960Y1006814I1J-2790D01*
G01X1310598Y1005453D01*
X1310202Y1005057D01*
X1309070Y1004588D01*
X1308086D01*
X1305995Y1006679D01*
G01X1312503Y1016800D02*
X1311402Y1015699D01*
X1305465D01*
X1305313Y1015851D01*
G01X1318054Y1020004D02*
X1317410Y1019360D01*
X1316172D01*
X1315090Y1018727D01*
G02X1313616I-737J1277D01*
G03X1311432Y1018751I-1113J-1927D01*
G01X1310981Y1018487D01*
X1309833Y1017339D01*
X1307221D01*
X1305938Y1018622D01*
G01X1301768Y1029798D02*
X1303226D01*
X1303663Y1030235D01*
X1304459D01*
X1304896Y1029798D01*
X1305675D01*
X1306304Y1030427D01*
X1308176D01*
X1308986Y1029617D01*
X1312503D01*
G01X1314353Y1026413D02*
Y1026412D01*
X1312942Y1026790D01*
X1310827Y1028013D01*
X1307410D01*
X1306793Y1027396D01*
X1304467D01*
G01X1301286Y1038072D02*
X1301529Y1037829D01*
X1306523D01*
X1309844Y1036026D01*
X1312503D01*
G01X1310654Y1032821D02*
X1309961Y1033514D01*
X1308274Y1034213D01*
X1307514D01*
X1307164Y1033863D01*
X1306375D01*
X1306025Y1034213D01*
X1304869D01*
X1304519Y1033863D01*
X1303730D01*
X1303380Y1034213D01*
X1302080D01*
X1301955Y1034088D01*
X1301868D01*
G01X1314353Y1032821D02*
X1311501Y1034003D01*
X1310488Y1034205D01*
X1310253D01*
X1308424Y1034962D01*
X1302081D01*
X1301955Y1035088D01*
X1301868D01*
G01X1314353Y1039230D02*
X1312048Y1038338D01*
X1311373Y1037948D01*
G02X1310615Y1037744I-759J1311D01*
G02X1309874Y1037902I-2J1809D01*
G01X1309234Y1038246D01*
X1307301Y1040179D01*
X1302576D01*
X1301655Y1041100D01*
G01X1304454Y1052638D02*
X1306008Y1051084D01*
X1306385D01*
X1307125Y1050344D01*
Y1049989D01*
X1308198Y1048916D01*
X1308692D01*
X1308969Y1049193D01*
X1309833D01*
X1310314Y1048712D01*
X1310960D01*
X1311090Y1048842D01*
X1312503D01*
G01X1314353Y1045639D02*
X1313502Y1044788D01*
X1312393D01*
X1311981Y1045200D01*
Y1046575D01*
X1311391Y1046915D01*
G03X1310629Y1047124I-782J-1357D01*
G01X1309264D01*
X1307785Y1045645D01*
X1307373Y1045474D01*
X1306468D01*
G01X1305851Y1061435D02*
X1312035Y1055251D01*
X1312503D01*
G01X1310654Y1052047D02*
X1310042Y1053101D01*
X1309825Y1053318D01*
Y1053320D01*
X1309416Y1053729D01*
X1308865D01*
X1308157Y1054437D01*
Y1054988D01*
X1307532Y1055613D01*
X1306981D01*
X1306273Y1056321D01*
Y1056872D01*
X1306136Y1057009D01*
X1305044Y1057462D01*
X1302860Y1059647D01*
X1302684D01*
X1302623Y1059708D01*
G01X1314353Y1052047D02*
X1312507Y1052559D01*
X1310355Y1053850D01*
X1306561Y1057645D01*
X1305469Y1058098D01*
X1303392Y1060175D01*
Y1060355D01*
X1303331Y1060416D01*
G01X1314353Y1064864D02*
X1313320Y1063831D01*
X1312305D01*
X1310472Y1065664D01*
X1310213D01*
X1309347Y1066530D01*
X1309346D01*
G01X1314353Y1058455D02*
X1312759Y1060049D01*
X1310633D01*
X1307549Y1063133D01*
G01X1304096Y1075180D02*
X1304162Y1075115D01*
X1304182Y1075096D01*
X1309846Y1069432D01*
X1310531D01*
X1310845Y1069118D01*
Y1068427D01*
X1311204Y1068068D01*
X1312503D01*
G01Y1074477D02*
X1311834Y1073808D01*
X1311129D01*
X1310145Y1074792D01*
X1309497D01*
X1308519Y1075197D01*
X1307876Y1075841D01*
X1306272Y1078240D01*
X1305457Y1079233D01*
X1304902Y1079788D01*
X1304726D01*
X1304665Y1079849D01*
G01X1314353Y1071273D02*
X1314028Y1072058D01*
Y1074008D01*
G03X1313449Y1075449I-2078J2D01*
G03X1312605Y1075807I-844J-815D01*
G01X1311329D01*
X1310702Y1075548D01*
X1310687Y1075541D01*
X1309647D01*
X1309295Y1075687D01*
X1308944Y1075832D01*
X1308459Y1076319D01*
X1306875Y1078687D01*
X1306013Y1079737D01*
X1305434Y1080316D01*
Y1080496D01*
X1305373Y1080557D01*
G01X1312503Y1080885D02*
X1311006Y1081872D01*
X1309197Y1083681D01*
G01X1318054Y1077681D02*
G03X1316795Y1078535I-2859J-2859D01*
G01X1315551Y1079071D01*
G03X1313616Y1078958I-855J-1985D01*
G02X1313067Y1078811I-549J951D01*
G01X1311583D01*
X1310873Y1079105D01*
X1308975Y1081003D01*
X1308126Y1081355D01*
X1307499Y1081982D01*
G01X1305241Y1096824D02*
X1306596Y1095469D01*
X1306706D01*
X1308818Y1093357D01*
Y1092798D01*
X1311118Y1090498D01*
X1314353D01*
G01X1316203Y1087294D02*
X1316142Y1087355D01*
G03X1314349Y1088208I-7213J-12851D01*
G03X1314011Y1088298I-571J-1466D01*
G02X1313381Y1088495I342J2199D01*
G03X1312410Y1088719I-973J-2001D01*
G01X1311108D01*
G02X1310712Y1088808I-4J908D01*
G02X1310627Y1088869I137J281D01*
G01X1307288Y1092208D01*
Y1092739D01*
X1306185Y1093842D01*
X1304746D01*
X1303502Y1095086D01*
G01X1312503Y1100111D02*
X1311937Y1100677D01*
Y1101427D01*
G01X1312503Y1093703D02*
X1313727D01*
X1313959Y1093935D01*
G03X1313321Y1094930I-1456J-232D01*
G03X1312986Y1095031I-334J-501D01*
G01X1310462D01*
X1309671Y1095822D01*
X1309256Y1096830D01*
Y1097893D01*
X1308892Y1098767D01*
X1307888Y1099771D01*
X1307710D01*
X1307649Y1099832D01*
G01X1308357Y1100540D02*
X1308418Y1100479D01*
Y1100301D01*
X1309527Y1099192D01*
X1310005Y1098043D01*
Y1096979D01*
X1310307Y1096246D01*
X1310773Y1095780D01*
X1312985D01*
G02X1313737Y1095553I2J-1351D01*
G02X1314701Y1094055I-1233J-1853D01*
G02X1314713Y1093969I-2198J-350D01*
G01X1314979Y1093703D01*
X1316203D01*
G01X1317621Y863103D02*
X1316173Y862716D01*
X1314089Y861512D01*
G02X1313554Y861368I-536J926D01*
G01X1311449D01*
X1310899Y860818D01*
G01X1319470Y866307D02*
X1320338Y866303D01*
X1320609Y866029D01*
X1320602Y865066D01*
X1320085Y864549D01*
X1312300D01*
X1311596Y863845D01*
X1310526D01*
X1309296Y862615D01*
X1309288D01*
X1309195Y862522D01*
G01X1321321Y869511D02*
G02X1319859Y869908I0J2890D01*
G01X1318358Y870788D01*
G03X1316884I-737J-1277D01*
G03X1316165Y869749I738J-1279D01*
G01X1316139Y869399D01*
X1315840Y868816D01*
X1314697Y868244D01*
G02X1314360Y868164I-338J672D01*
G01X1313306D01*
G02X1312968Y868237I0J817D01*
G01X1312569Y868419D01*
G03X1311897Y868548I-599J-1304D01*
G03X1311152Y868339I116J-1845D01*
G01X1311120Y868322D01*
X1311110Y868317D01*
X1311103Y868313D01*
X1311100Y868311D01*
X1311091Y868307D01*
X1311088Y868305D01*
X1311087D01*
X1311079Y868301D01*
X1311069Y868295D01*
X1310991Y868252D01*
X1310980Y868246D01*
G03X1310497Y867880I1090J-1940D01*
G01X1310200Y867583D01*
X1309472Y867584D01*
X1306952Y865064D01*
X1306774D01*
X1306713Y865003D01*
G01X1307421Y864295D02*
X1307482Y864356D01*
Y864534D01*
X1309782Y866834D01*
X1310510Y866833D01*
X1311027Y867350D01*
G02X1311333Y867585I1044J-1043D01*
G01X1311343Y867590D01*
X1311346Y867592D01*
X1311436Y867640D01*
X1311439Y867642D01*
X1311444Y867644D01*
X1311462Y867654D01*
X1311465Y867655D01*
X1311468Y867657D01*
Y867658D01*
X1311471Y867660D01*
X1311503Y867677D01*
G02X1311913Y867797I508J-975D01*
G02X1312258Y867737I59J-683D01*
G01X1312682Y867544D01*
G03X1313306Y867415I622J1437D01*
G01X1314361D01*
G03X1315033Y867574I0J1501D01*
G01X1316395Y868256D01*
X1316861Y869164D01*
X1317208Y869511D01*
X1317621D01*
G01Y875920D02*
X1316920Y875225D01*
X1315487D01*
X1314624Y874362D01*
Y873859D01*
X1314270Y873505D01*
X1313768D01*
X1313285Y873988D01*
Y874171D01*
X1312924Y874532D01*
X1312309D01*
G03X1312134Y874485I0J-349D01*
G01X1311387Y874054D01*
X1310247Y873788D01*
X1309261Y873733D01*
X1307475Y873991D01*
G03X1306593Y873526I311J-1659D01*
G01X1305842Y872775D01*
G01X1319470Y872716D02*
X1319594Y872592D01*
X1320467D01*
X1321211Y871848D01*
Y871288D01*
X1320845Y870922D01*
X1320058D01*
X1318420Y871602D01*
X1317958Y872064D01*
X1317539D01*
X1316464Y871442D01*
G02X1315961Y871263I-738J1277D01*
G01X1315703Y871005D01*
X1314815D01*
X1314381Y871439D01*
X1312807D01*
G02X1311072I-867J1503D01*
G01X1310569Y871729D01*
G03X1310235Y871819I-335J-578D01*
G01X1308282D01*
X1307540Y871077D01*
G01X1319470Y904759D02*
X1316696Y903157D01*
G02X1314846I-925J1602D01*
G03X1312996I-925J-1602D01*
G02X1311760Y902934I-927J1602D01*
G01X1311674Y902979D01*
X1310937Y903716D01*
G03X1310521Y903887I-416J-420D01*
G01X1310245D01*
X1310002Y904130D01*
X1308019D01*
X1307002Y903709D01*
X1306312Y903019D01*
Y902642D01*
X1305644Y901974D01*
G01X1317621Y901555D02*
G03X1315501Y900469I624J-3830D01*
G01X1314901Y899887D01*
G02X1313997Y899693I-607J624D01*
G01X1313211Y899979D01*
G03X1312192Y899985I-518J-1424D01*
G01X1311861Y899869D01*
X1311238Y899541D01*
X1309970Y898325D01*
X1307665D01*
G01X1319470Y911167D02*
X1319878Y910759D01*
X1321369D01*
X1321558Y910570D01*
Y909806D01*
X1321213Y909461D01*
X1320314D01*
G02X1318731Y909890I0J3135D01*
G01X1318690Y909914D01*
G03X1316506Y909890I-1071J-1951D01*
G02X1315346Y909579I-1160J2009D01*
G01X1314801D01*
X1314114Y910266D01*
X1313618D01*
X1312931Y909579D01*
X1312509D01*
G02X1311357Y909877I0J2377D01*
G01X1310556Y910321D01*
X1307512D01*
X1307229Y910604D01*
X1304965D01*
G01X1321321Y907963D02*
G02X1319859Y908360I0J2890D01*
G01X1318358Y909240D01*
G03X1316884I-737J-1277D01*
G01X1316883Y909239D01*
G03X1316165Y908201I736J-1276D01*
G01X1316142Y907891D01*
X1316143D01*
X1316138Y907835D01*
X1315856Y907281D01*
X1314655Y906681D01*
X1314652Y906680D01*
X1314645Y906676D01*
X1314632Y906669D01*
G02X1313183Y906685I-710J1294D01*
G01X1313184Y906686D01*
G03X1311016Y906720I-1114J-1927D01*
G01X1310958Y906686D01*
G02X1310315Y906490I-740J1276D01*
G02X1310221Y906487I-94J1472D01*
G01X1309212D01*
X1309084Y906615D01*
X1306796D01*
X1306670Y906741D01*
X1306583D01*
G01Y905741D02*
X1306670D01*
X1306795Y905866D01*
X1308773D01*
X1308901Y905738D01*
X1310222D01*
G03X1310365Y905742I9J2225D01*
G03X1311333Y906036I-146J2220D01*
G02X1312807I737J-1277D01*
G03X1314988Y906009I1115J1927D01*
G01X1314990Y906011D01*
X1316411Y906721D01*
X1316876Y907631D01*
X1317208Y907963D01*
X1317621D01*
G01X1319470Y923985D02*
G02X1319458Y923976I-40J41D01*
G01X1316696Y922382D01*
G02X1314846I-925J1603D01*
G03X1312996I-925J-1602D01*
G02X1311199Y922351I-926J1603D01*
G01X1310191Y923359D01*
X1307725D01*
X1306297Y921931D01*
X1304966D01*
G01X1317621Y920780D02*
G03X1315923Y920079I-6J-2393D01*
G01X1314888Y919044D01*
G02X1313286I-801J801D01*
G01X1313135Y919195D01*
G03X1312884Y919299I-251J-251D01*
G01X1312815D01*
G03X1311510Y918956I-1J-2652D01*
G01X1311328Y918853D01*
G02X1310522Y918576I-1113J1927D01*
G01X1309441Y918436D01*
X1308714D01*
X1308097Y917819D01*
X1307066D01*
G01X1317621Y914372D02*
X1316614Y913365D01*
X1316135D01*
X1315886Y913614D01*
X1315180D01*
X1314604Y913038D01*
Y912343D01*
X1314184Y911923D01*
X1313592D01*
X1312870Y912645D01*
X1312086D01*
G03X1311333Y912444I0J-1510D01*
G03X1311027Y912210I735J-1278D01*
G01X1310748Y911931D01*
X1308612D01*
X1307514Y913029D01*
X1304965D01*
G01X1319470Y930393D02*
X1320081Y929334D01*
X1319965Y928906D01*
G02X1319450Y928695I-338J91D01*
G01X1318735Y929114D01*
G03X1318723Y929121I-1127J-1918D01*
G02X1318718Y929124I756J1266D01*
G03X1318694Y929138I-1133J-1914D01*
G01X1318690Y929141D01*
G03X1316508Y929116I-1069J-1952D01*
G01X1315949Y928793D01*
X1312846D01*
X1312830Y928809D01*
X1312301D01*
G02X1311476Y929031I1J1648D01*
G01X1311328Y929116D01*
G03X1310782Y929363I-1506J-2603D01*
G03X1310641Y929400I-345J-1029D01*
G03X1310544Y929409I-96J-508D01*
G01X1304966D01*
G01X1321321Y927189D02*
G02X1319859Y927586I0J2890D01*
G01X1318358Y928466D01*
G03X1316884I-737J-1277D01*
G03X1316165Y927427I738J-1279D01*
G01X1316142Y927117D01*
X1316143D01*
X1316138Y927061D01*
X1315856Y926507D01*
X1314655Y925907D01*
X1314652Y925906D01*
X1314645Y925902D01*
X1314632Y925895D01*
G02X1313183Y925911I-710J1294D01*
G01X1313184Y925912D01*
G03X1313100Y925958I-1111J-1929D01*
G03X1311016Y925946I-1031J-1973D01*
G01X1310958Y925912D01*
G02X1310315Y925716I-740J1276D01*
G02X1310222Y925713I-94J1472D01*
G01X1306745D01*
X1306394Y925362D01*
X1304979D01*
X1304853Y925488D01*
X1304766D01*
G01Y924488D02*
X1304853D01*
X1304978Y924613D01*
X1306705D01*
X1307056Y924964D01*
X1310223D01*
G03X1310364Y924968I7J2225D01*
G03X1311336Y925264I-145J2220D01*
G01X1311382Y925292D01*
G02X1312753Y925294I687J-1307D01*
G01X1312808Y925262D01*
G03X1314992Y925237I1114J1927D01*
G01X1316412Y925947D01*
X1316806Y926720D01*
X1316876Y926857D01*
X1317208Y927189D01*
X1317621D01*
G01Y933598D02*
X1314846Y931996D01*
G02X1312996I-925J1602D01*
G01X1312460D01*
G03X1311288Y931682I0J-2345D01*
G02X1309560Y931219I-1728J2994D01*
G01X1306662D01*
X1306072Y931809D01*
X1304966D01*
G01X1319470Y943210D02*
X1316696Y941608D01*
G02X1314846I-925J1602D01*
G03X1312996I-925J-1602D01*
G02X1310678Y941913I-961J1661D01*
G01X1309988Y942603D01*
X1307623D01*
X1307153Y942133D01*
X1306765Y941197D01*
X1306443Y940875D01*
G01X1307666Y936612D02*
X1309793D01*
X1311026Y937845D01*
G02X1311333Y938079I1040J-1047D01*
G02X1312807I737J-1277D01*
G03X1314993Y938055I1114J1927D01*
G01X1315034Y938079D01*
G03X1316131Y939739I-1112J1927D01*
G01X1316398Y940006D01*
X1317621D01*
G01X1304182Y942490D02*
X1304243Y942551D01*
Y942727D01*
X1304896Y943381D01*
X1305514D01*
X1306111Y943977D01*
G02X1307297Y944189I1189J-3229D01*
G01X1310222D01*
G03X1311333Y944488I-3J2224D01*
G01Y944487D01*
G02X1312807I737J-1277D01*
G03X1314988Y944460I1115J1927D01*
G01X1314990Y944462D01*
X1316411Y945172D01*
X1316876Y946082D01*
X1317208Y946414D01*
X1317621D01*
G01Y952823D02*
X1315033Y951751D01*
X1314561Y951279D01*
Y950520D01*
X1314211Y950170D01*
X1313618D01*
X1313261Y950527D01*
Y950969D01*
X1312911Y951319D01*
X1312538D01*
X1311333Y950896D01*
G02X1310365Y950602I-1305J2556D01*
G01X1310310Y950547D01*
X1304440D01*
X1304251Y950736D01*
G01X1319470Y949619D02*
X1320296D01*
X1320819Y949096D01*
Y948403D01*
X1320515Y948099D01*
X1319336D01*
G02X1318984Y948194I0J699D01*
G01X1318735Y948339D01*
G03X1318698Y948360I-1116J-1924D01*
G01X1318282Y948591D01*
G03X1316508Y948342I-722J-1301D01*
G01X1316244Y948190D01*
G02X1315642Y948029I-602J1046D01*
G01X1312130D01*
G02X1311826Y948098I0J706D01*
G01X1311288Y948355D01*
G03X1310176Y948654I-1114J-1926D01*
G01X1308178D01*
X1307898Y948374D01*
X1303216D01*
X1302845Y948745D01*
G01X1321321Y946414D02*
G02X1319859Y946811I0J2890D01*
G01X1318358Y947691D01*
G03X1316884I-737J-1277D01*
G01Y947690D01*
G03X1316146Y946414I736J-1277D01*
G01X1316138Y946286D01*
X1315856Y945732D01*
X1314655Y945132D01*
X1314652Y945131D01*
X1314645Y945127D01*
X1314632Y945120D01*
G02X1313183Y945136I-710J1294D01*
G01X1313184Y945137D01*
G03X1311016Y945171I-1114J-1927D01*
G01X1310958Y945137D01*
G02X1310221Y944938I-740J1276D01*
G01X1307296D01*
G03X1305692Y944618I2J-4190D01*
G01X1305204Y944130D01*
X1304585D01*
X1303714Y943259D01*
X1303536D01*
X1303475Y943198D01*
G01X1317621Y959232D02*
X1315844Y961009D01*
X1311564D01*
X1310615Y961402D01*
X1307612D01*
X1307466Y961548D01*
X1306366D01*
G01X1319470Y968845D02*
X1317986Y970329D01*
X1315807D01*
G03X1315034Y970122I0J-1547D01*
G01X1314356Y969730D01*
G03X1313995Y969105I362J-626D01*
G02X1313105Y967566I-1776J0D01*
G01X1312985Y967497D01*
G02X1311202Y967506I-884J1542D01*
G01X1310928Y967655D01*
G03X1310215Y967834I-713J-1330D01*
G01X1310202Y967821D01*
X1307366D01*
G01X1321321Y965640D02*
X1320318Y964637D01*
G02X1318851Y964029I-1467J1466D01*
G01X1317891D01*
G02X1317093Y964243I1J1598D01*
G01X1316232Y964739D01*
G03X1315310I-461J-798D01*
G01X1314658Y964363D01*
G02X1313184I-737J1277D01*
G01X1312524Y964745D01*
G03X1311687Y964758I-430J-744D01*
G01X1310958Y964363D01*
G02X1310645Y964279I-313J540D01*
G01X1309643D01*
X1309028Y964534D01*
X1308208Y965354D01*
X1307366D01*
G01X1319470Y981662D02*
Y978220D01*
X1318209Y976959D01*
X1316636D01*
G03X1315034Y976530I0J-3204D01*
G01X1314993Y976506D01*
G02X1312807Y976530I-1072J1951D01*
G03X1312120Y976828I-1642J-2845D01*
G01X1311676Y977272D01*
Y978934D01*
X1310232Y980378D01*
X1305867D01*
G01X1317621Y972049D02*
X1314768Y970836D01*
X1314474Y970666D01*
G02X1313001I-737J1275D01*
G01X1312698Y970840D01*
G03X1311514Y971001I-789J-1372D01*
G01X1311057Y970544D01*
X1306724D01*
X1306491Y970777D01*
G01X1306767Y988554D02*
X1306877D01*
X1307147Y988824D01*
X1313528D01*
X1315119Y987232D01*
X1315397Y986564D01*
Y984866D01*
G03X1316456Y982971I2225J0D01*
G03X1316509Y982939I1177J1889D01*
G03X1318692Y982915I1113J1927D01*
G01X1318733Y982939D01*
X1318736Y982941D01*
X1318757Y982953D01*
G03X1319818Y984516I-1136J1913D01*
G03X1319830Y984599I-2196J360D01*
G01X1320097Y984866D01*
X1321321D01*
G01X1317621D02*
X1318845D01*
X1319077Y984634D01*
G02X1318393Y983609I-1457J231D01*
G01X1318364Y983592D01*
X1318358Y983589D01*
G02X1316884I-737J1277D01*
G01X1316849Y983609D01*
G02X1316146Y984866I772J1257D01*
G01Y986713D01*
X1315755Y987657D01*
X1313839Y989573D01*
X1307148D01*
X1306877Y989844D01*
X1306767D01*
G01X1321753Y1013595D02*
X1320295Y1012137D01*
X1318273D01*
G02X1317317Y1012318I-219J1458D01*
G03X1315131Y1012342I-1114J-1927D01*
G01X1315090Y1012318D01*
G02X1313616I-737J1277D01*
G03X1311432Y1012342I-1113J-1927D01*
G01X1311391Y1012318D01*
G02X1310654Y1012121I-736J1277D01*
G01X1309619D01*
G01X1319903Y1010391D02*
X1317246Y1011492D01*
X1316940Y1011668D01*
G03X1315467I-737J-1275D01*
G01X1315466D01*
G03X1315066Y1011413I2673J-4634D01*
G01X1314621Y1010968D01*
Y1009579D01*
X1313861Y1008819D01*
X1311460D01*
X1310608Y1009671D01*
X1308067D01*
G01X1318054Y1007187D02*
X1317414Y1006547D01*
X1315889D01*
X1314546Y1005204D01*
X1313366Y1005134D01*
X1313240Y1005260D01*
G03X1311881I-680J-1178D01*
G02X1311781Y1005214I-260J433D01*
G01X1309937Y1003769D01*
X1307207D01*
X1305296Y1005680D01*
G01X1319903Y1016800D02*
X1318374Y1018329D01*
X1315902D01*
X1315466Y1018077D01*
G02X1313240I-1113J1927D01*
G03X1311766I-737J-1277D01*
G03X1311460Y1017843I735J-1278D01*
G01X1310181Y1016564D01*
X1306298D01*
X1305739Y1017123D01*
G01X1319903Y1029617D02*
Y1028397D01*
X1320312Y1027988D01*
Y1027495D01*
X1320001Y1027184D01*
X1319506D01*
X1318661Y1028029D01*
Y1028499D01*
X1318297Y1028863D01*
X1317801D01*
X1317461Y1028523D01*
Y1028119D01*
X1316961Y1027619D01*
X1315484D01*
X1314984Y1028119D01*
Y1028695D01*
X1314634Y1029045D01*
X1314139D01*
X1313802Y1028708D01*
Y1028237D01*
X1313452Y1027887D01*
X1313450D01*
G02X1311760Y1028340I0J3380D01*
G01X1311026Y1028763D01*
X1308586D01*
X1307825Y1029524D01*
X1307071D01*
X1306634Y1029087D01*
G01X1318054Y1026413D02*
X1319748D01*
X1320044Y1026117D01*
Y1024950D01*
X1319732Y1024638D01*
X1313861D01*
X1312834Y1025665D01*
X1311991D01*
X1311737Y1025411D01*
Y1024988D01*
X1310560Y1023811D01*
X1307921D01*
X1307312Y1024420D01*
Y1025226D01*
X1306343Y1026195D01*
X1304467D01*
G01X1303168Y1031521D02*
X1303255D01*
X1303380Y1031646D01*
X1304193D01*
X1304543Y1031296D01*
X1305332D01*
X1305682Y1031646D01*
X1306471D01*
X1306821Y1031296D01*
X1307610D01*
X1307960Y1031646D01*
X1308447D01*
X1309497Y1030596D01*
X1310654D01*
G03X1311766Y1030894I0J2224D01*
G02X1313240I737J-1277D01*
G03X1315421Y1030867I1115J1927D01*
G01X1315423Y1030869D01*
X1316844Y1031579D01*
X1317309Y1032489D01*
X1317641Y1032821D01*
X1318054D01*
G01Y1039230D02*
Y1038814D01*
X1317841Y1038601D01*
X1315734D01*
X1315436Y1038303D01*
Y1037275D01*
X1314680Y1036519D01*
X1314161D01*
X1313078Y1037602D01*
X1312466D01*
G03X1311760Y1037304I842J-2981D01*
G02X1311381Y1037128I-1166J2014D01*
G02X1311117Y1037051I-765J2131D01*
G02X1310703Y1036995I-518J2268D01*
G01X1310616D01*
X1310613Y1036994D01*
G02X1310543Y1036995I2J2559D01*
G01X1309997Y1037024D01*
X1309132Y1037287D01*
X1309095D01*
X1307621Y1038761D01*
X1306900D01*
X1306352Y1039309D01*
X1305401D01*
X1304853Y1038761D01*
X1304202D01*
X1303893Y1039070D01*
X1303184D01*
X1302903Y1038789D01*
X1302268D01*
X1301447Y1039610D01*
G01X1319903Y1036026D02*
X1320603Y1036726D01*
X1321305D01*
X1322034Y1035997D01*
Y1034847D01*
X1321487Y1034300D01*
X1320909Y1034356D01*
G02X1319829Y1034552I627J6530D01*
G02X1319069Y1034809I75J1474D01*
G02X1318934Y1034866I2484J6071D01*
G03X1317448Y1034966I-884J-2043D01*
G01X1317189Y1034893D01*
G03X1316864Y1034763I465J-1633D01*
G02X1316096Y1034605I-660J1263D01*
G02X1316091I-2J522D01*
G03X1314343Y1034660I-1457J-18515D01*
G03X1312617Y1034605I-286J-18144D01*
G02X1311827Y1034771I-114J1421D01*
G03X1311510Y1034919I-1346J-2470D01*
G03X1310047Y1035208I-1551J-4004D01*
G02X1309562Y1035329I21J1117D01*
G01X1308527Y1035854D01*
G03X1308492Y1035870I-226J-448D01*
G01X1307445Y1036304D01*
X1306731Y1036446D01*
X1306404Y1036511D01*
X1306368Y1036518D01*
G01X1321753Y1032821D02*
G02X1320292Y1033218I0J2887D01*
G01X1318791Y1034098D01*
G03X1317317I-737J-1277D01*
G03X1316598Y1033059I738J-1279D01*
G01X1316575Y1032749D01*
X1316576D01*
X1316571Y1032693D01*
X1316289Y1032139D01*
X1315088Y1031539D01*
X1315085Y1031538D01*
X1315078Y1031534D01*
X1315065Y1031527D01*
G02X1313616Y1031543I-710J1294D01*
G01Y1031544D01*
G03X1311432Y1031568I-1113J-1927D01*
G01X1311391Y1031544D01*
X1311390Y1031543D01*
G02X1310654Y1031346I-736J1276D01*
G01X1310653Y1031345D01*
X1309808D01*
X1308758Y1032395D01*
X1303381D01*
X1303255Y1032521D01*
X1303168D01*
G01X1319903Y1048842D02*
Y1047562D01*
X1320463Y1047002D01*
Y1046341D01*
X1320216Y1046094D01*
X1319622D01*
X1318661Y1047055D01*
Y1047941D01*
X1318253Y1048349D01*
X1317735D01*
X1317361Y1047975D01*
Y1047052D01*
X1316399Y1046090D01*
X1315956D01*
X1315347Y1046699D01*
Y1047630D01*
X1314518Y1048459D01*
X1314140D01*
X1313716Y1048035D01*
Y1047203D01*
X1313530Y1047017D01*
X1313074D01*
X1310915Y1047962D01*
X1308586D01*
X1307858Y1047234D01*
X1307350D01*
G01X1318054Y1045639D02*
Y1044677D01*
X1318364Y1044367D01*
Y1043620D01*
X1318002Y1043258D01*
X1317448D01*
X1316661Y1044045D01*
Y1044719D01*
X1316361Y1045019D01*
X1315761D01*
X1315143Y1044401D01*
Y1043401D01*
X1314661Y1042919D01*
X1314035D01*
X1313452Y1043502D01*
Y1043732D01*
X1313145Y1044039D01*
X1311507D01*
X1310343Y1042875D01*
X1309772D01*
X1308629Y1041732D01*
X1307295D01*
X1306614Y1042413D01*
Y1042875D01*
X1306568Y1042921D01*
G01X1319903Y1055251D02*
X1321264D01*
G02X1321613Y1054902I0J-349D01*
G01Y1054074D01*
G02X1321264Y1053725I-349J0D01*
G01X1319794D01*
G02X1319455Y1053810I-2J711D01*
G02X1319166Y1053974I4730J8671D01*
G01X1319108Y1054008D01*
G03X1316940Y1053974I-1054J-1961D01*
G01X1316181Y1053529D01*
X1315763D01*
X1314559Y1054733D01*
X1313918D01*
X1312954Y1053769D01*
X1311962D01*
X1310990Y1054389D01*
X1310718Y1054661D01*
Y1055494D01*
X1310050Y1056162D01*
X1309314D01*
X1308737Y1056739D01*
Y1057475D01*
X1308055Y1058157D01*
X1307429D01*
X1306701Y1058885D01*
G01X1321753Y1052047D02*
X1319522Y1052819D01*
X1318791Y1053324D01*
G03X1317317I-737J-1277D01*
G03X1316953Y1053086I1928J-3346D01*
G01X1316912D01*
X1316285Y1052459D01*
Y1052460D01*
G03X1315847Y1051815I2960J-2481D01*
G03X1315804Y1051734I2015J-1122D01*
G01X1315387Y1050915D01*
X1315088Y1050765D01*
X1315085Y1050764D01*
X1315078Y1050760D01*
X1315065Y1050753D01*
G02X1313856Y1050658I-710J1294D01*
G02X1313616Y1050769I497J1390D01*
G01X1313354Y1051031D01*
X1311627D01*
X1311300Y1050704D01*
X1309467D01*
X1304509Y1055662D01*
Y1055842D01*
X1304448Y1055903D01*
G01X1318054Y1052047D02*
G03X1316472Y1051393I-409J-1252D01*
G01X1315943Y1050355D01*
X1315423Y1050095D01*
X1315421Y1050093D01*
G02X1313603Y1049951I-1067J1954D01*
G01Y1049953D01*
G02X1313148Y1050176I746J2097D01*
G01X1313043Y1050282D01*
X1311938D01*
X1311611Y1049955D01*
X1309156D01*
X1308862Y1050249D01*
X1308285D01*
X1307790Y1050744D01*
Y1051321D01*
X1307296Y1051815D01*
X1306719D01*
X1306224Y1052310D01*
Y1052887D01*
X1305730Y1053381D01*
X1305153D01*
X1304658Y1053876D01*
Y1054453D01*
X1303977Y1055134D01*
X1303801D01*
X1303740Y1055195D01*
G01X1318054Y1064864D02*
Y1063306D01*
X1317747Y1062999D01*
X1317221D01*
X1316862Y1063358D01*
Y1064068D01*
X1316530Y1064400D01*
X1315950D01*
X1315740Y1064190D01*
Y1063368D01*
X1314824Y1062452D01*
X1313644D01*
X1313033Y1063063D01*
X1312007D01*
X1310388Y1064682D01*
X1309495D01*
X1308647Y1065530D01*
G01X1318054Y1058455D02*
X1318888D01*
X1319325Y1058892D01*
Y1059912D01*
X1318693Y1060544D01*
X1317090D01*
X1316111Y1059565D01*
Y1057369D01*
X1314761Y1056019D01*
X1313861D01*
X1313061Y1056819D01*
X1312446D01*
X1311946Y1057319D01*
Y1058629D01*
X1311446Y1059129D01*
X1309855D01*
X1306700Y1062284D01*
G01X1319903Y1068068D02*
Y1066179D01*
X1319611Y1065887D01*
X1319152D01*
X1318683Y1066356D01*
Y1066996D01*
X1318264Y1067415D01*
X1317633D01*
X1317083Y1066865D01*
Y1066005D01*
X1316696Y1065618D01*
X1315870D01*
X1315650Y1065838D01*
X1314960Y1067221D01*
X1314649Y1067532D01*
X1313916D01*
X1313086Y1066702D01*
Y1065558D01*
X1312693Y1065165D01*
X1312118D01*
X1311337Y1065946D01*
Y1066873D01*
X1310954Y1067256D01*
X1310319D01*
X1308246Y1069329D01*
G01X1321753Y1071273D02*
G02X1320292Y1071670I0J2887D01*
G01X1318791Y1072550D01*
G03X1317317I-737J-1277D01*
G03X1316598Y1071511I738J-1279D01*
G01X1316575Y1071201D01*
X1316576D01*
X1316571Y1071145D01*
X1316289Y1070591D01*
X1315088Y1069991D01*
X1315085Y1069990D01*
X1315078Y1069986D01*
X1315065Y1069979D01*
G02X1313614Y1069995I-711J1294D01*
G02X1313309Y1070230I741J1277D01*
G01Y1070229D01*
X1312761Y1070777D01*
X1312049D01*
X1311245Y1071111D01*
X1311023Y1071332D01*
X1311024D01*
X1305791Y1076565D01*
X1305788D01*
X1305119Y1077234D01*
Y1077414D01*
X1305058Y1077475D01*
G01X1304350Y1076767D02*
X1304411Y1076706D01*
X1304587D01*
X1305477Y1075816D01*
X1305480D01*
X1306010Y1075286D01*
Y1074734D01*
X1306576Y1074167D01*
X1307128D01*
X1307693Y1073602D01*
Y1073051D01*
X1308259Y1072484D01*
X1308811D01*
X1309376Y1071919D01*
Y1071368D01*
X1309942Y1070801D01*
X1310494D01*
X1310820Y1070475D01*
X1311899Y1070028D01*
X1312450D01*
X1312779Y1069699D01*
G03X1313240Y1069346I1572J1575D01*
G03X1315421Y1069319I1115J1927D01*
G01X1315423Y1069321D01*
X1316844Y1070031D01*
X1317409Y1071137D01*
X1317545Y1071273D01*
X1318054D01*
G01X1316203Y1080885D02*
X1315026Y1082062D01*
X1314430Y1082076D01*
X1314063Y1081743D01*
X1313961Y1080719D01*
Y1080419D01*
X1313761Y1080019D01*
X1313289Y1079668D01*
G02X1312963Y1079560I-326J439D01*
G01X1311839D01*
X1311352Y1079762D01*
X1310316Y1080798D01*
Y1080863D01*
X1308348Y1082831D01*
G01X1319903Y1074477D02*
X1318882Y1074096D01*
X1317392Y1073461D01*
X1316666Y1073042D01*
G02X1316171Y1072909I-496J857D01*
G01X1315291D01*
X1314778Y1073422D01*
Y1074516D01*
G03X1313692Y1076360I-2173J-38D01*
G01X1313616Y1076404D01*
G03X1313099Y1076647I-1680J-2903D01*
G03X1313002Y1076664I-95J-259D01*
G01X1311428D01*
X1310525Y1076290D01*
X1309883D01*
X1309381Y1076498D01*
X1308974Y1076905D01*
X1308514Y1078015D01*
Y1079256D01*
X1306643Y1081127D01*
G01X1321753Y1090498D02*
X1321359Y1090103D01*
G02X1318480Y1088909I-2879J2874D01*
G01X1315268D01*
G02X1313852Y1089133I0J4590D01*
G02X1313530Y1089269I662J2016D01*
G03X1312503Y1089519I-1025J-1975D01*
G01X1311037D01*
X1308038Y1092518D01*
Y1093049D01*
X1306409Y1094678D01*
X1305629D01*
X1304362Y1095945D01*
G01X1319903Y1087294D02*
X1318123Y1086538D01*
G03X1317810Y1086381I1111J-2605D01*
G01X1316667Y1085718D01*
G02X1315293Y1085716I-689J1186D01*
G01X1314771Y1086017D01*
G03X1313240I-765J-1326D01*
G02X1312503Y1085820I-736J1277D01*
G01X1310544D01*
X1305792Y1090572D01*
X1305279D01*
X1303696Y1092155D01*
Y1093153D01*
X1302633Y1094216D01*
G01X1319903Y1093703D02*
X1321127D01*
X1321359Y1093935D01*
G03X1320675Y1094960I-1457J-231D01*
G01X1320640Y1094980D01*
G03X1319166I-737J-1277D01*
G01X1319160Y1094977D01*
X1319131Y1094960D01*
G03X1318428Y1093703I772J-1257D01*
G01Y1093616D01*
G02X1317317Y1091775I-2225J87D01*
G02X1315131Y1091751I-1114J1928D01*
G01X1315090Y1091775D01*
G03X1313616I-737J-1277D01*
G02X1312503Y1091477I-1113J1928D01*
G01X1311743D01*
X1311110Y1091739D01*
X1310314Y1092535D01*
X1309999Y1093294D01*
X1308181Y1095113D01*
X1307723Y1096503D01*
X1307471Y1096755D01*
X1307293D01*
X1307232Y1096816D01*
G01X1331003Y1093703D02*
X1328447Y1094902D01*
X1327395Y1095155D01*
X1325054Y1095445D01*
X1324475Y1095728D01*
X1324150Y1096087D01*
X1322849Y1097841D01*
X1322510Y1098180D01*
X1322120Y1098342D01*
X1320977D01*
G02X1319166Y1098834I0J3578D01*
G01X1319108Y1098868D01*
G03X1316940Y1098834I-1054J-1961D01*
G02X1315466I-737J1277D01*
G01X1315156Y1099013D01*
G02X1314777Y1099422I469J814D01*
G03X1314614Y1099732I-3893J-1849D01*
G01X1314286Y1100219D01*
X1314206Y1100323D01*
X1314212Y1100365D01*
X1312875Y1102158D01*
G01X1309745Y1101027D02*
X1310265Y1100507D01*
G02X1310536Y1100017I-714J-715D01*
G03X1310807Y1099525I985J222D01*
G01X1311568Y1098764D01*
X1312951D01*
G02X1315090Y1098184I0J-4235D01*
G01X1315131Y1098160D01*
G03X1317317Y1098184I1072J1951D01*
G02X1319038Y1097957I713J-1235D01*
G01X1319958Y1097037D01*
G03X1320272Y1096907I314J314D01*
G01X1321753D01*
G01X1307940Y1097524D02*
X1308001Y1097463D01*
Y1097285D01*
X1308379Y1096907D01*
X1308837Y1095517D01*
X1310635Y1093719D01*
X1310950Y1092960D01*
X1311535Y1092375D01*
X1311892Y1092226D01*
X1312503D01*
G03X1313240Y1092426I-5J1476D01*
G02X1315466I1113J-1928D01*
G03X1316940I737J1277D01*
G01X1316975Y1092446D01*
G03X1317677Y1093645I-772J1257D01*
G03X1317678Y1093703I-1474J54D01*
G02X1318767Y1095616I2225J0D01*
G01X1318788Y1095628D01*
X1318791Y1095630D01*
X1318832Y1095654D01*
G02X1321016Y1095630I1071J-1951D01*
G02X1322101Y1094054I-1112J-1927D01*
G02X1322113Y1093969I-2197J-354D01*
G01X1322379Y1093703D01*
X1323603D01*
G01X1500770Y981662D02*
X1498906Y982368D01*
X1498286Y982662D01*
X1497807Y982939D01*
G02X1496696Y984805I1114J1927D01*
G01Y985164D01*
X1496756Y985452D01*
X1496896Y985890D01*
X1497209Y986322D01*
X1497885Y987070D01*
X1498289Y987431D01*
X1498623Y987662D01*
X1502581Y990049D01*
X1508987Y993391D01*
X1509486Y993625D01*
X1511426Y994538D01*
X1512943Y994989D01*
X1513608Y995095D01*
G01X1502621Y978457D02*
X1502219Y981902D01*
X1502052Y982304D01*
G03X1501865Y982598I-945J-395D01*
G01X1501572Y982922D01*
G03X1501280Y983116I-522J-469D01*
G03X1500421Y983259I-856J-2488D01*
G01X1499427D01*
G02X1498184Y983589I0J2505D01*
G01X1498149Y983609D01*
G02X1497446Y984866I772J1257D01*
G01Y985089D01*
X1497559Y985487D01*
X1497690Y985700D01*
X1497898Y985960D01*
X1498657Y986698D01*
X1502521Y988939D01*
X1507782Y991543D01*
X1508851Y991986D01*
G01X1506321Y978457D02*
Y982003D01*
G02X1506601Y982679I956J0D01*
G01X1506809Y982886D01*
G02X1507901Y983339I1093J-1092D01*
G01X1510331D01*
X1510820Y983626D01*
X1510847Y983641D01*
X1510879Y983658D01*
X1511027Y983788D01*
X1511495Y984256D01*
Y984818D01*
X1511497Y984851D01*
G02X1511498Y984866I2342J-149D01*
G01X1511497D01*
G02X1513741Y987089I2345J-123D01*
G01X1514055D01*
X1515207Y987566D01*
X1515867D01*
G01X1508170Y981662D02*
G03X1511027Y982847I-3914J13472D01*
G01X1511099Y982919D01*
Y982920D01*
X1511203Y982981D01*
X1511208Y982984D01*
X1511214Y982987D01*
G03X1512102Y983769I-1025J2060D01*
G03X1512246Y984248I-717J477D01*
G01Y984827D01*
G02X1513759Y986340I1596J-83D01*
G01X1521048D01*
X1521768Y985620D01*
X1522467D01*
G01X1519271Y891942D02*
G03X1521577Y890176I7817J7819D01*
G01X1521858Y890014D01*
G02X1522164Y889780I-735J-1278D01*
G01X1523189Y888755D01*
X1524349Y886959D01*
X1525012Y886296D01*
G01X1515570Y891942D02*
X1518346Y893544D01*
G02X1520196I925J-1602D01*
G01X1520806Y892933D01*
G02X1521061Y892319I-614J-615D01*
G01Y892282D01*
G03X1521432Y891386I1267J0D01*
G01X1521927Y890891D01*
G03X1522382Y890616I784J783D01*
G03X1522800Y890504I1776J5794D01*
G02X1523117Y890354I-183J-796D01*
G01X1524872Y888599D01*
X1525186D01*
X1526251Y887534D01*
G01X1521121Y895146D02*
X1522912Y893355D01*
X1525435D01*
X1527553Y891237D01*
G01X1513721Y895146D02*
G03X1515079Y895507I0J2733D01*
G01X1516834Y896512D01*
G02X1517761Y896759I927J-1618D01*
G01X1520544D01*
G02X1522030Y896313I1J-2697D01*
G01X1523489Y895351D01*
X1523981Y895401D01*
X1524449Y895869D01*
X1524931D01*
X1528558Y892242D01*
G01X1511871Y898350D02*
X1514723Y897039D01*
G03X1515461Y896910I613J1331D01*
G01X1515692Y896929D01*
G03X1516487Y897254I-117J1421D01*
G01X1516651Y897390D01*
G03X1516703Y897445I-204J245D01*
G01X1518080Y899293D01*
X1518231Y899430D01*
Y899431D01*
G02X1519999Y899635I1025J-1123D01*
G01X1520012Y899627D01*
X1520013D01*
X1520015Y899626D01*
X1520189Y899526D01*
G03X1520574Y899370I768J1343D01*
G03X1522161Y899583I531J2062D01*
G01X1522403Y899721D01*
X1522495Y899768D01*
X1523561D01*
X1524680Y899305D01*
Y899303D01*
X1526335Y898619D01*
X1527540Y898120D01*
X1528209D01*
X1529024Y897305D01*
Y897129D01*
X1529085Y897068D01*
G01X1522970Y898350D02*
G02X1522978Y898346I0J-10D01*
G01X1523674Y897652D01*
X1526311D01*
X1528493Y895470D01*
X1528671D01*
X1528732Y895409D01*
G01X1515570Y898350D02*
X1516064Y898244D01*
X1516641Y898617D01*
X1517522Y899800D01*
X1517725Y899985D01*
G02X1520366Y900290I1532J-1677D01*
G01X1520370Y900288D01*
X1520562Y900178D01*
G03X1520761Y900097I397J690D01*
G03X1521788Y900235I343J1335D01*
G01X1522026Y900371D01*
X1522317Y900517D01*
X1523710D01*
X1524967Y899997D01*
X1525463Y900203D01*
X1526416Y899809D01*
X1526622Y899311D01*
X1527689Y898869D01*
X1528520D01*
X1529552Y897837D01*
X1529732D01*
X1529793Y897776D01*
G01X1519271Y898350D02*
X1519954D01*
X1519985Y898319D01*
G02X1520160Y898272I0J-350D01*
G01X1522238Y897073D01*
X1522547Y896903D01*
X1526000D01*
X1527963Y894939D01*
Y894763D01*
X1528024Y894702D01*
G01X1528266Y914518D02*
X1527415Y915369D01*
X1522370D01*
X1521867Y915660D01*
X1521842Y915670D01*
X1521148Y915969D01*
X1517332D01*
X1516246Y915341D01*
G02X1515017Y915324I-630J1086D01*
G01X1514449Y915632D01*
X1514124Y915823D01*
X1512715D01*
X1512359Y915467D01*
Y914563D01*
X1512550Y914372D01*
X1513721D01*
G01X1515570Y911167D02*
X1517046D01*
X1517447Y911568D01*
Y912091D01*
X1518475Y913119D01*
X1520061D01*
X1520503Y912673D01*
X1522880D01*
X1523946Y913739D01*
X1525649D01*
X1530502Y908886D01*
G01X1521121Y914372D02*
X1521216Y914467D01*
G02X1521304Y914503I88J-88D01*
G01X1526583D01*
X1531351Y909735D01*
G01X1519271Y911167D02*
X1523129Y909569D01*
X1528121D01*
X1529653Y908037D01*
G01X1515570Y904759D02*
G02X1517863Y906167I4090J-4090D01*
G01X1518007Y906214D01*
G03X1518355Y906369I-575J1759D01*
G02X1520193Y906376I925J-1602D01*
G01X1520205Y906369D01*
G03X1521318Y906131I925J1603D01*
G02X1521918Y906185I2675J-26360D01*
G01X1523193Y907460D01*
X1526776D01*
X1527233Y907271D01*
X1533111Y901393D01*
G01X1513721Y901555D02*
Y902791D01*
X1513213Y903299D01*
Y903877D01*
X1513571Y904235D01*
X1514007D01*
X1515139Y903103D01*
X1516134D01*
X1516581Y903366D01*
G02X1518397Y903374I915J-1552D01*
G01X1518803Y903139D01*
X1520665D01*
G02X1521948Y902780I0J-2471D01*
G01X1522690Y902329D01*
X1526464D01*
X1527310Y901979D01*
X1529129D01*
X1529762Y901346D01*
G01X1519271Y904759D02*
G02X1520442Y904460I-1J-2446D01*
G01X1522247Y903476D01*
X1522673Y903218D01*
X1529588D01*
X1532325Y900481D01*
G01X1521121Y901555D02*
X1523662D01*
X1524012Y901205D01*
X1525011D01*
X1525361Y901555D01*
X1525987D01*
X1526234Y901308D01*
Y900943D01*
X1526618Y900559D01*
X1528851D01*
X1530564Y898846D01*
G01X1511871Y917576D02*
G02X1513436Y917157I2J-3124D01*
G01X1515303Y916078D01*
G03X1515888Y916108I199J1832D01*
G01X1516178Y916229D01*
X1516627Y916470D01*
X1517255Y916985D01*
X1517640Y917370D01*
Y917438D01*
X1517637Y917441D01*
Y918222D01*
X1518411Y918801D01*
Y918802D01*
X1519156Y919087D01*
X1519508D01*
X1520787Y918553D01*
X1521969D01*
X1522385Y918969D01*
X1523915D01*
X1524220Y918664D01*
X1527346D01*
X1527347Y918663D01*
X1528631D01*
X1528756Y918538D01*
X1528843D01*
G01X1522970Y917576D02*
Y917224D01*
X1523321Y916873D01*
X1528987D01*
X1529639Y916221D01*
X1529817D01*
X1529878Y916160D01*
G01X1519271Y917576D02*
X1521384Y916757D01*
G02X1521873Y916522I-1256J-3240D01*
G03X1522535Y916220I1864J3209D01*
G01X1522542Y916218D01*
G03X1523108Y916124I566J1657D01*
G01X1528676D01*
X1529109Y915691D01*
Y915514D01*
X1529170Y915453D01*
G01X1515570Y930393D02*
X1516794D01*
X1517060Y930659D01*
G02X1518158Y932321I2210J-266D01*
G02X1520384I1113J-1928D01*
G02X1521496Y930466I-1113J-1928D01*
G01Y930359D01*
G03X1522233Y929116I1474J34D01*
G03X1522970Y928917I740J1276D01*
G01X1528614D01*
X1529622Y927909D01*
X1531666D01*
G01X1519271Y930393D02*
X1520260Y929983D01*
X1521209Y929034D01*
G03X1521834Y928480I1762J1358D01*
G03X1522824Y928172I1138J1912D01*
G03X1522969Y928168I134J2221D01*
G01X1528279D01*
X1529738Y926709D01*
X1531666D01*
G01X1515570Y923985D02*
X1515199Y924881D01*
Y925413D01*
X1515611Y925825D01*
X1516365D01*
X1516861Y925329D01*
Y924969D01*
X1517211Y924619D01*
X1517789D01*
X1518139Y924969D01*
Y925598D01*
X1518604Y926063D01*
X1519729D01*
G02X1520219Y925860I1J-691D01*
G03X1520977Y925401I1304J1299D01*
G03X1521324Y925349I345J1118D01*
G01X1524357Y926605D01*
X1525773D01*
X1527794Y924584D01*
X1528666D01*
G01X1513721Y920780D02*
X1513361Y921650D01*
Y922697D01*
X1513710Y923046D01*
X1514204D01*
X1514561Y922689D01*
Y922075D01*
X1515262Y921374D01*
X1515646D01*
X1516661Y922389D01*
X1520635D01*
G02X1521858Y922057I0J-2418D01*
G01X1522455Y921707D01*
X1526389D01*
X1526768Y922086D01*
X1527501D01*
X1527502Y922087D01*
X1528666D01*
G01X1519271Y923985D02*
X1520417D01*
X1520957Y923445D01*
X1522661Y922461D01*
X1525983D01*
X1526843Y923321D01*
X1528666D01*
G01X1521121Y920780D02*
X1521228Y920887D01*
X1528666D01*
G01X1515570Y917576D02*
X1516625D01*
X1516888Y917839D01*
Y918597D01*
X1518045Y919464D01*
X1519017Y919836D01*
X1519659D01*
X1520938Y919302D01*
X1521658D01*
X1522074Y919718D01*
X1524226D01*
X1524531Y919413D01*
X1525245D01*
X1525672Y919840D01*
X1526373D01*
X1526800Y919413D01*
X1527719D01*
X1527720Y919412D01*
X1528630D01*
X1528756Y919538D01*
X1528843D01*
G01X1519271Y949619D02*
X1523303Y947949D01*
X1523838D01*
X1527621Y946381D01*
X1528659Y945343D01*
G01X1519271Y943210D02*
X1520250Y942231D01*
X1521129D01*
G02X1522220Y941943I-4J-2225D01*
G03X1522975Y941734I757J1267D01*
G01X1524409D01*
X1525550Y942875D01*
X1526474D01*
X1530640Y938709D01*
X1531066D01*
G01X1521121Y940006D02*
X1521130Y940015D01*
X1526681D01*
X1530387Y936309D01*
X1531066D01*
G01X1513721Y933598D02*
G03X1516684Y934874I-3884J13098D01*
G01X1517309Y935236D01*
G02X1517881Y935389I571J-989D01*
G01X1517941D01*
G02X1518270Y935286I-1J-580D01*
G01X1518461Y935095D01*
Y934619D01*
X1518961Y934119D01*
X1519561D01*
X1520011Y934569D01*
Y934869D01*
X1520311Y935169D01*
X1520601D01*
G02X1520779Y935154I0J-1065D01*
G01X1521374Y935050D01*
G02X1522163Y934640I-253J-1452D01*
G01X1525549D01*
X1529881Y930308D01*
X1529882Y930309D01*
X1531666D01*
G01X1521121Y933598D02*
X1525496D01*
X1529985Y929109D01*
X1531666D01*
G01X1515570Y943210D02*
X1516405Y943092D01*
G03X1516736Y943177I63J442D01*
G01X1518710Y944659D01*
G02X1519036Y944768I326J-434D01*
G01X1522614D01*
X1524120Y946274D01*
X1525562D01*
X1526232Y945604D01*
X1526414Y945331D01*
Y944591D01*
X1531096Y939909D01*
X1532366D01*
G01X1513721Y940006D02*
Y941128D01*
G02X1513726Y941140I17J0D01*
G01X1514076Y941490D01*
X1514645D01*
X1515216Y940919D01*
X1516045D01*
X1516945Y941819D01*
X1518016D01*
X1519016Y940819D01*
X1519715D01*
X1520077Y941181D01*
X1520485Y941341D01*
X1520547Y941364D01*
X1520550Y941365D01*
X1520598Y941383D01*
X1521118Y941481D01*
X1521131D01*
X1521840Y941296D01*
X1521848Y941292D01*
X1522369Y940985D01*
X1527064D01*
X1530540Y937509D01*
X1531066D01*
G01X1511871Y936801D02*
X1514452Y935615D01*
G03X1515692Y935380I1083J2323D01*
G03X1516487Y935705I-117J1421D01*
G01X1516651Y935841D01*
G03X1516703Y935896I-204J245D01*
G01X1517124Y936459D01*
X1517122Y936460D01*
X1517550Y937034D01*
X1518268Y937818D01*
X1518596Y938111D01*
G02X1520008Y938078I676J-1310D01*
G01X1520199Y937967D01*
X1520200D01*
X1520219Y937959D01*
G03X1522024Y937958I903J1564D01*
G02X1522926Y938200I903J-1563D01*
G01X1524176D01*
X1525088Y938052D01*
G02X1525575Y937846I-1355J-3882D01*
G01X1525635Y937815D01*
X1525694Y937786D01*
X1525695D01*
X1528221Y935261D01*
Y935262D01*
X1529353Y934130D01*
X1530193D01*
X1530314Y934009D01*
G01X1522970Y936801D02*
Y936491D01*
X1523320Y936141D01*
X1526168D01*
X1529826Y932483D01*
X1531653D01*
X1531779Y932609D01*
X1531866D01*
G01X1515570Y936801D02*
X1516095Y936688D01*
X1516602Y937016D01*
X1516972Y937512D01*
X1517740Y938351D01*
X1518159Y938727D01*
G02X1520382I1112J-1926D01*
G01X1520384Y938729D01*
X1520593Y938608D01*
G03X1521650Y938607I529J915D01*
G02X1522925Y938949I1277J-2212D01*
G01X1524237D01*
X1525270Y938782D01*
G02X1525913Y938515I-1538J-4611D01*
G01X1526139Y938402D01*
X1526371Y938170D01*
X1526926D01*
X1527350Y937746D01*
Y937193D01*
X1527774Y936769D01*
X1528327D01*
X1528751Y936345D01*
Y935792D01*
X1529664Y934879D01*
X1530184D01*
X1530314Y935009D01*
G01X1519271Y936801D02*
X1519273Y936795D01*
X1522714Y935392D01*
X1525857D01*
X1529515Y931734D01*
X1531654D01*
X1531779Y931609D01*
X1531866D01*
G01X1513721Y952823D02*
X1513696Y952848D01*
Y953369D01*
X1514046Y953719D01*
X1516105D01*
X1517045Y954263D01*
G02X1517796Y954531I1103J-1905D01*
G01X1517869Y954543D01*
G02X1518531Y954329I122J-754D01*
G03X1519841I655J655D01*
G02X1520251Y954499I410J-410D01*
G01X1520491D01*
G02X1521371Y954330I-1J-2382D01*
G01X1521674Y954210D01*
G02X1521967Y954018I-322J-810D01*
G01X1522944Y953049D01*
X1526491D01*
X1529473Y950067D01*
Y949719D01*
X1529955Y949237D01*
G01X1515570Y949619D02*
X1517129D01*
X1517499Y949989D01*
Y950785D01*
X1518093Y951379D01*
X1525798D01*
X1526926Y950251D01*
Y948858D01*
X1528250Y947534D01*
G01X1521121Y952823D02*
X1521123Y952824D01*
X1522176Y952389D01*
G03X1522930Y952239I755J1823D01*
G01X1526155D01*
X1528297Y950097D01*
Y949185D01*
X1529099Y948383D01*
G01X1515570Y962436D02*
X1517309D01*
X1517695Y962822D01*
Y963886D01*
X1518248Y964439D01*
X1519983D01*
X1520483Y963939D01*
Y963331D01*
X1520952Y962862D01*
X1521447D01*
X1521886Y963301D01*
Y964236D01*
X1522101Y964451D01*
X1523225D01*
X1523867Y963809D01*
X1524797D01*
X1526225Y965237D01*
X1526933D01*
X1527327Y964843D01*
Y963893D01*
X1527676Y963544D01*
X1527904D01*
G01X1513721Y959232D02*
X1513361Y960102D01*
Y961445D01*
X1513572Y961656D01*
X1514257D01*
X1514846Y961067D01*
Y960379D01*
X1515196Y960029D01*
X1515691D01*
X1517099Y961409D01*
X1517704D01*
X1518918Y960195D01*
X1519414D01*
X1520091Y960872D01*
X1520111Y960883D01*
G02X1521246Y960884I568J-983D01*
G01X1521868Y960525D01*
G03X1523200Y960168I1332J2307D01*
G01X1525318D01*
X1525986Y959500D01*
X1527966D01*
G01X1519271Y962436D02*
X1520685Y962075D01*
X1522261Y961164D01*
G03X1522994Y960968I732J1269D01*
G01X1525718D01*
X1525986Y960700D01*
X1527966D01*
G01X1521121Y959232D02*
X1525179Y959247D01*
X1526126Y958300D01*
X1527966D01*
G01X1522970Y956027D02*
Y955677D01*
X1523918Y954729D01*
X1524814D01*
X1525180Y955095D01*
X1525944D01*
X1526310Y954729D01*
X1527191D01*
X1534036Y947884D01*
X1534753D01*
X1534879Y948010D01*
X1534966D01*
G01X1511871Y956027D02*
Y956028D01*
X1514717Y954818D01*
X1514833Y954750D01*
G03X1516305Y954751I735J1276D01*
G01X1516307D01*
X1516422Y954818D01*
G03X1517514Y955910I-1496J2588D01*
G01X1517786Y956380D01*
G03X1517952Y956690I-5177J2972D01*
G02X1518001Y956780I1318J-659D01*
G02X1518533Y957304I1266J-754D01*
G01Y957306D01*
G02X1520010I738J-1279D01*
G03X1522232I1111J1926D01*
G02X1522970Y957504I738J-1276D01*
G01X1523067D01*
X1523068Y957503D01*
X1524171D01*
X1525294Y956380D01*
X1527536D01*
X1529768Y954148D01*
Y953971D01*
X1529829Y953910D01*
G01X1519271Y956027D02*
Y956028D01*
X1521566Y955155D01*
X1523603Y953979D01*
X1526309D01*
X1526310Y953980D01*
X1526880D01*
X1533725Y947135D01*
X1534754D01*
X1534879Y947010D01*
X1534966D01*
G01X1515570Y956027D02*
Y955889D01*
X1515764Y955695D01*
G03X1516121Y955609I248J247D01*
G03X1516578Y955949I-280J853D01*
G01X1517066Y956648D01*
G03X1517198Y956973I-672J462D01*
G02X1517397Y957355I704J-124D01*
G01X1517566Y957524D01*
G02X1518043Y957889I1611J-1612D01*
G01X1518158Y957955D01*
G02X1520384I1113J-1928D01*
G03X1521858I737J1277D01*
G02X1522970Y958253I1112J-1926D01*
G01X1523222D01*
X1523223Y958252D01*
X1524482D01*
X1525605Y957129D01*
X1527847D01*
X1530297Y954679D01*
X1530475D01*
X1530536Y954618D01*
G01X1515570Y981662D02*
X1516948Y983040D01*
X1520732D01*
X1522112Y984420D01*
X1528012D01*
X1533875Y978557D01*
G01X1519271Y981662D02*
X1521155D01*
X1522513Y983020D01*
X1527712D01*
X1533467Y977265D01*
G01X1513721Y978457D02*
X1516571Y977246D01*
X1516684Y977180D01*
G03X1518157I737J1275D01*
G01X1518158D01*
X1518159Y977181D01*
G03X1518896Y978457I-736J1276D01*
G01X1520520Y980105D01*
X1521820Y980116D01*
X1522904Y981220D01*
X1527812D01*
X1532626Y976406D01*
G01X1522970Y975253D02*
X1523370D01*
X1524425Y976308D01*
X1530192D01*
X1531252Y975248D01*
G01X1511871Y975253D02*
X1513101Y976483D01*
X1514661D01*
X1515045Y976630D01*
G02X1516307Y976530I526J-1377D01*
G03X1518493Y976506I1114J1927D01*
G01X1518534Y976530D01*
G02X1520008I737J-1277D01*
G02X1520745Y975253I-738J-1277D01*
G03X1521108Y974626I724J1D01*
G01X1522695Y973884D01*
X1523975D01*
X1525311Y975220D01*
X1529180D01*
X1530367Y974033D01*
G01X1519271Y968845D02*
Y969989D01*
X1519621Y970339D01*
X1520912D01*
X1521773Y970781D01*
G02X1522178Y970952I1314J-2548D01*
G02X1522524Y971007I343J-1042D01*
G01X1525487D01*
X1525706Y970788D01*
X1528567D01*
G01X1522970Y968845D02*
X1524462D01*
X1524919Y968388D01*
X1528566D01*
G01X1515570Y968845D02*
X1517091Y968215D01*
X1517765D01*
X1518246Y967734D01*
X1518543Y967564D01*
X1519271Y967368D01*
X1520010Y967566D01*
X1521307Y968863D01*
Y969500D01*
X1521710Y969903D01*
X1522128Y970118D01*
G02X1522667Y970249I539J-1045D01*
G01X1525154D01*
X1525815Y969588D01*
X1528567D01*
G01X1513721Y972049D02*
Y969949D01*
X1514181Y968129D01*
X1515061Y967249D01*
X1517171D01*
G02X1517939Y967043I-1J-1537D01*
G01X1518158Y966917D01*
G03X1520384I1113J1928D01*
G02X1520656Y967013I397J-692D01*
G01X1521742Y967188D01*
X1528566D01*
G01X1530367Y971988D02*
X1529618D01*
X1527475Y974131D01*
X1525756D01*
X1524700Y973075D01*
X1522250D01*
G02X1522067Y973115I1J443D01*
G03X1521907Y973238I-946J-1066D01*
G03X1521009Y973651I-1788J-2704D01*
G01X1520364D01*
G03X1520350Y973645I0J-20D01*
G01X1520076Y973370D01*
G02X1519413Y973096I-662J663D01*
G01X1518662D01*
G02X1518348Y973226I0J444D01*
G01X1517686Y973888D01*
G02Y975131I621J621D01*
G02X1517981Y975253I295J-295D01*
G01X1519271D01*
G01X1516003Y997574D02*
X1517090D01*
X1517520Y998004D01*
X1518591Y999500D01*
Y999501D01*
G02X1520817I1113J-1927D01*
G01X1521166Y998823D01*
X1521611Y998601D01*
G03X1521963Y998547I258J505D01*
G01X1525487Y999139D01*
G03X1526077Y999336I-334J1983D01*
G01X1526471Y999538D01*
X1528302Y1001369D01*
X1530767D01*
G01X1519703Y997574D02*
X1521509Y997575D01*
X1525891Y998446D01*
X1527100Y998812D01*
X1528199D01*
X1528814Y999068D01*
X1528967Y999131D01*
G01X1519703Y1003983D02*
X1524378Y1006569D01*
X1525001D01*
X1525342Y1006228D01*
X1526967D01*
G01X1523403Y1003983D02*
X1525924Y1005027D01*
X1528467D01*
G01X1512303Y1003983D02*
X1513221Y1003065D01*
X1514892D01*
X1515231Y1002726D01*
X1515266Y1002706D01*
G03X1516740I737J1277D01*
G02X1518966I1113J-1928D01*
G03X1520027Y1002545I737J1277D01*
G01X1520356Y1002714D01*
X1520925Y1002969D01*
G02X1522231Y1002930I589J-2146D01*
G01X1523161Y1002616D01*
X1523993D01*
X1524947Y1003029D01*
X1525676D01*
X1526474Y1003827D01*
X1528467D01*
G01X1514154Y1000778D02*
X1515133Y1001757D01*
X1516030D01*
G03X1517116Y1002055I-27J2226D01*
G02X1518590I737J-1277D01*
G03X1520291Y1001836I1113J1928D01*
G01X1520701Y1002047D01*
X1521202Y1002255D01*
G02X1522262Y1002094I324J-1438D01*
G01X1522309Y1002067D01*
X1523061Y1001867D01*
X1524212D01*
X1525163Y1002279D01*
X1526026D01*
X1526374Y1002627D01*
X1528467D01*
G01X1519703Y1010391D02*
X1519601Y1010493D01*
Y1011524D01*
X1519849Y1011772D01*
X1521521D01*
G02X1522132Y1012259I1521J-1282D01*
G01X1522927Y1012699D01*
G02X1524030Y1012983I1102J-1995D01*
G01X1527267D01*
G01X1523403Y1010391D02*
X1527267D01*
G01X1516003D02*
X1515095Y1010015D01*
X1514679D01*
X1514304Y1010390D01*
Y1011492D01*
X1515063Y1012251D01*
X1516952D01*
X1517969Y1011234D01*
Y1009958D01*
X1518396Y1009531D01*
Y1009490D01*
X1518903Y1009154D01*
G03X1519217Y1008998I778J1172D01*
G03X1520440Y1009114I485J1391D01*
G02X1521161Y1009419I1579J-2728D01*
G03X1521828Y1010391I-251J887D01*
G01Y1010768D01*
G02X1522503Y1011601I1284J-350D01*
G01X1522725Y1011713D01*
G02X1523274Y1011716I277J-545D01*
G01X1523866D01*
X1523879Y1011729D01*
X1527267D01*
G01X1514154Y1007187D02*
X1512869Y1007720D01*
X1512627Y1007962D01*
Y1008318D01*
X1513217Y1008908D01*
X1515396D01*
X1515644Y1008660D01*
X1517909D01*
G02X1518590Y1008464I-55J-1473D01*
G01X1518591D01*
G03X1520817I1113J1927D01*
G02X1521917Y1008759I1100J-1902D01*
G01X1527267D01*
G01X1516520Y1026103D02*
X1514914Y1025155D01*
X1514037Y1024834D01*
X1513650Y1024845D01*
X1512303Y1025318D01*
G01X1516003Y1029617D02*
X1516008D01*
X1517127Y1030736D01*
G02X1517394Y1030964I1508J-1495D01*
G02X1520361Y1031345I1839J-2575D01*
G03X1520786Y1031169I425J425D01*
G01X1521181D01*
G03X1522036Y1031397I1J1715D01*
G01X1522291Y1031544D01*
G03X1522597Y1031778I-735J1278D01*
G01X1522781Y1032003D01*
X1524364Y1033130D01*
X1525254Y1033456D01*
G03X1526026Y1033674I0J1476D01*
G03X1526395Y1033997I-774J1256D01*
G01X1526623Y1034225D01*
X1527607D01*
X1528251Y1034869D01*
G01X1514154Y1026413D02*
X1513750Y1026817D01*
Y1027969D01*
X1514153Y1028372D01*
X1515021D01*
X1515708Y1027685D01*
X1516508D01*
X1516829Y1028006D01*
X1518537D01*
X1519498Y1027045D01*
X1520020D01*
X1520981Y1028006D01*
X1525651D01*
X1528759Y1031114D01*
Y1031981D01*
X1529961Y1033183D01*
G01X1519703Y1029617D02*
G03X1521088Y1029987I0J2779D01*
G01X1522666Y1030894D01*
G03X1523065Y1031187I-1109J1929D01*
G03X1523183Y1031305I-1513J1631D01*
G01X1524932Y1032488D01*
X1525693Y1032750D01*
G03X1526390Y1033018I-438J2180D01*
G03X1526801Y1033332I-1136J1913D01*
G01X1528412D01*
X1529097Y1034017D01*
G01X1521554Y1026413D02*
X1523010Y1027016D01*
X1525915D01*
X1529673Y1030774D01*
Y1031197D01*
X1530846Y1032370D01*
G01X1514154Y1020004D02*
X1514201Y1020117D01*
X1517129Y1021330D01*
X1518402Y1021583D01*
X1521356D01*
G02X1521703Y1021534I1J-1246D01*
G02X1522273Y1021294I-742J-2560D01*
G01X1522296Y1021281D01*
G02X1522602Y1021047I-735J-1279D01*
G01X1522666Y1020983D01*
X1527456D01*
X1530742Y1024269D01*
X1531238D01*
X1532113Y1025144D01*
G01X1516003Y1016800D02*
X1517231Y1017309D01*
X1518381Y1018459D01*
X1521292D01*
G03X1522278Y1018716I0J2018D01*
G01X1522916Y1019219D01*
X1523116Y1019419D01*
X1525016D01*
X1525316Y1019119D01*
X1529484D01*
X1533840Y1023475D01*
G01X1521554Y1020004D02*
X1522577Y1019993D01*
X1522823Y1020234D01*
X1528822D01*
X1529714Y1021126D01*
Y1021930D01*
X1530961Y1023177D01*
X1531844D01*
X1532991Y1024324D01*
G01X1519703Y1016800D02*
X1520975Y1017319D01*
X1521782D01*
X1522361Y1017898D01*
X1522671Y1018077D01*
G02X1523571Y1018319I900J-1553D01*
G01X1525621D01*
X1527456Y1017559D01*
X1529622D01*
X1534639Y1022576D01*
G01X1516003Y1023208D02*
X1516443Y1023026D01*
X1517423D01*
X1517930Y1023533D01*
Y1023769D01*
X1518207Y1024046D01*
G03X1518266Y1024078I-401J809D01*
G01X1518942Y1024469D01*
X1518966Y1024485D01*
G02X1520440I737J-1277D01*
G03X1520443Y1024487I-545J821D01*
G03X1522664Y1024486I1111J1926D01*
G02X1523403Y1024684I739J-1278D01*
G01X1526396Y1025095D01*
X1526892Y1025338D01*
X1528450Y1026896D01*
X1529017D01*
X1529512Y1027391D01*
Y1027958D01*
X1530006Y1028452D01*
X1530572D01*
X1531067Y1028947D01*
Y1029513D01*
X1531764Y1030210D01*
X1531942D01*
G01X1523403Y1023208D02*
X1523361Y1023166D01*
Y1022889D01*
X1523759Y1022491D01*
X1524124D01*
X1524125Y1022490D01*
X1526381D01*
X1526946Y1023055D01*
Y1023622D01*
X1527512Y1024188D01*
X1528079D01*
X1528644Y1024753D01*
Y1025320D01*
X1529210Y1025886D01*
X1529777D01*
X1530342Y1026451D01*
Y1027018D01*
X1530908Y1027584D01*
X1531475D01*
X1531907Y1028016D01*
Y1028583D01*
X1532288Y1028964D01*
X1532852D01*
X1535308Y1031413D01*
X1535305Y1031592D01*
X1535366Y1031653D01*
G01X1512303Y1023208D02*
X1515681Y1024664D01*
G02X1516021Y1024734I339J-788D01*
G01X1516850D01*
G02X1517234Y1024690I-4J-1736D01*
G03X1518029Y1024811I243J1074D01*
G01X1518594Y1025137D01*
X1518590Y1025136D01*
X1518631Y1025160D01*
G02X1520817Y1025136I1072J-1952D01*
G03X1522291I737J1277D01*
G02X1523347Y1025433I1112J-1928D01*
G01X1526174Y1025821D01*
X1526450Y1025957D01*
X1531234Y1030740D01*
Y1030918D01*
G01X1519703Y1023208D02*
X1521640Y1022468D01*
G02X1522639Y1021948I-9282J-19051D01*
G01X1522667Y1021932D01*
G02X1522701Y1021913I-1068J-1951D01*
G03X1523166Y1021760I571J954D01*
G03X1523757Y1021732I593J6264D01*
G01X1524125Y1021741D01*
X1526692D01*
X1534287Y1029336D01*
X1535846Y1030890D01*
X1536021Y1030892D01*
X1536082Y1030953D01*
G01X1514154Y1045639D02*
X1513739Y1046652D01*
X1513740Y1046890D01*
X1514090Y1047239D01*
X1518445D01*
X1519158Y1046526D01*
X1520530D01*
X1521243Y1047239D01*
X1522205D01*
X1527041Y1052075D01*
G01X1521554Y1045639D02*
X1522833Y1046169D01*
X1529240Y1052576D01*
G01X1514154Y1039230D02*
X1513212Y1039620D01*
X1512158D01*
X1511858Y1039920D01*
Y1040596D01*
X1512251Y1040989D01*
X1513095D01*
G02X1514896Y1040507I0J-3605D01*
G01X1515096Y1040390D01*
X1515766Y1039720D01*
X1516262D01*
X1516889Y1040347D01*
X1517709Y1040819D01*
X1518205Y1041315D01*
X1518647D01*
X1518961Y1041001D01*
Y1040171D01*
X1519312Y1039820D01*
X1519846D01*
X1520712Y1040686D01*
X1521620D01*
G02X1522427Y1040467I0J-1596D01*
G01X1523506Y1039835D01*
X1525135D01*
X1527059Y1041759D01*
G01X1516003Y1036026D02*
X1517137Y1036496D01*
X1518523Y1037882D01*
X1520298D01*
X1520661Y1037519D01*
X1520985D01*
G03X1522022Y1037798I-1J2070D01*
G01X1522291Y1037953D01*
G02X1523403Y1038251I1112J-1926D01*
G01X1526948D01*
X1531007Y1042310D01*
G01X1521554Y1039230D02*
X1522647Y1039241D01*
X1522873Y1039019D01*
X1526017D01*
X1530157Y1043159D01*
G01X1519703Y1036026D02*
G03X1521479Y1036546I-117J3693D01*
G01X1522608Y1037269D01*
G02X1523403Y1037502I796J-1243D01*
G01X1524730D01*
X1525112Y1037120D01*
X1527516D01*
X1531856Y1041460D01*
G01X1512303Y1042434D02*
X1514702Y1041482D01*
X1515445Y1041118D01*
G03X1517035Y1041375I585J1426D01*
G01X1518601Y1043397D01*
G02X1518931Y1043691I976J-764D01*
G01X1518941Y1043696D01*
X1518950Y1043702D01*
X1518958Y1043706D01*
X1518966Y1043711D01*
G02X1520440I737J-1277D01*
G03X1523301Y1044039I1209J2093D01*
G01X1524333Y1044592D01*
X1529429Y1049688D01*
X1529607D01*
X1529668Y1049749D01*
G01X1523403Y1042434D02*
Y1042376D01*
X1523753Y1042026D01*
X1524248D01*
X1524704Y1042482D01*
Y1043034D01*
X1525128Y1043459D01*
X1525681D01*
X1526105Y1043883D01*
Y1044435D01*
X1526529Y1044860D01*
X1527082D01*
X1527503Y1045281D01*
Y1045836D01*
X1527930Y1046261D01*
X1528484D01*
X1530520Y1048297D01*
Y1048475D01*
X1530581Y1048536D01*
G01X1516003Y1042434D02*
X1516653Y1042261D01*
X1517130Y1042738D01*
Y1043508D01*
X1517675Y1044053D01*
X1518175D01*
G02X1518179Y1044049I-1571J-1575D01*
G02X1518540Y1044330I1395J-1419D01*
G01X1518541Y1044331D01*
X1518586Y1044357D01*
X1518592Y1044360D01*
G02X1520815I1111J-1926D01*
G03X1522789Y1044586I835J1444D01*
G01X1522860Y1044654D01*
X1523881Y1045201D01*
X1524446Y1045766D01*
Y1046049D01*
X1525013Y1046616D01*
X1525296D01*
X1526131Y1047451D01*
Y1047734D01*
X1526698Y1048301D01*
X1526982D01*
X1528899Y1050218D01*
Y1050396D01*
X1528960Y1050457D01*
G01X1519703Y1042434D02*
X1523023Y1041048D01*
X1524141D01*
X1524465Y1041182D01*
X1529015Y1045731D01*
X1529014D01*
X1531050Y1047767D01*
X1531228D01*
X1531289Y1047828D01*
G01X1521554Y1058455D02*
Y1058255D01*
X1521930Y1057879D01*
X1523099D01*
X1528546Y1063331D01*
Y1065398D01*
X1529582Y1066434D01*
G01X1516003Y1055251D02*
X1515826Y1055298D01*
X1515344Y1056134D01*
X1515478Y1056628D01*
G02X1516740Y1056528I526J-1377D01*
G03X1518966I1113J1927D01*
G02X1520599Y1056443I751J-1300D01*
G01X1520661Y1056381D01*
X1523722D01*
X1529976Y1062635D01*
X1530106Y1062948D01*
Y1063556D01*
X1530483Y1063933D01*
G01X1514154Y1058455D02*
X1514115Y1058310D01*
X1514620Y1057434D01*
X1515130Y1057299D01*
G02X1517116Y1057178I872J-2047D01*
G03X1518590I737J1277D01*
G01X1518826Y1057314D01*
G02X1519651Y1057535I825J-1429D01*
G01X1520207D01*
X1521185Y1057130D01*
X1523410D01*
X1529296Y1063016D01*
Y1064444D01*
X1530434Y1065582D01*
G01X1519703Y1055251D02*
X1520623Y1055632D01*
X1522521D01*
X1523030Y1055123D01*
X1523524D01*
X1530916Y1062513D01*
Y1062667D01*
X1531333Y1063084D01*
G01X1516003Y1048842D02*
X1515833Y1048672D01*
X1514379D01*
X1514032Y1049019D01*
Y1049717D01*
X1514701Y1050386D01*
X1521009D01*
X1522726Y1050837D01*
X1523987Y1052098D01*
Y1052417D01*
X1525343Y1053773D01*
G01X1519703Y1048842D02*
X1520685Y1049029D01*
X1523340Y1050072D01*
X1526192Y1052924D01*
G01X1512303Y1061660D02*
X1514935Y1062779D01*
X1514934Y1062782D01*
G03X1515708Y1063281I-778J2056D01*
G03X1516351Y1064399I-1750J1750D01*
G01X1516352D01*
G03X1516426Y1064914I-2210J580D01*
G02X1517108Y1066125I1503J-49D01*
G01X1517121Y1066133D01*
X1517126Y1066135D01*
G02X1517289Y1066215I405J-619D01*
G02X1519281Y1065220I510J-1470D01*
G01X1519341Y1065030D01*
Y1065028D01*
G02X1519375Y1064852I-711J-229D01*
G03X1521593Y1062785I2218J157D01*
G01X1522028D01*
G03X1522902Y1063005I2J1838D01*
G01X1522919Y1063015D01*
G03X1523448Y1063421I-1157J2055D01*
G01X1523450Y1063423D01*
X1523449D01*
G03X1524040Y1064764I-1252J1352D01*
G02X1524157Y1065324I1519J-25D01*
G01X1524210Y1065449D01*
X1524300Y1065611D01*
X1524330Y1065680D01*
X1524344Y1065714D01*
X1525552Y1067524D01*
X1526177Y1068369D01*
X1526616Y1068808D01*
X1526720D01*
G01X1517853Y1064864D02*
X1517242Y1063805D01*
X1517341Y1063439D01*
G02X1517407Y1063387I-1344J-1774D01*
G02X1518228Y1061699I-1404J-1726D01*
G01Y1061660D01*
G03X1518613Y1060732I1313J1D01*
G01X1518699Y1060645D01*
G03X1519689Y1060235I990J990D01*
G01X1520099D01*
G03X1520370Y1060302I1J579D01*
G02X1521346Y1060546I977J-1833D01*
G01X1523026D01*
X1524063Y1060976D01*
X1526630Y1063542D01*
X1527039Y1064526D01*
Y1066432D01*
X1527417Y1067347D01*
X1527689Y1067618D01*
X1528094Y1068023D01*
Y1068201D01*
X1528155Y1068262D01*
G01X1516003Y1061660D02*
X1516614Y1062719D01*
X1516933Y1062804D01*
X1516934Y1062806D01*
G02X1517479Y1061686I-931J-1146D01*
G01Y1061662D01*
G03Y1061635I2224J-14D01*
G03X1518081Y1060203I2062J24D01*
G01X1518167Y1060116D01*
G03X1519690Y1059486I1520J1519D01*
G01X1520100D01*
G03X1520723Y1059641I0J1328D01*
G02X1521347Y1059797I624J-1171D01*
G01X1523176D01*
X1524488Y1060340D01*
X1527265Y1063117D01*
X1527788Y1064376D01*
Y1066283D01*
X1528053Y1066922D01*
X1528624Y1067493D01*
X1528802D01*
X1528863Y1067554D01*
G01X1516003Y1074477D02*
X1516012D01*
X1517442Y1075907D01*
X1518562D01*
X1519412Y1076757D01*
X1519847D01*
X1521849Y1075928D01*
X1522423D01*
X1527621Y1078081D01*
X1529978Y1080438D01*
G01X1516003Y1068068D02*
X1514967Y1068497D01*
X1514501Y1068963D01*
Y1069457D01*
X1515602Y1070558D01*
X1516180D01*
X1517168Y1069570D01*
X1519358D01*
X1519895Y1070107D01*
Y1071620D01*
X1520367Y1072092D01*
X1521163Y1072682D01*
X1521817Y1073096D01*
X1523440Y1073769D01*
X1525112D01*
X1527832Y1074896D01*
X1528127Y1075191D01*
G01X1517853Y1071273D02*
X1518918Y1072211D01*
X1523650Y1075349D01*
X1528662Y1077424D01*
X1530827Y1079589D01*
G01X1521554Y1064864D02*
X1521758D01*
X1522639Y1065745D01*
X1523153Y1066986D01*
X1523062Y1067206D01*
X1523449Y1068139D01*
X1524673Y1069363D01*
X1524814Y1069704D01*
X1524878Y1070025D01*
Y1070242D01*
X1532526Y1077890D01*
G01X1512303Y1080885D02*
G02X1512370Y1080867I0J-133D01*
G01X1515078Y1079283D01*
G03X1516928I925J1602D01*
G02X1518778I925J-1602D01*
G03X1520628I925J1602D01*
G02X1520664Y1079297I60J-102D01*
G01X1521111Y1079386D01*
X1524178D01*
X1526859Y1082067D01*
Y1082409D01*
X1527783Y1083333D01*
G01X1521554Y1077681D02*
X1523521D01*
X1524054Y1077902D01*
X1528634Y1082482D01*
G01X1514154Y1064864D02*
X1513543Y1063805D01*
X1513629Y1063487D01*
G03X1514127Y1063390I527J1377D01*
G03X1514669Y1063483I31J1448D01*
G03X1515178Y1063812I-514J1354D01*
G03X1515627Y1064591I-1219J1221D01*
G03X1515677Y1064937I-1485J391D01*
G02X1516698Y1066752I2252J-72D01*
G01X1516717Y1066764D01*
G02X1517045Y1066924I812J-1249D01*
G02X1519995Y1065448I754J-2179D01*
G01Y1065447D01*
X1520055Y1065257D01*
G02X1520123Y1064905I-1425J-458D01*
G03X1521593Y1063534I1470J103D01*
G01X1522028D01*
G03X1522544Y1063664I0J1088D01*
G01X1522555Y1063670D01*
G03X1522914Y1063948I-795J1398D01*
G01X1522923Y1063957D01*
G03X1522931Y1063965I-1040J1048D01*
G03X1523291Y1064772I-734J811D01*
G02X1523466Y1065613I2268J-33D01*
G01X1523534Y1065775D01*
X1523623Y1065935D01*
Y1065937D01*
X1523625Y1065939D01*
X1523681Y1066071D01*
X1524939Y1067955D01*
X1525607Y1068860D01*
X1525926Y1069179D01*
X1526032Y1069435D01*
Y1069536D01*
G01X1516003Y1093703D02*
X1516379Y1094611D01*
Y1096941D01*
G02X1517116Y1098184I1474J-34D01*
G02X1518590I737J-1277D01*
G01X1518631Y1098160D01*
G03X1520817Y1098184I1072J1951D01*
G01X1520850Y1098217D01*
X1521623Y1098537D01*
X1522345D01*
X1523684Y1099092D01*
X1524743Y1100151D01*
X1525896Y1102933D01*
X1526286Y1104892D01*
Y1106549D01*
G01X1521554Y1090498D02*
X1521911Y1090559D01*
X1524760Y1094582D01*
X1525497Y1096352D01*
X1525776Y1097933D01*
Y1098742D01*
X1526916Y1102499D01*
X1527486Y1105351D01*
Y1106549D01*
G01X1514154Y1084090D02*
G03X1516288Y1082708I4299J4300D01*
G01X1517195Y1082362D01*
G03X1518778Y1082488I659J1729D01*
G02X1520137Y1082685I926J-1602D01*
G01X1522900Y1081518D01*
X1524033D01*
X1524661Y1082146D01*
X1525573Y1084346D01*
X1525960Y1084926D01*
X1527026Y1085992D01*
G01X1519703Y1080885D02*
X1520952Y1080368D01*
X1523955D01*
X1525587Y1082000D01*
X1526186Y1083446D01*
X1527879Y1085139D01*
G01X1519703Y1087294D02*
X1519301Y1087402D01*
X1518984Y1087952D01*
X1519178Y1088671D01*
G02X1520440Y1088571I526J-1377D01*
G03X1521423Y1088276I1114J1927D01*
G03X1521550Y1088273I116J2222D01*
G03X1521552I1J2224D01*
G01X1522402D01*
X1523608Y1088773D01*
Y1088774D01*
X1524409Y1089575D01*
Y1090361D01*
X1525151Y1091103D01*
X1525329D01*
X1525390Y1091164D01*
G01X1516003Y1087294D02*
X1519225Y1085918D01*
G03X1520116Y1085898I470J1100D01*
G01X1522190Y1086679D01*
X1523680Y1087297D01*
X1525782Y1088421D01*
X1526613Y1089252D01*
Y1089428D01*
X1526674Y1089489D01*
G01X1517853Y1090498D02*
X1517752Y1090121D01*
X1518088Y1089539D01*
X1518829Y1089342D01*
G02X1518910Y1089375I880J-2045D01*
G02X1520817Y1089221I792J-2080D01*
G03X1521468Y1089025I739J1276D01*
G03X1521554Y1089022I94J1472D01*
G01X1522252D01*
X1523183Y1089409D01*
X1523660Y1089886D01*
Y1090672D01*
X1524621Y1091633D01*
Y1091811D01*
X1524682Y1091872D01*
G01X1517853Y1084090D02*
X1519674Y1085044D01*
X1519785Y1085074D01*
G03X1520380Y1085196I-88J1943D01*
G01X1522452Y1085976D01*
Y1085977D01*
X1522462Y1085981D01*
X1522461Y1085980D01*
X1522477Y1085987D01*
X1524001Y1086619D01*
X1526234Y1087813D01*
X1527141Y1088720D01*
X1527321D01*
X1527382Y1088781D01*
G01X1514154Y1096907D02*
G02X1516490Y1098691I7828J-7829D01*
G01X1516775Y1098854D01*
G03X1517478Y1100111I-772J1257D01*
G01Y1100184D01*
G02X1518590Y1102039I2225J-73D01*
G01X1518631Y1102063D01*
G02X1520687Y1102109I1072J-1952D01*
G03X1521670Y1101880I984J1997D01*
G01X1522488D01*
G03X1522802Y1102010I0J444D01*
G01X1523401Y1102609D01*
X1523886Y1103779D01*
Y1106549D01*
G01X1519703Y1100111D02*
X1522395Y1100403D01*
X1524360Y1102368D01*
X1525086Y1104120D01*
Y1106549D01*
G54D338*
G01X44967Y420010D02*
Y421639D01*
X47150Y423822D01*
Y427616D01*
X45960Y428806D01*
G01X44967Y416860D02*
X46371D01*
X47618Y415613D01*
G01X44967Y413710D02*
Y413378D01*
X47326Y411019D01*
Y410400D01*
X49357Y408364D01*
Y406260D01*
G01X70657Y32756D02*
Y30549D01*
X69990Y29882D01*
Y25381D01*
X68611Y24002D01*
X63439D01*
X57680Y29761D01*
Y45392D01*
X51860Y51212D01*
Y57190D01*
X50308Y58742D01*
G01X68295Y32756D02*
Y30677D01*
X68970Y30002D01*
Y25804D01*
X68188Y25022D01*
X67290D01*
X66800Y25512D01*
X65300D01*
X64810Y25022D01*
X63862D01*
X62093Y26791D01*
Y27484D01*
X61032Y28545D01*
X60339D01*
X58700Y30184D01*
Y31684D01*
X59190Y32174D01*
Y33674D01*
X58700Y34164D01*
Y35664D01*
X59190Y36154D01*
Y37654D01*
X58700Y38144D01*
Y39644D01*
X59190Y40134D01*
Y41634D01*
X58700Y42124D01*
Y45815D01*
X57640Y46875D01*
Y47568D01*
X56578Y48630D01*
X55885D01*
X55106Y49409D01*
Y50102D01*
X54044Y51164D01*
X53351D01*
X52880Y51635D01*
Y53112D01*
X53370Y53602D01*
Y55102D01*
X52880Y55592D01*
Y57002D01*
X54620Y58742D01*
G01X75382Y44370D02*
Y46526D01*
X76057Y47201D01*
Y48986D01*
X71181Y53862D01*
X67016D01*
X62357Y58521D01*
Y61034D01*
X61057Y62334D01*
G01X61157Y69340D02*
X62342Y68155D01*
Y65719D01*
X61057Y64434D01*
G01X60220Y80860D02*
Y78750D01*
X57396Y75926D01*
Y72650D01*
X51954Y67208D01*
Y63538D01*
X50308Y61892D01*
G01X63048Y78031D02*
X60938D01*
Y78025D01*
X58416Y75503D01*
Y72227D01*
X52974Y66785D01*
Y63538D01*
X54620Y61892D01*
G01X60220Y80860D02*
X62325D01*
X63126Y81661D01*
X63130D01*
Y82159D01*
X62660Y82629D01*
Y83432D01*
X61470Y84622D01*
G01X57342Y399799D02*
Y400599D01*
X56868Y401073D01*
Y403608D01*
X54381Y406095D01*
X53068D01*
X52185Y406978D01*
Y409088D01*
G01X50339Y413795D02*
Y413336D01*
X48346Y411343D01*
Y410823D01*
X50081Y409088D01*
X52185D01*
G01X55374Y399799D02*
Y400575D01*
X55848Y401049D01*
Y403185D01*
X53958Y405075D01*
X52645D01*
X51467Y406253D01*
Y406260D01*
X49357D01*
G01X64922Y405732D02*
X63232Y404042D01*
Y402730D01*
X62382Y401880D01*
X61044D01*
X60790Y401626D01*
Y401072D01*
X61280Y400582D01*
Y399799D01*
G01X60522Y405732D02*
X62212Y404042D01*
Y403153D01*
X61959Y402900D01*
X60621D01*
X59770Y402049D01*
Y401072D01*
X59311Y400613D01*
Y399799D01*
G01X60189Y410770D02*
Y409965D01*
X62212Y407942D01*
Y407422D01*
X60522Y405732D01*
G01X60189Y413920D02*
X58429D01*
X58421Y413928D01*
X56163D01*
G01X60189Y413920D02*
X60793D01*
X62623Y415750D01*
X62813D01*
G01X50339Y420095D02*
Y421653D01*
X48170Y423822D01*
Y427616D01*
X49360Y428806D01*
G01X61171D02*
X62361Y427616D01*
Y423994D01*
X60182Y421815D01*
Y421746D01*
G01X60189Y417070D02*
X60154Y418437D01*
X61372Y419715D01*
X62348Y420691D01*
Y421228D01*
X61830Y421746D01*
X60182D01*
G01X50339Y416945D02*
X49329D01*
X47619Y418655D01*
G01X77744Y32756D02*
X77745Y32755D01*
Y30627D01*
X77079Y29961D01*
Y27664D01*
X78269Y26474D01*
G01X75382Y32756D02*
Y30691D01*
X76059Y30014D01*
Y27664D01*
X74869Y26474D01*
G01X77744Y44370D02*
Y46559D01*
X77077Y47226D01*
Y49409D01*
X71604Y54882D01*
X67439D01*
X63377Y58944D01*
Y61054D01*
X64657Y62334D01*
G01X82468Y44370D02*
Y46526D01*
X83143Y47201D01*
Y49910D01*
X73347Y59706D01*
Y67044D01*
X72057Y68334D01*
G01X84831Y44370D02*
Y46522D01*
X84173Y47180D01*
Y47191D01*
X84163Y47201D01*
Y50333D01*
X74367Y60129D01*
Y67044D01*
X75657Y68334D01*
G01X72157Y75340D02*
X73342Y74155D01*
Y71719D01*
X72057Y70434D01*
G01X64557Y69340D02*
X63362Y68145D01*
Y65729D01*
X64657Y64434D01*
G01X75557Y75340D02*
X74362Y74145D01*
Y71729D01*
X75657Y70434D01*
G01X63048Y78031D02*
Y80136D01*
X64150Y81238D01*
Y82582D01*
X63680Y83052D01*
Y83432D01*
X64870Y84622D01*
G01X65533Y414040D02*
X64144D01*
X62812Y412708D01*
G01X65533Y410890D02*
Y410370D01*
X63232Y408069D01*
Y407422D01*
X64922Y405732D01*
G01X65533Y414040D02*
X67293D01*
X67313Y414020D01*
X69431D01*
X69523Y413928D01*
G01X64571Y428806D02*
X63381Y427616D01*
Y423994D01*
X65533Y421842D01*
Y421746D01*
G01Y417190D02*
X65501Y418563D01*
X63368Y420603D01*
Y421350D01*
X63764Y421746D01*
X65533D01*
G01X75585Y1517581D02*
X77091D01*
X78120Y1518610D01*
Y1518836D01*
G01X75585Y1514431D02*
Y1512777D01*
X75638Y1512724D01*
X77610Y1510749D01*
Y1508697D01*
X76369Y1507456D01*
G01X75585Y1520731D02*
Y1521432D01*
X77643Y1523490D01*
Y1525483D01*
X81040Y1528880D01*
Y1531809D01*
X80762Y1532087D01*
Y1533173D01*
G01X73389Y1557522D02*
Y1556213D01*
X73441Y1556161D01*
X75417Y1554182D01*
Y1553593D01*
X80920Y1548090D01*
Y1544470D01*
X80762Y1544312D01*
Y1543015D01*
G01X78456Y1557527D02*
Y1556309D01*
X78408Y1556261D01*
X76437Y1554286D01*
Y1554016D01*
X81940Y1548513D01*
Y1544557D01*
X82337Y1544160D01*
Y1543015D01*
G01X78456Y1563827D02*
Y1565434D01*
X76440Y1567450D01*
Y1570566D01*
X76428Y1570578D01*
Y1571314D01*
X77618Y1572504D01*
G01X73389Y1563822D02*
Y1565259D01*
X75420Y1567290D01*
Y1570143D01*
X75408Y1570155D01*
Y1571314D01*
X74218Y1572504D01*
G01X84831Y32756D02*
Y30613D01*
X84180Y29962D01*
Y20732D01*
X85374Y19538D01*
G01X82468Y32756D02*
Y30655D01*
X83160Y29963D01*
Y20724D01*
X81974Y19538D01*
G01X91917Y32756D02*
Y30626D01*
X91252Y29961D01*
Y27664D01*
X92442Y26474D01*
G01X89555Y32756D02*
Y30691D01*
X90232Y30014D01*
Y27664D01*
X89042Y26474D01*
G01X91917Y44370D02*
Y46544D01*
X91260Y47201D01*
Y52132D01*
X85377Y58015D01*
Y61054D01*
X86657Y62334D01*
G01X89555Y44370D02*
Y46526D01*
X90240Y47211D01*
Y51709D01*
X84357Y57592D01*
Y61034D01*
X83057Y62334D01*
G01X96642Y44370D02*
Y46526D01*
X97317Y47201D01*
Y53164D01*
X95347Y55134D01*
Y67044D01*
X94057Y68334D01*
G01X94157Y75340D02*
X95342Y74155D01*
Y71719D01*
X94057Y70434D01*
G01X86557Y69340D02*
X85362Y68145D01*
Y65729D01*
X86657Y64434D01*
G01X83157Y69340D02*
X84342Y68155D01*
Y65719D01*
X83057Y64434D01*
G01X80652Y1517586D02*
X80270D01*
X78120Y1515436D01*
G01X88426Y1514087D02*
Y1512795D01*
X90454Y1510767D01*
Y1508801D01*
X89264Y1507611D01*
G01X93571Y1514087D02*
Y1512841D01*
X91474Y1510744D01*
Y1508801D01*
X92664Y1507611D01*
G01X80652Y1514436D02*
Y1512683D01*
X78630Y1510659D01*
Y1508595D01*
X79769Y1507456D01*
G01X90211Y1533173D02*
Y1532229D01*
X90489Y1531951D01*
Y1524110D01*
X88426Y1522047D01*
Y1520387D01*
G01X91786Y1533173D02*
Y1532246D01*
X91509Y1531969D01*
Y1524109D01*
X93571Y1522047D01*
Y1520387D01*
G01X80652Y1520736D02*
Y1521501D01*
X78663Y1523490D01*
Y1525060D01*
X82060Y1528457D01*
Y1531829D01*
X82337Y1532106D01*
Y1533173D01*
G01X97183Y1560973D02*
Y1559364D01*
X99410Y1557134D01*
Y1556470D01*
X90489Y1547549D01*
Y1545495D01*
X90211Y1545217D01*
Y1543015D01*
G01X102250Y1560978D02*
Y1559002D01*
X102204Y1558956D01*
X100430Y1557178D01*
Y1556047D01*
X91509Y1547126D01*
Y1545495D01*
X91786Y1545218D01*
Y1543015D01*
G01X99004Y32756D02*
Y30613D01*
X98353Y29962D01*
Y20732D01*
X99547Y19538D01*
G01X110815Y32756D02*
Y30654D01*
X111506Y29963D01*
Y20724D01*
X110320Y19538D01*
G01X96642Y32756D02*
Y30654D01*
X97333Y29963D01*
Y20724D01*
X96147Y19538D01*
G01X106090Y32756D02*
Y30626D01*
X105425Y29961D01*
Y27664D01*
X106615Y26474D01*
G01X103728Y32756D02*
Y30691D01*
X104405Y30014D01*
Y27664D01*
X103215Y26474D01*
G01X106090Y44370D02*
Y46551D01*
X105433Y47208D01*
Y54725D01*
X107377Y56669D01*
Y61054D01*
X108657Y62334D01*
G01X103728Y44370D02*
Y46526D01*
X104403Y47201D01*
Y47205D01*
X104413Y47215D01*
Y55148D01*
X106357Y57092D01*
Y61034D01*
X105057Y62334D01*
G01X99004Y44370D02*
Y46437D01*
X98347Y47094D01*
Y47191D01*
X98337Y47201D01*
Y53587D01*
X96367Y55557D01*
Y67044D01*
X97657Y68334D01*
G01X108557Y69340D02*
X107362Y68145D01*
Y65729D01*
X108657Y64434D01*
G01X105157Y69340D02*
X106342Y68155D01*
Y65719D01*
X105057Y64434D01*
G01X97557Y75340D02*
X96362Y74145D01*
Y71729D01*
X97657Y70434D01*
G01X99750Y1565378D02*
X98495Y1564123D01*
X97183D01*
G01X99750Y1561978D02*
X101900Y1564128D01*
X102250D01*
G01X97183Y1567273D02*
Y1568062D01*
X99530Y1570409D01*
Y1570871D01*
X103441Y1574782D01*
Y1575314D01*
X102251Y1576504D01*
G01X102250Y1567278D02*
Y1568281D01*
X100550Y1569981D01*
Y1570448D01*
X104461Y1574359D01*
Y1575314D01*
X105651Y1576504D01*
G01X113177Y32756D02*
Y30613D01*
X112526Y29962D01*
Y20732D01*
X113720Y19538D01*
G01X127350Y32756D02*
Y30613D01*
X126700Y29963D01*
Y20732D01*
X127894Y19538D01*
G01X124988Y32756D02*
Y30654D01*
X125680Y29962D01*
Y20724D01*
X124494Y19538D01*
G01X120264Y32756D02*
Y30626D01*
X119599Y29961D01*
Y27664D01*
X120789Y26474D01*
G01X117902Y32756D02*
Y30691D01*
X118579Y30014D01*
Y27664D01*
X117389Y26474D01*
G01X110815Y44370D02*
Y46526D01*
X111500Y47211D01*
Y54405D01*
X117357Y60262D01*
Y67034D01*
X116057Y68334D01*
G01X124988Y44370D02*
Y46526D01*
X125673Y47211D01*
Y49488D01*
X139357Y63172D01*
Y67034D01*
X138057Y68334D01*
G01X120264Y44370D02*
Y46579D01*
X119607Y47236D01*
Y50069D01*
X129377Y59839D01*
Y61054D01*
X130657Y62334D01*
G01X113177Y44370D02*
Y46525D01*
X112520Y47182D01*
Y53982D01*
X118377Y59839D01*
Y67054D01*
X119657Y68334D01*
G01X127350Y44370D02*
Y46561D01*
X126693Y47218D01*
Y49065D01*
X140377Y62749D01*
Y67054D01*
X141657Y68334D01*
G01X117902Y44370D02*
Y46526D01*
X118577Y47201D01*
Y47226D01*
X118587Y47236D01*
Y50492D01*
X128357Y60262D01*
Y61034D01*
X127057Y62334D01*
G01X116157Y75340D02*
X117342Y74155D01*
Y71719D01*
X116057Y70434D01*
G01X119557Y75340D02*
X118362Y74145D01*
Y71729D01*
X119657Y70434D01*
G01X138157Y75340D02*
X139342Y74155D01*
Y71719D01*
X138057Y70434D01*
G01X130557Y69340D02*
X129362Y68145D01*
Y65729D01*
X130657Y64434D01*
G01X141557Y75340D02*
X140362Y74145D01*
Y71729D01*
X141657Y70434D01*
G01X127157Y69340D02*
X128342Y68155D01*
Y65719D01*
X127057Y64434D01*
G01X156130Y32756D02*
Y30626D01*
X155465Y29961D01*
Y27664D01*
X156655Y26474D01*
G01X153768Y32756D02*
Y30691D01*
X154445Y30014D01*
Y27664D01*
X153255Y26474D01*
G01X156130Y44370D02*
Y46473D01*
X155473Y47130D01*
Y53379D01*
X151377Y57475D01*
Y61054D01*
X152657Y62334D01*
G01X153768Y44370D02*
Y46526D01*
X154453Y47211D01*
Y52956D01*
X150357Y57052D01*
Y61034D01*
X149057Y62334D01*
G01X152557Y69340D02*
X151362Y68145D01*
Y65729D01*
X152657Y64434D01*
G01X149157Y69340D02*
X150342Y68155D01*
Y65719D01*
X149057Y64434D01*
G01X145538Y1517374D02*
X146728Y1518564D01*
Y1524908D01*
X148672Y1529602D01*
X152876Y1533806D01*
Y1536394D01*
X152402Y1536868D01*
Y1537521D01*
G01X148938Y1517374D02*
X147748Y1518564D01*
Y1524705D01*
X149537Y1529024D01*
X153896Y1533383D01*
Y1536346D01*
X154370Y1536820D01*
Y1537521D01*
G01X146312Y1569525D02*
X147530Y1568307D01*
Y1560070D01*
X152876Y1554724D01*
Y1553656D01*
X152402Y1553182D01*
Y1552481D01*
G01X149712Y1569525D02*
X148550Y1568363D01*
Y1560493D01*
X153896Y1555147D01*
Y1553694D01*
X154370Y1553220D01*
Y1552481D01*
G01X163216Y32756D02*
Y30613D01*
X162575Y29972D01*
Y20722D01*
X163759Y19538D01*
X163760D01*
G01X175028Y32756D02*
Y30654D01*
X175719Y29963D01*
Y20724D01*
X174533Y19538D01*
G01X160854Y32756D02*
Y30654D01*
X161555Y29953D01*
Y20733D01*
X160360Y19538D01*
G01X170303Y32756D02*
Y30626D01*
X169638Y29961D01*
Y27664D01*
X170828Y26474D01*
G01X167941Y32756D02*
Y30691D01*
X168618Y30014D01*
Y27664D01*
X167428Y26474D01*
G01X175028Y44370D02*
Y46526D01*
X175703Y47201D01*
Y50664D01*
X184551Y59512D01*
Y67044D01*
X183261Y68334D01*
G01X170303Y44370D02*
Y46519D01*
X169646Y47176D01*
Y53748D01*
X174581Y58683D01*
Y61054D01*
X175861Y62334D01*
G01X160854Y44370D02*
Y46526D01*
X161539Y47211D01*
Y55734D01*
X162561Y56756D01*
Y67034D01*
X161261Y68334D01*
G01X167941Y44370D02*
Y46526D01*
X168626Y47211D01*
Y54171D01*
X173561Y59106D01*
Y61034D01*
X172261Y62334D01*
G01X163216Y44370D02*
Y46587D01*
X162559Y47244D01*
Y55311D01*
X163581Y56333D01*
Y67054D01*
X164861Y68334D01*
G01X175761Y69340D02*
X174566Y68145D01*
Y65729D01*
X175861Y64434D01*
G01X161361Y75340D02*
X162546Y74155D01*
Y71719D01*
X161261Y70434D01*
G01X172361Y69340D02*
X173546Y68155D01*
Y65719D01*
X172261Y64434D01*
G01X164761Y75340D02*
X163566Y74145D01*
Y71729D01*
X164861Y70434D01*
G01X164710Y1518014D02*
X165910Y1519214D01*
Y1525830D01*
X163851Y1530800D01*
X160750Y1533901D01*
Y1536320D01*
X160276Y1536794D01*
Y1537521D01*
G01X162244D02*
Y1536824D01*
X161770Y1536350D01*
Y1534324D01*
X164716Y1531378D01*
X166930Y1526033D01*
Y1519194D01*
X168110Y1518014D01*
G01X167266Y1569968D02*
X168560Y1568674D01*
Y1565310D01*
X166709Y1560842D01*
X160750Y1554883D01*
Y1553670D01*
X160276Y1553196D01*
Y1552481D01*
G01X170666Y1569968D02*
X169580Y1568882D01*
Y1565107D01*
X167574Y1560264D01*
X161770Y1554460D01*
Y1553660D01*
X162244Y1553186D01*
Y1552481D01*
G01X177390Y32756D02*
Y30613D01*
X176739Y29962D01*
Y20732D01*
X177933Y19538D01*
G01X177390Y44370D02*
Y46582D01*
X176723Y47249D01*
Y50241D01*
X185571Y59089D01*
Y67044D01*
X186861Y68334D01*
G01X183361Y75340D02*
X184546Y74155D01*
Y71719D01*
X183261Y70434D01*
G01X186761Y75340D02*
X185566Y74145D01*
Y71729D01*
X186861Y70434D01*
G01X188797Y1583088D02*
X188815D01*
X190100Y1581803D01*
Y1579385D01*
X188897Y1578182D01*
G01X192397Y1583088D02*
X191120Y1581811D01*
Y1579359D01*
X192297Y1578182D01*
G01X188797Y1585188D02*
X188810D01*
X190090Y1586468D01*
Y1588901D01*
X188897Y1590094D01*
G01X192397Y1585188D02*
X191110Y1586475D01*
Y1588907D01*
X192297Y1590094D01*
G01X207350Y32756D02*
Y30613D01*
X206700Y29963D01*
Y20732D01*
X207894Y19538D01*
G01X204988Y32756D02*
Y30654D01*
X205680Y29962D01*
Y20724D01*
X204494Y19538D01*
G01X200264Y32756D02*
Y30626D01*
X199599Y29961D01*
Y27664D01*
X200789Y26474D01*
G01X197902Y32756D02*
Y30691D01*
X198579Y30014D01*
Y27664D01*
X197389Y26474D01*
G01X204988Y44370D02*
Y46526D01*
X205663Y47201D01*
Y55744D01*
X206685Y56766D01*
Y67044D01*
X205395Y68334D01*
G01X200264Y44370D02*
Y46518D01*
X199597Y47185D01*
Y54127D01*
X196571Y57153D01*
Y61039D01*
X196581Y61049D01*
Y61054D01*
X197861Y62334D01*
G01X207350Y44370D02*
Y46593D01*
X206683Y47260D01*
Y55321D01*
X207705Y56343D01*
Y67044D01*
X208995Y68334D01*
G01X197902Y44370D02*
Y46526D01*
X198577Y47201D01*
Y53704D01*
X195551Y56730D01*
Y61044D01*
X194261Y62334D01*
G01X205495Y75340D02*
X206680Y74155D01*
Y71719D01*
X205395Y70434D01*
G01X197761Y69340D02*
X196566Y68145D01*
Y65729D01*
X197861Y64434D01*
G01X194361Y69340D02*
X195546Y68155D01*
Y65719D01*
X194261Y64434D01*
G01X208895Y75340D02*
X207700Y74145D01*
Y71729D01*
X208995Y70434D01*
G01X200857Y1583088D02*
X200875D01*
X202160Y1581803D01*
Y1579385D01*
X200957Y1578182D01*
G01X204457Y1583088D02*
X203180Y1581811D01*
Y1579359D01*
X204357Y1578182D01*
G01X200857Y1585188D02*
X200870D01*
X202150Y1586468D01*
Y1588901D01*
X200957Y1590094D01*
G01X204457Y1585188D02*
X203170Y1586475D01*
Y1588907D01*
X204357Y1590094D01*
G01X194097Y1609386D02*
X194110D01*
X195390Y1610666D01*
Y1613099D01*
X194197Y1614292D01*
G01X197697Y1609386D02*
X196410Y1610673D01*
Y1613105D01*
X197597Y1614292D01*
G01X206157Y1609386D02*
X206170D01*
X207450Y1610666D01*
Y1613099D01*
X206257Y1614292D01*
G01X194097Y1607286D02*
X194115D01*
X195400Y1606001D01*
Y1603583D01*
X194197Y1602380D01*
G01X197697Y1607286D02*
X196420Y1606009D01*
Y1603557D01*
X197597Y1602380D01*
G01X206157Y1607286D02*
X206175D01*
X207460Y1606001D01*
Y1603583D01*
X206257Y1602380D01*
G01X221524Y32756D02*
Y30613D01*
X220857Y29946D01*
Y20748D01*
X222067Y19538D01*
G01X219161Y32756D02*
Y30655D01*
X219837Y29979D01*
Y20708D01*
X218667Y19538D01*
G01X214437Y32756D02*
Y30626D01*
X213772Y29961D01*
Y27664D01*
X214962Y26474D01*
G01X212075Y32756D02*
Y30691D01*
X212752Y30014D01*
Y27664D01*
X211562Y26474D01*
G01X219161Y44370D02*
Y46526D01*
X219846Y47211D01*
Y50531D01*
X228695Y59380D01*
Y67034D01*
X227395Y68334D01*
G01X214437Y44370D02*
Y46545D01*
X213780Y47202D01*
Y53852D01*
X218715Y58787D01*
Y61054D01*
X219995Y62334D01*
G01X221524Y44370D02*
Y46438D01*
X220866Y47096D01*
Y50108D01*
X229715Y58957D01*
Y67054D01*
X230995Y68334D01*
G01X212075Y44370D02*
Y46526D01*
X212750Y47201D01*
Y47202D01*
X212760Y47212D01*
Y54275D01*
X217695Y59210D01*
Y61034D01*
X216395Y62334D01*
G01X219895Y69340D02*
X218700Y68145D01*
Y65729D01*
X219995Y64434D01*
G01X216495Y69340D02*
X217680Y68155D01*
Y65719D01*
X216395Y64434D01*
G01X212917Y1583088D02*
X212935D01*
X214220Y1581803D01*
Y1579385D01*
X213017Y1578182D01*
G01X216517Y1583088D02*
X215240Y1581811D01*
Y1579359D01*
X216417Y1578182D01*
G01X212917Y1585188D02*
X212930D01*
X214210Y1586468D01*
Y1588901D01*
X213017Y1590094D01*
G01X216517Y1585188D02*
X215230Y1586475D01*
Y1588907D01*
X216417Y1590094D01*
G01X209757Y1609386D02*
X208470Y1610673D01*
Y1613105D01*
X209657Y1614292D01*
G01X218217Y1609386D02*
X218230D01*
X219510Y1610666D01*
Y1613099D01*
X218317Y1614292D01*
G01X221817Y1609386D02*
X220530Y1610673D01*
Y1613105D01*
X221717Y1614292D01*
G01X209757Y1607286D02*
X208480Y1606009D01*
Y1603557D01*
X209657Y1602380D01*
G01X218217Y1607286D02*
X218235D01*
X219520Y1606001D01*
Y1603583D01*
X218317Y1602380D01*
G01X221817Y1607286D02*
X220540Y1606009D01*
Y1603557D01*
X221717Y1602380D01*
G01X228610Y32756D02*
Y30629D01*
X227945Y29964D01*
Y27664D01*
X229135Y26474D01*
G01X226248Y32756D02*
Y30691D01*
X226925Y30014D01*
Y27664D01*
X225735Y26474D01*
G01X228610Y44370D02*
Y46437D01*
X227941Y47106D01*
Y49456D01*
X229131Y50646D01*
G01X226248Y44370D02*
Y46483D01*
X226921Y47156D01*
Y49456D01*
X225731Y50646D01*
G01X227495Y75340D02*
X228680Y74155D01*
Y71719D01*
X227395Y70434D01*
G01X230895Y75340D02*
X229700Y74145D01*
Y71729D01*
X230995Y70434D01*
G01X237037Y1583088D02*
X237055D01*
X238340Y1581803D01*
Y1579385D01*
X237137Y1578182D01*
G01X224977Y1583088D02*
X224995D01*
X226280Y1581803D01*
Y1579385D01*
X225077Y1578182D01*
G01X240637Y1583088D02*
X239360Y1581811D01*
Y1579359D01*
X240537Y1578182D01*
G01X228577Y1583088D02*
X227300Y1581811D01*
Y1579359D01*
X228477Y1578182D01*
G01X237037Y1585188D02*
X237050D01*
X238330Y1586468D01*
Y1588901D01*
X237137Y1590094D01*
G01X224977Y1585188D02*
X224990D01*
X226270Y1586468D01*
Y1588901D01*
X225077Y1590094D01*
G01X240637Y1585188D02*
X239350Y1586475D01*
Y1588907D01*
X240537Y1590094D01*
G01X228577Y1585188D02*
X227290Y1586475D01*
Y1588907D01*
X228477Y1590094D01*
G01X230277Y1609386D02*
X230290D01*
X231570Y1610666D01*
Y1613099D01*
X230377Y1614292D01*
G01X233877Y1609386D02*
X232590Y1610673D01*
Y1613105D01*
X233777Y1614292D01*
G01X230277Y1607286D02*
X230295D01*
X231580Y1606001D01*
Y1603583D01*
X230377Y1602380D01*
G01X233877Y1607286D02*
X232600Y1606009D01*
Y1603557D01*
X233777Y1602380D01*
G01X249097Y1583088D02*
X249115D01*
X250400Y1581803D01*
Y1579385D01*
X249197Y1578182D01*
G01X252697Y1583088D02*
X251420Y1581811D01*
Y1579359D01*
X252597Y1578182D01*
G01X249097Y1585188D02*
X249110D01*
X250390Y1586468D01*
Y1588901D01*
X249197Y1590094D01*
G01X252697Y1585188D02*
X251410Y1586475D01*
Y1588907D01*
X252597Y1590094D01*
G01X242337Y1609386D02*
X242350D01*
X243630Y1610666D01*
Y1613099D01*
X242437Y1614292D01*
G01X254397Y1609386D02*
X254410D01*
X255690Y1610666D01*
Y1613099D01*
X254497Y1614292D01*
G01X245937Y1609386D02*
X244650Y1610673D01*
Y1613105D01*
X245837Y1614292D01*
G01X257997Y1609386D02*
X256710Y1610673D01*
Y1613105D01*
X257897Y1614292D01*
G01X242337Y1607286D02*
X242355D01*
X243640Y1606001D01*
Y1603583D01*
X242437Y1602380D01*
G01X254397Y1607286D02*
X254415D01*
X255700Y1606001D01*
Y1603583D01*
X254497Y1602380D01*
G01X245937Y1607286D02*
X244660Y1606009D01*
Y1603557D01*
X245837Y1602380D01*
G01X257997Y1607286D02*
X256720Y1606009D01*
Y1603557D01*
X257897Y1602380D01*
G01X261157Y1583088D02*
X261175D01*
X262460Y1581803D01*
Y1579385D01*
X261257Y1578182D01*
G01X264757Y1583088D02*
X263480Y1581811D01*
Y1579359D01*
X264657Y1578182D01*
G01X261157Y1585188D02*
X261170D01*
X262450Y1586468D01*
Y1588901D01*
X261257Y1590094D01*
G01X264757Y1585188D02*
X263470Y1586475D01*
Y1588907D01*
X264657Y1590094D01*
G01X266457Y1609386D02*
X266470D01*
X267750Y1610666D01*
Y1613099D01*
X266557Y1614292D01*
G01X270057Y1609386D02*
X268770Y1610673D01*
Y1613105D01*
X269957Y1614292D01*
G01X266457Y1607286D02*
X266475D01*
X267760Y1606001D01*
Y1603583D01*
X266557Y1602380D01*
G01X270057Y1607286D02*
X268780Y1606009D01*
Y1603557D01*
X269957Y1602380D01*
G01X283709Y32756D02*
Y30630D01*
X283043Y29964D01*
Y27664D01*
X284233Y26474D01*
G01X281346Y32756D02*
Y30691D01*
X282023Y30014D01*
Y27664D01*
X280833Y26474D01*
G01X283709Y44370D02*
Y46437D01*
X283040Y47106D01*
Y49456D01*
X284230Y50646D01*
G01X281346Y44370D02*
Y46482D01*
X282020Y47156D01*
Y49456D01*
X280830Y50646D01*
G01X285277Y1583088D02*
X285295D01*
X286580Y1581803D01*
Y1579385D01*
X285377Y1578182D01*
G01X273217Y1583088D02*
X273235D01*
X274520Y1581803D01*
Y1579385D01*
X273317Y1578182D01*
G01X288877Y1583088D02*
X287600Y1581811D01*
Y1579359D01*
X288777Y1578182D01*
G01X276817Y1583088D02*
X275540Y1581811D01*
Y1579359D01*
X276717Y1578182D01*
G01X285277Y1585188D02*
X285290D01*
X286570Y1586468D01*
Y1588901D01*
X285377Y1590094D01*
G01X273217Y1585188D02*
X273230D01*
X274510Y1586468D01*
Y1588901D01*
X273317Y1590094D01*
G01X288877Y1585188D02*
X287590Y1586475D01*
Y1588907D01*
X288777Y1590094D01*
G01X276817Y1585188D02*
X275530Y1586475D01*
Y1588907D01*
X276717Y1590094D01*
G01X278517Y1609386D02*
X278530D01*
X279810Y1610666D01*
Y1613099D01*
X278617Y1614292D01*
G01X282117Y1609386D02*
X280830Y1610673D01*
Y1613105D01*
X282017Y1614292D01*
G01X278517Y1607286D02*
X278535D01*
X279820Y1606001D01*
Y1603583D01*
X278617Y1602380D01*
G01X282117Y1607286D02*
X280840Y1606009D01*
Y1603557D01*
X282017Y1602380D01*
G01X297337Y1583088D02*
X297355D01*
X298640Y1581803D01*
Y1579385D01*
X297437Y1578182D01*
G01X300937Y1583088D02*
X299660Y1581811D01*
Y1579359D01*
X300837Y1578182D01*
G01X297337Y1585188D02*
X297350D01*
X298630Y1586468D01*
Y1588901D01*
X297437Y1590094D01*
G01X300937Y1585188D02*
X299650Y1586475D01*
Y1588907D01*
X300837Y1590094D01*
G01X290577Y1609386D02*
X290590D01*
X291870Y1610666D01*
Y1613099D01*
X290677Y1614292D01*
G01X302637Y1609386D02*
X302650D01*
X303930Y1610666D01*
Y1613099D01*
X302737Y1614292D01*
G01X294177Y1609386D02*
X292890Y1610673D01*
Y1613105D01*
X294077Y1614292D01*
G01X306237Y1609386D02*
X304950Y1610673D01*
Y1613105D01*
X306137Y1614292D01*
G01X290577Y1607286D02*
X290595D01*
X291880Y1606001D01*
Y1603583D01*
X290677Y1602380D01*
G01X302637Y1607286D02*
X302655D01*
X303940Y1606001D01*
Y1603583D01*
X302737Y1602380D01*
G01X294177Y1607286D02*
X292900Y1606009D01*
Y1603557D01*
X294077Y1602380D01*
G01X306237Y1607286D02*
X304960Y1606009D01*
Y1603557D01*
X306137Y1602380D01*
G01X321457Y1583088D02*
X321475D01*
X322760Y1581803D01*
Y1579385D01*
X321557Y1578182D01*
G01X309397Y1583088D02*
X309415D01*
X310700Y1581803D01*
Y1579385D01*
X309497Y1578182D01*
G01X312997Y1583088D02*
X311720Y1581811D01*
Y1579359D01*
X312897Y1578182D01*
G01X321457Y1585188D02*
X321470D01*
X322750Y1586468D01*
Y1588901D01*
X321557Y1590094D01*
G01X309397Y1585188D02*
X309410D01*
X310690Y1586468D01*
Y1588901D01*
X309497Y1590094D01*
G01X312997Y1585188D02*
X311710Y1586475D01*
Y1588907D01*
X312897Y1590094D01*
G01X314697Y1609386D02*
X314710D01*
X315990Y1610666D01*
Y1613099D01*
X314797Y1614292D01*
G01X318297Y1609386D02*
X317010Y1610673D01*
Y1613105D01*
X318197Y1614292D01*
G01X314697Y1607286D02*
X314715D01*
X316000Y1606001D01*
Y1603583D01*
X314797Y1602380D01*
G01X318297Y1607286D02*
X317020Y1606009D01*
Y1603557D01*
X318197Y1602380D01*
G01X336361Y1119337D02*
Y1121447D01*
G01X333517Y1583088D02*
X333535D01*
X334820Y1581803D01*
Y1579385D01*
X333617Y1578182D01*
G01X337117Y1583088D02*
X335840Y1581811D01*
Y1579359D01*
X337017Y1578182D01*
G01X325057Y1583088D02*
X323780Y1581811D01*
Y1579359D01*
X324957Y1578182D01*
G01X333517Y1585188D02*
X333530D01*
X334810Y1586468D01*
Y1588901D01*
X333617Y1590094D01*
G01X337117Y1585188D02*
X335830Y1586475D01*
Y1588907D01*
X337017Y1590094D01*
G01X325057Y1585188D02*
X323770Y1586475D01*
Y1588907D01*
X324957Y1590094D01*
G01X330357Y1609386D02*
X329070Y1610673D01*
Y1613105D01*
X330257Y1614292D01*
G01X326757Y1609386D02*
X326770D01*
X328050Y1610666D01*
Y1613099D01*
X326857Y1614292D01*
G01X330357Y1607286D02*
X329080Y1606009D01*
Y1603557D01*
X330257Y1602380D01*
G01X326757Y1607286D02*
X326775D01*
X328060Y1606001D01*
Y1603583D01*
X326857Y1602380D01*
G01X350728Y853490D02*
Y851381D01*
X350727Y851380D01*
G01X354428Y847081D02*
Y844972D01*
X354427Y844971D01*
G01X348879Y850286D02*
Y848177D01*
X348878Y848176D01*
G01X352579Y850286D02*
Y848177D01*
X352578Y848176D01*
G01X350728Y859899D02*
Y857790D01*
X350729Y857789D01*
G01X352579Y863103D02*
Y860994D01*
X352578Y860993D01*
G01X354428Y859899D02*
Y857790D01*
X354429Y857789D01*
G01X350728Y872716D02*
X350729Y872715D01*
Y870606D01*
G01X354428Y872716D02*
X354429Y872715D01*
Y870606D01*
G01X352579Y875920D02*
Y873811D01*
X352578Y873810D01*
G01X354428Y885533D02*
X354429Y885532D01*
Y883423D01*
G01X341912Y1103316D02*
Y1105425D01*
X341911Y1105426D01*
G01X343761Y1106520D02*
Y1108629D01*
X343762Y1108630D01*
G01X345611Y1109724D02*
Y1111834D01*
G01X351161Y1100111D02*
Y1102221D01*
G01X349312Y1111834D02*
Y1109724D01*
G01X353011Y1103316D02*
Y1105426D01*
G01X345611Y1103316D02*
Y1105426D01*
G01X341912Y1109724D02*
Y1111834D01*
G01X353011Y1109724D02*
X353012Y1109725D01*
Y1111834D01*
G01X351161Y1106520D02*
Y1108629D01*
X351162Y1108630D01*
G01X353011Y1122541D02*
Y1124651D01*
G01X347461Y1112929D02*
Y1115039D01*
G01X341912Y1116133D02*
Y1118243D01*
G01X340061Y1125746D02*
Y1127856D01*
G01X343761Y1125746D02*
Y1127856D01*
G01X347461Y1119337D02*
Y1121447D01*
G01X340061Y1119337D02*
Y1121447D01*
G01X343761Y1119337D02*
Y1121447D01*
G01X347461Y1125746D02*
Y1127856D01*
G01X345611Y1122541D02*
Y1124651D01*
G01X349312Y1135359D02*
Y1137469D01*
G01X351161Y1132154D02*
Y1134264D01*
G01X341912Y1128950D02*
Y1131059D01*
X341911Y1131060D01*
G01X345577Y1583088D02*
X345595D01*
X346880Y1581803D01*
Y1579385D01*
X345677Y1578182D01*
G01X349177Y1583088D02*
X347900Y1581811D01*
Y1579359D01*
X349077Y1578182D01*
G01X345577Y1585188D02*
X345590D01*
X346870Y1586468D01*
Y1588901D01*
X345677Y1590094D01*
G01X349177Y1585188D02*
X347890Y1586475D01*
Y1588907D01*
X349077Y1590094D01*
G01X338817Y1609386D02*
X338830D01*
X340110Y1610666D01*
Y1613099D01*
X338917Y1614292D01*
G01X350877Y1609386D02*
X350890D01*
X352170Y1610666D01*
Y1613099D01*
X350977Y1614292D01*
G01X342417Y1609386D02*
X341130Y1610673D01*
Y1613105D01*
X342317Y1614292D01*
G01X354477Y1609386D02*
X353190Y1610673D01*
Y1613105D01*
X354377Y1614292D01*
G01X338817Y1607286D02*
X338835D01*
X340120Y1606001D01*
Y1603583D01*
X338917Y1602380D01*
G01X350877Y1607286D02*
X350895D01*
X352180Y1606001D01*
Y1603583D01*
X350977Y1602380D01*
G01X342417Y1607286D02*
X341140Y1606009D01*
Y1603557D01*
X342317Y1602380D01*
G01X354477Y1607286D02*
X353200Y1606009D01*
Y1603557D01*
X354377Y1602380D01*
G01X356279Y843877D02*
Y841467D01*
G01X361828Y847081D02*
Y844972D01*
X361827Y844971D01*
G01X363679Y843877D02*
Y841467D01*
G01X369228Y847081D02*
Y844972D01*
X369227Y844971D01*
G01X358128Y847081D02*
Y844972D01*
X358127Y844971D01*
G01X359979Y850286D02*
X359978Y850285D01*
Y848176D01*
G01X365528Y847081D02*
Y844972D01*
X365527Y844971D01*
G01X367379Y850286D02*
X367378Y850285D01*
Y848176D01*
G01X356279Y869511D02*
X356278Y869510D01*
Y867401D01*
G01X363679Y869511D02*
X363678Y869510D01*
Y867401D01*
G01X356279Y856694D02*
Y854585D01*
X356278Y854584D01*
G01X358128Y859899D02*
Y857790D01*
X358129Y857789D01*
G01X363679Y856694D02*
Y854585D01*
X363678Y854584D01*
G01X365528Y859899D02*
Y857790D01*
X365529Y857789D01*
G01X359979Y863103D02*
Y860994D01*
X359978Y860993D01*
G01X361828Y859899D02*
Y857790D01*
X361829Y857789D01*
G01X367379Y863103D02*
Y860994D01*
X367378Y860993D01*
G01X369228Y859899D02*
Y857790D01*
X369229Y857789D01*
G01X358128Y872716D02*
Y870607D01*
X358129Y870606D01*
G01X361828Y872716D02*
Y870607D01*
X361829Y870606D01*
G01X365528Y872716D02*
Y870607D01*
X365529Y870606D01*
G01X359979Y875920D02*
Y873811D01*
X359978Y873810D01*
G01X367379Y875920D02*
X367378Y875919D01*
Y873810D01*
G01X369228Y872716D02*
Y870607D01*
X369229Y870606D01*
G01X356279Y882329D02*
Y880220D01*
X356278Y880219D01*
G01X358128Y885533D02*
X358129Y885532D01*
Y883423D01*
G01X363679Y882329D02*
X363678Y882328D01*
Y880219D01*
G01X365528Y885533D02*
X365529Y885532D01*
Y883423D01*
G01X361828Y885533D02*
X361829Y885532D01*
Y883423D01*
G01X369228Y885533D02*
X369229Y885532D01*
Y883423D01*
G01X359979Y888737D02*
X359978Y888736D01*
Y886627D01*
G01X367379Y888737D02*
Y886628D01*
X367378Y886627D01*
G01X354861Y1100111D02*
Y1102221D01*
G01X358561Y1106520D02*
X358562Y1106521D01*
Y1108629D01*
X358561Y1108630D01*
G01X360412Y1109724D02*
X360413Y1109725D01*
Y1111833D01*
X360412Y1111834D01*
G01X364112Y1103316D02*
X364113Y1103317D01*
Y1105425D01*
X364112Y1105426D01*
G01X369661Y1106520D02*
Y1108630D01*
G01X362261Y1106520D02*
X362262Y1106521D01*
Y1108629D01*
X362261Y1108630D01*
G01X365961Y1106520D02*
X365962Y1106521D01*
Y1108629D01*
X365961Y1108630D01*
G01X367812Y1109724D02*
X367813Y1109725D01*
Y1111833D01*
X367812Y1111834D01*
G01X358561Y1119337D02*
Y1121447D01*
G01X360412Y1122541D02*
Y1124651D01*
G01X364112Y1122541D02*
Y1124650D01*
X364111Y1124651D01*
G01X367812Y1122541D02*
Y1124650D01*
X367811Y1124651D01*
G01X354861Y1125746D02*
Y1127856D01*
G01X356712Y1122541D02*
Y1124651D01*
G01X362261Y1125746D02*
Y1127855D01*
X362262Y1127856D01*
G01X365961Y1119337D02*
Y1121446D01*
X365962Y1121447D01*
G01X369661Y1125746D02*
Y1127855D01*
X369662Y1127856D01*
G01X365961Y1112929D02*
Y1115039D01*
G01X358561Y1112929D02*
Y1115039D01*
G01X369661Y1112929D02*
Y1115039D01*
G01X358561Y1132154D02*
Y1134264D01*
G01X362261Y1140973D02*
Y1138563D01*
G01X365961Y1132154D02*
Y1134263D01*
X365962Y1134264D01*
G01X369661Y1138563D02*
Y1140973D01*
G01X356712Y1135359D02*
Y1137469D01*
G01X360412Y1135359D02*
Y1137469D01*
G01X364112Y1135359D02*
Y1137469D01*
G01X367812Y1135359D02*
Y1137469D01*
G01X369697Y1583088D02*
X369715D01*
X371000Y1581803D01*
Y1579385D01*
X369797Y1578182D01*
G01X357637Y1583088D02*
X357655D01*
X358940Y1581803D01*
Y1579385D01*
X357737Y1578182D01*
G01X361237Y1583088D02*
X359960Y1581811D01*
Y1579359D01*
X361137Y1578182D01*
G01X369697Y1585188D02*
X369710D01*
X370990Y1586468D01*
Y1588901D01*
X369797Y1590094D01*
G01X357637Y1585188D02*
X357650D01*
X358930Y1586468D01*
Y1588901D01*
X357737Y1590094D01*
G01X361237Y1585188D02*
X359950Y1586475D01*
Y1588907D01*
X361137Y1590094D01*
G01X362937Y1609386D02*
X362950D01*
X364230Y1610666D01*
Y1613099D01*
X363037Y1614292D01*
G01X366537Y1609386D02*
X365250Y1610673D01*
Y1613105D01*
X366437Y1614292D01*
G01X362937Y1607286D02*
X362955D01*
X364240Y1606001D01*
Y1603583D01*
X363037Y1602380D01*
G01X366537Y1607286D02*
X365260Y1606009D01*
Y1603557D01*
X366437Y1602380D01*
G01X371079Y843877D02*
Y841467D01*
G01X376628Y847081D02*
Y844972D01*
X376627Y844971D01*
G01X380328Y847081D02*
Y844972D01*
X380327Y844971D01*
G01X384028Y847081D02*
Y844972D01*
X384027Y844971D01*
G01X385879Y843877D02*
Y841467D01*
G01X372928Y847081D02*
Y844972D01*
X372927Y844971D01*
G01X374779Y850286D02*
Y848177D01*
X374778Y848176D01*
G01X378479Y843877D02*
Y841467D01*
G01X382179Y850286D02*
Y848177D01*
X382178Y848176D01*
G01X371079Y869511D02*
X371078Y869510D01*
Y867401D01*
G01X378479Y869511D02*
Y867402D01*
X378478Y867401D01*
G01X385879Y869511D02*
Y867402D01*
X385878Y867401D01*
G01X371079Y856694D02*
Y854585D01*
X371078Y854584D01*
G01X372928Y859899D02*
Y857790D01*
X372929Y857789D01*
G01X378479Y856694D02*
Y854585D01*
X378478Y854584D01*
G01X380328Y859899D02*
Y857790D01*
X380329Y857789D01*
G01X384028Y859899D02*
Y857790D01*
X384029Y857789D01*
G01X374779Y863103D02*
Y860994D01*
X374778Y860993D01*
G01X376628Y859899D02*
Y857790D01*
X376629Y857789D01*
G01X382179Y863103D02*
Y860994D01*
X382178Y860993D01*
G01X385879Y856694D02*
Y854585D01*
X385878Y854584D01*
G01X372928Y872716D02*
Y870607D01*
X372929Y870606D01*
G01X380328Y872716D02*
Y870607D01*
X380329Y870606D01*
G01X374779Y875920D02*
Y873811D01*
X374778Y873810D01*
G01X376628Y872716D02*
Y870607D01*
X376629Y870606D01*
G01X382179Y875920D02*
X382178Y875919D01*
Y873810D01*
G01X384028Y872716D02*
Y870607D01*
X384029Y870606D01*
G01X371079Y882329D02*
X371078Y882328D01*
Y880219D01*
G01X372928Y885533D02*
X372929Y885532D01*
Y883423D01*
G01X378479Y882329D02*
Y880220D01*
X378478Y880219D01*
G01X380328Y885533D02*
X380329Y885532D01*
Y883423D01*
G01X385879Y882329D02*
X385878Y882328D01*
Y880219D01*
G01X376628Y885533D02*
Y883424D01*
X376629Y883423D01*
G01X384028Y885533D02*
X384029Y885532D01*
Y883423D01*
G01X374779Y888737D02*
X374778Y888736D01*
Y886627D01*
G01X382179Y888737D02*
Y886628D01*
X382178Y886627D01*
G01X386312Y1103316D02*
Y1105425D01*
X386311Y1105426D01*
G01X382612Y1109724D02*
Y1111833D01*
X382611Y1111834D01*
G01X375212Y1103316D02*
Y1105425D01*
X375211Y1105426D01*
G01X377061Y1106520D02*
Y1108629D01*
X377062Y1108630D01*
G01X380761Y1100111D02*
Y1102220D01*
X380762Y1102221D01*
G01X378912Y1109724D02*
Y1111833D01*
X378911Y1111834D01*
G01X384461Y1106520D02*
Y1108629D01*
X384462Y1108630D01*
G01X386312Y1109724D02*
Y1111833D01*
X386311Y1111834D01*
G01X378912Y1105426D02*
Y1103316D01*
G01X375212Y1109724D02*
Y1111833D01*
X375211Y1111834D01*
G01X382612Y1103316D02*
Y1105425D01*
X382611Y1105426D01*
G01X371512Y1122541D02*
Y1124650D01*
X371511Y1124651D01*
G01X375212Y1122541D02*
Y1124650D01*
X375211Y1124651D01*
G01X378912Y1122541D02*
Y1124650D01*
X378911Y1124651D01*
G01X382612Y1122541D02*
Y1124650D01*
X382611Y1124651D01*
G01X386312Y1122541D02*
Y1124650D01*
X386311Y1124651D01*
G01X373361Y1119337D02*
Y1121446D01*
X373362Y1121447D01*
G01X377061Y1125746D02*
Y1127855D01*
X377062Y1127856D01*
G01X380761Y1119337D02*
Y1121446D01*
X380762Y1121447D01*
G01X384461Y1125746D02*
Y1127855D01*
X384462Y1127856D01*
G01X380761Y1112929D02*
Y1115038D01*
X380762Y1115039D01*
G01X373361Y1132154D02*
Y1134263D01*
X373362Y1134264D01*
G01X377061Y1138563D02*
Y1140973D01*
G01X380761Y1132154D02*
Y1134263D01*
X380762Y1134264D01*
G01X384461Y1138563D02*
Y1140973D01*
G01X371512Y1135359D02*
Y1137469D01*
G01X375212Y1135359D02*
Y1137469D01*
G01X378912Y1135359D02*
Y1137469D01*
G01X382612Y1135359D02*
Y1137469D01*
G01X386312Y1135359D02*
Y1137469D01*
G01X391330Y1585155D02*
X390140Y1586345D01*
Y1588370D01*
X389349Y1589161D01*
X384987D01*
X383070Y1587244D01*
Y1584220D01*
X388075Y1534485D01*
X395030Y1527530D01*
X664225Y1508025D01*
X671283D01*
X671285Y1508027D01*
X684119Y1505121D01*
X712242Y1488314D01*
X836601Y1353705D01*
X899679Y1218494D01*
X899680Y1218493D01*
X962759Y1083281D01*
X967650Y1037859D01*
Y969917D01*
X965174Y775903D01*
X971346Y753956D01*
X998302Y727000D01*
X1120903Y676217D01*
X1154560Y642560D01*
Y639382D01*
X1153370Y638192D01*
G01X1156770D02*
X1155580Y639382D01*
Y642983D01*
X1121481Y677082D01*
X998880Y727865D01*
X972256Y754489D01*
X966196Y776037D01*
X968670Y969910D01*
Y1037914D01*
X963755Y1083559D01*
X837459Y1354281D01*
X712892Y1489115D01*
X684503Y1506080D01*
X671408Y1509045D01*
X664262D01*
X395483Y1528520D01*
X389054Y1534949D01*
X387878Y1546656D01*
X388308Y1547182D01*
X388158Y1548675D01*
X387631Y1549105D01*
X387482Y1550597D01*
X387912Y1551122D01*
X387762Y1552616D01*
X387235Y1553045D01*
X387069Y1554703D01*
X387498Y1555229D01*
X387348Y1556722D01*
X386822Y1557152D01*
X386672Y1558644D01*
X387101Y1559170D01*
X386951Y1560663D01*
X386425Y1561093D01*
X386275Y1562585D01*
X386704Y1563111D01*
X386554Y1564604D01*
X386028Y1565034D01*
X385878Y1566526D01*
X386307Y1567052D01*
X386157Y1568545D01*
X385631Y1568975D01*
X385481Y1570467D01*
X385910Y1570993D01*
X385760Y1572486D01*
X385234Y1572916D01*
X385084Y1574408D01*
X385513Y1574934D01*
X385363Y1576428D01*
X384837Y1576857D01*
X384687Y1578349D01*
X385116Y1578874D01*
X384966Y1580368D01*
X384439Y1580797D01*
X384090Y1584272D01*
Y1586821D01*
X385410Y1588141D01*
X388926D01*
X389120Y1587947D01*
Y1586345D01*
X387930Y1585155D01*
G01X373297Y1583088D02*
X372020Y1581811D01*
Y1579359D01*
X373197Y1578182D01*
G01X373297Y1585188D02*
X372010Y1586475D01*
Y1588907D01*
X373197Y1590094D01*
G01X374997Y1609386D02*
X375010D01*
X376290Y1610666D01*
Y1613099D01*
X375097Y1614292D01*
G01X378597Y1609386D02*
X377310Y1610673D01*
Y1613105D01*
X378497Y1614292D01*
G01X374997Y1607286D02*
X375015D01*
X376300Y1606001D01*
Y1603583D01*
X375097Y1602380D01*
G01X378597Y1607286D02*
X377320Y1606009D01*
Y1603557D01*
X378497Y1602380D01*
G01X387728Y847081D02*
Y844972D01*
X387727Y844971D01*
G01X391428Y847081D02*
Y844972D01*
X391427Y844971D01*
G01X395128Y847081D02*
Y844972D01*
X395127Y844971D01*
G01X398828Y847081D02*
Y844972D01*
X398827Y844971D01*
G01X400679Y843877D02*
Y841467D01*
G01X389579Y850286D02*
Y848177D01*
X389578Y848176D01*
G01X393279Y843877D02*
Y841467D01*
G01X396979Y850286D02*
Y848177D01*
X396978Y848176D01*
G01X402528Y847081D02*
Y844972D01*
X402527Y844971D01*
G01X400679Y869511D02*
X400467Y869299D01*
Y867612D01*
X400678Y867401D01*
G01X393279Y869511D02*
Y867402D01*
X393278Y867401D01*
G01X387728Y859899D02*
Y857790D01*
X387729Y857789D01*
G01X393279Y856694D02*
Y854585D01*
X393278Y854584D01*
G01X395128Y859899D02*
Y857790D01*
X395129Y857789D01*
G01X400679Y856694D02*
Y854585D01*
X400678Y854584D01*
G01X402528Y859899D02*
Y857790D01*
X402529Y857789D01*
G01X389579Y863103D02*
Y860994D01*
X389578Y860993D01*
G01X391428Y859899D02*
Y857790D01*
X391429Y857789D01*
G01X396979Y863103D02*
Y860994D01*
X396978Y860993D01*
G01X398828Y859899D02*
Y857790D01*
X398829Y857789D01*
G01X387728Y872716D02*
Y870607D01*
X387729Y870606D01*
G01X391428Y872716D02*
Y870607D01*
X391429Y870606D01*
G01X395128Y872716D02*
Y870607D01*
X395129Y870606D01*
G01X402528Y872716D02*
Y870607D01*
X402529Y870606D01*
G01X389579Y875920D02*
X389578Y875919D01*
Y873810D01*
G01X396979Y875920D02*
X397177Y875722D01*
Y874009D01*
X396978Y873810D01*
G01X398828Y872716D02*
Y870607D01*
X398829Y870606D01*
G01X393279Y882329D02*
Y880220D01*
X393278Y880219D01*
G01X395128Y885533D02*
Y883424D01*
X395129Y883423D01*
G01X400679Y882329D02*
Y880220D01*
X400678Y880219D01*
G01X402528Y885533D02*
Y883424D01*
X402529Y883423D01*
G01X387728Y885533D02*
Y883424D01*
X387729Y883423D01*
G01X391428Y885533D02*
Y883424D01*
X391429Y883423D01*
G01X398828Y885533D02*
X398829Y885532D01*
Y883423D01*
G01X396979Y888737D02*
Y886628D01*
X396978Y886627D01*
G01X389579Y888737D02*
Y886628D01*
X389578Y886627D01*
G01X400679Y933598D02*
Y931489D01*
X400678Y931488D01*
G01X402528Y930393D02*
X402529Y930392D01*
Y928283D01*
G01X398828Y936801D02*
X398829D01*
Y934691D01*
G01X402528Y936801D02*
X402529D01*
Y934691D01*
G01X402961Y1080885D02*
Y1082994D01*
X402962Y1082995D01*
G01X402961Y1089404D02*
Y1087294D01*
G01X401112Y1096907D02*
Y1099016D01*
X401111Y1099017D01*
G01X391861Y1106520D02*
Y1108629D01*
X391862Y1108630D01*
G01X393712Y1109724D02*
Y1111833D01*
X393711Y1111834D01*
G01X397412Y1103316D02*
Y1105425D01*
X397411Y1105426D01*
G01X402961Y1106520D02*
Y1108629D01*
X402962Y1108630D01*
G01X402961Y1100111D02*
X402962Y1100112D01*
Y1102221D01*
G01X395561Y1106520D02*
Y1108629D01*
X395562Y1108630D01*
G01X399261Y1106520D02*
Y1108629D01*
X399262Y1108630D01*
G01X401112Y1109724D02*
Y1111833D01*
X401111Y1111834D01*
G01X390012Y1122541D02*
Y1124650D01*
X390011Y1124651D01*
G01X395561Y1119337D02*
Y1121446D01*
X395562Y1121447D01*
G01X397412Y1122541D02*
Y1124650D01*
X397411Y1124651D01*
G01X401112Y1122541D02*
Y1124650D01*
X401111Y1124651D01*
G01X391861Y1125746D02*
Y1127855D01*
X391862Y1127856D01*
G01X393712Y1122541D02*
Y1124650D01*
X393711Y1124651D01*
G01X399261Y1125746D02*
Y1127855D01*
X399262Y1127856D01*
G01X402961Y1119337D02*
Y1121446D01*
X402962Y1121447D01*
G01X388161Y1119337D02*
Y1121446D01*
X388162Y1121447D01*
G01X399261Y1112929D02*
Y1115038D01*
X399262Y1115039D01*
G01X391861Y1112929D02*
Y1115038D01*
X391862Y1115039D01*
G01X402961Y1112929D02*
Y1115038D01*
X402962Y1115039D01*
G01X391861Y1138563D02*
Y1140973D01*
G01X395561Y1132154D02*
Y1134263D01*
X395562Y1134264D01*
G01X399261Y1138563D02*
Y1140973D01*
G01X402961Y1132154D02*
Y1134263D01*
X402962Y1134264D01*
G01X388161Y1132154D02*
Y1134263D01*
X388162Y1134264D01*
G01X390012Y1135359D02*
Y1137469D01*
G01X393712Y1135359D02*
Y1137469D01*
G01X397412Y1135359D02*
Y1137469D01*
G01X401112Y1135359D02*
Y1137469D01*
G01X404030Y1595390D02*
X402690Y1594050D01*
X400931D01*
X399539Y1592658D01*
X394087Y1566575D01*
X394082Y1566500D01*
X392710Y1544313D01*
Y1536526D01*
X397125Y1532111D01*
X664396Y1512745D01*
X671528D01*
X685928Y1509484D01*
X715389Y1491882D01*
X809288Y1390243D01*
X840588Y1356363D01*
X968165Y1082890D01*
X972380Y1043751D01*
Y969886D01*
X969913Y776526D01*
X975226Y757637D01*
X976455Y755537D01*
X999577Y732415D01*
X1001163Y731357D01*
X1132029Y677149D01*
X1163050Y646128D01*
Y643302D01*
X1161860Y642112D01*
G01X404030Y1591990D02*
X402990Y1593030D01*
X401354D01*
X400476Y1592151D01*
X400136Y1590523D01*
X400508Y1589955D01*
X400192Y1588447D01*
X399623Y1588075D01*
X399308Y1586568D01*
X399680Y1586000D01*
X399365Y1584492D01*
X398796Y1584120D01*
X398481Y1582613D01*
X398853Y1582045D01*
X398538Y1580537D01*
X397969Y1580165D01*
X397655Y1578658D01*
X398026Y1578090D01*
X397711Y1576582D01*
X397142Y1576210D01*
X395101Y1566438D01*
X393730Y1544281D01*
Y1536949D01*
X397578Y1533101D01*
X664433Y1513765D01*
X671643D01*
X686312Y1510443D01*
X716039Y1492683D01*
X778738Y1424815D01*
X778739Y1424814D01*
X841446Y1356939D01*
X969161Y1083168D01*
X973400Y1043806D01*
Y969855D01*
X970935Y776660D01*
X976173Y758040D01*
X977270Y756166D01*
X1000228Y733208D01*
X1001646Y732261D01*
X1132607Y678014D01*
X1164070Y646551D01*
Y643302D01*
X1165260Y642112D01*
G01X402781Y1613560D02*
X403780Y1614559D01*
Y1617762D01*
X402590Y1618952D01*
G01X402781Y1611460D02*
X403830Y1610411D01*
Y1603870D01*
X412670Y1595030D01*
Y1562919D01*
X415300Y1556569D01*
Y1546318D01*
X418626Y1542644D01*
X429524Y1537236D01*
X438801Y1534651D01*
X657644Y1524805D01*
X681302Y1517701D01*
X718794Y1495302D01*
X844231Y1359526D01*
X972805Y1083911D01*
X977200Y1043102D01*
Y969854D01*
X974742Y777159D01*
X979867Y758943D01*
X1003267Y735543D01*
X1146854Y676068D01*
X1171010Y651912D01*
Y637242D01*
X1169820Y636052D01*
G01X418540Y1632842D02*
X417050Y1634332D01*
X398596D01*
X397406Y1633142D01*
G01X418540Y1636842D02*
X417050Y1635352D01*
X398596D01*
X397406Y1636542D01*
G01X406228Y847081D02*
Y844972D01*
X406227Y844971D01*
G01X409928Y847081D02*
Y844972D01*
X409927Y844971D01*
G01X413628Y847081D02*
Y844972D01*
X413627Y844971D01*
G01X417328Y847081D02*
Y844972D01*
X417327Y844971D01*
G01X404379Y850286D02*
Y848177D01*
X404378Y848176D01*
G01X408079Y843877D02*
Y841467D01*
G01X411779Y850286D02*
Y848177D01*
X411778Y848176D01*
G01X415479Y843877D02*
Y841467D01*
G01X419179Y850286D02*
Y848177D01*
X419178Y848176D01*
G01X408079Y869511D02*
X408078Y869510D01*
Y867401D01*
G01X415479Y869511D02*
Y867402D01*
X415478Y867401D01*
G01X408079Y856694D02*
Y854585D01*
X408078Y854584D01*
G01X409928Y859899D02*
Y857790D01*
X409929Y857789D01*
G01X415479Y856694D02*
Y854585D01*
X415478Y854584D01*
G01X417328Y859899D02*
Y857790D01*
X417329Y857789D01*
G01X404379Y863103D02*
Y860994D01*
X404378Y860993D01*
G01X406228Y859899D02*
Y857790D01*
X406229Y857789D01*
G01X411779Y863103D02*
Y860994D01*
X411778Y860993D01*
G01X413628Y859899D02*
Y857790D01*
X413629Y857789D01*
G01X419179Y863103D02*
Y860994D01*
X419178Y860993D01*
G01X404379Y875920D02*
X404378Y875919D01*
Y873810D01*
G01X406228Y872716D02*
Y870607D01*
X406229Y870606D01*
G01X408079Y882329D02*
Y880220D01*
X408078Y880219D01*
G01X409928Y885533D02*
X409929Y885532D01*
Y883423D01*
G01X406228Y885533D02*
Y883424D01*
X406229Y883423D01*
G01X419179Y875920D02*
Y873811D01*
X419178Y873810D01*
G01X417328Y872716D02*
Y870607D01*
X417329Y870606D01*
G01X411779Y875920D02*
X411778Y875919D01*
Y873810D01*
G01X413628Y872716D02*
Y870607D01*
X413629Y870606D01*
G01X417328Y885533D02*
X417329Y885532D01*
Y883423D01*
G01X415479Y882329D02*
X415478Y882328D01*
Y880219D01*
G01X413628Y885533D02*
X413629Y885532D01*
Y883423D01*
G01X404379Y888737D02*
X404378Y888736D01*
Y886627D01*
G01X411779Y888737D02*
Y886628D01*
X411778Y886627D01*
G01X419179Y888737D02*
X419178Y888736D01*
Y886627D01*
G01X408512Y1077681D02*
X408511Y1077682D01*
Y1079791D01*
G01X406661Y1087294D02*
Y1089403D01*
X406662Y1089404D01*
G01X410361Y1087294D02*
Y1089403D01*
X410362Y1089404D01*
G01X404812Y1084090D02*
Y1086199D01*
X404811Y1086200D01*
G01X414061Y1080885D02*
Y1082994D01*
X414062Y1082995D01*
G01X410361Y1080885D02*
Y1082994D01*
X410362Y1082995D01*
G01X406661Y1080885D02*
Y1082994D01*
X406662Y1082995D01*
G01X408512Y1090498D02*
Y1092606D01*
X408511Y1092607D01*
Y1092608D01*
G01X414061Y1087294D02*
Y1089403D01*
X414062Y1089404D01*
G01X412212Y1084090D02*
Y1086199D01*
X412211Y1086200D01*
G01X404812Y1096907D02*
Y1099016D01*
X404811Y1099017D01*
G01X408512Y1103316D02*
Y1105425D01*
X408511Y1105426D01*
G01X412212Y1109724D02*
Y1111833D01*
X412211Y1111834D01*
G01X415912Y1109724D02*
Y1111833D01*
X415911Y1111834D01*
G01X414061Y1100111D02*
X414062Y1100112D01*
Y1102221D01*
G01X417761Y1106520D02*
Y1108629D01*
X417762Y1108630D01*
G01X408512Y1096907D02*
Y1099016D01*
X408511Y1099017D01*
G01X410361Y1106520D02*
Y1108629D01*
X410362Y1108630D01*
G01X408512Y1109724D02*
Y1111833D01*
X408511Y1111834D01*
G01X412212Y1103316D02*
Y1105425D01*
X412211Y1105426D01*
G01X415912Y1103316D02*
Y1105425D01*
X415911Y1105426D01*
G01X404812Y1122541D02*
Y1124650D01*
X404811Y1124651D01*
G01X408512Y1122541D02*
Y1124650D01*
X408511Y1124651D01*
G01X406661Y1125746D02*
Y1127855D01*
X406662Y1127856D01*
G01X410361Y1119337D02*
Y1121446D01*
X410362Y1121447D01*
G01X414061Y1112929D02*
Y1115038D01*
X414062Y1115039D01*
G01X406661Y1138563D02*
Y1140973D01*
G01X410361Y1132154D02*
Y1134263D01*
X410362Y1134264D01*
G01X404812Y1135359D02*
Y1137469D01*
G01X408512Y1135359D02*
Y1137469D01*
G01X405919Y1611460D02*
X404850Y1610391D01*
Y1604293D01*
X413690Y1595453D01*
Y1563123D01*
X413691Y1563122D01*
X416320Y1556772D01*
Y1546712D01*
X419253Y1543473D01*
X429891Y1538193D01*
X438963Y1535665D01*
X657816Y1525819D01*
X681717Y1518642D01*
X719444Y1496103D01*
X845089Y1360102D01*
X973801Y1084189D01*
X978220Y1043157D01*
Y969847D01*
X975764Y777293D01*
X980777Y759476D01*
X1003845Y736408D01*
X1147432Y676933D01*
X1172030Y652335D01*
Y637242D01*
X1173220Y636052D01*
G01X1183360Y642062D02*
X1184550Y643252D01*
Y645292D01*
X1150076Y679766D01*
X1007470Y738836D01*
X984591Y761715D01*
X980052Y777859D01*
X982500Y969819D01*
Y1037753D01*
X977412Y1085001D01*
X847203Y1364121D01*
X723546Y1497970D01*
X683721Y1521761D01*
X655610Y1530203D01*
X446464Y1539612D01*
X441273Y1542668D01*
X437800Y1548313D01*
Y1557345D01*
X437067Y1559116D01*
X435066Y1561117D01*
X421052Y1566922D01*
X419575Y1568399D01*
Y1593298D01*
X420900Y1594623D01*
Y1601682D01*
X419780Y1602802D01*
G01X405919Y1613560D02*
X404800Y1614679D01*
Y1617762D01*
X405990Y1618952D01*
G01X418540Y1624692D02*
X417050Y1626182D01*
X415596D01*
X414406Y1624992D01*
G01X418540Y1628692D02*
X417050Y1627202D01*
X415596D01*
X414406Y1628392D01*
G01X421028Y847081D02*
Y844972D01*
X421027Y844971D01*
G01X424728Y847081D02*
Y844972D01*
X424727Y844971D01*
G01X428428Y847081D02*
X428427Y847080D01*
Y844971D01*
G01X433979Y850286D02*
Y848177D01*
X433978Y848176D01*
G01X422879Y843877D02*
Y841467D01*
G01X426579Y850286D02*
Y848177D01*
X426578Y848176D01*
G01X430279Y850286D02*
Y848177D01*
X430278Y848176D01*
G01X430279Y869511D02*
X430278Y869510D01*
Y867401D01*
G01X422879Y869511D02*
X422878Y869510D01*
Y867401D01*
G01X422879Y856694D02*
Y854585D01*
X422878Y854584D01*
G01X424728Y859899D02*
Y857790D01*
X424729Y857789D01*
G01X430279Y856694D02*
Y854585D01*
X430278Y854584D01*
G01X433979Y863103D02*
Y860993D01*
G01X421028Y859899D02*
Y857790D01*
X421029Y857789D01*
G01X426579Y863103D02*
Y860994D01*
X426578Y860993D01*
G01X428428Y859899D02*
Y857790D01*
X428429Y857789D01*
G01X432128Y859899D02*
Y857790D01*
X432129Y857789D01*
G01X432128Y872716D02*
Y870607D01*
X432129Y870606D01*
G01X426579Y875920D02*
X426578Y875919D01*
Y873810D01*
G01X424728Y872716D02*
Y870607D01*
X424729Y870606D01*
G01X433979Y875920D02*
Y873810D01*
G01X428428Y872716D02*
Y870607D01*
X428429Y870606D01*
G01X421028Y872716D02*
Y870607D01*
X421029Y870606D01*
G01X432128Y885533D02*
X432129Y885532D01*
Y883423D01*
G01X430279Y882329D02*
Y880220D01*
X430278Y880219D01*
G01X424728Y885533D02*
X424729Y885532D01*
Y883423D01*
G01X422879Y882329D02*
X422878Y882328D01*
Y880219D01*
G01X428428Y885533D02*
Y883424D01*
X428429Y883423D01*
G01X421028Y885533D02*
X421029Y885532D01*
Y883423D01*
G01X433979Y888737D02*
X433978Y888736D01*
Y886627D01*
G01X426579Y888737D02*
Y886628D01*
X426578Y886627D01*
G01X428861Y1074477D02*
Y1076587D01*
G01X430711Y1077681D02*
Y1079791D01*
G01X421461Y1087294D02*
Y1089403D01*
X421462Y1089404D01*
G01X423312Y1090498D02*
Y1092606D01*
X423311Y1092607D01*
Y1092608D01*
G01X427012Y1090498D02*
Y1092606D01*
X427011Y1092607D01*
Y1092608D01*
G01X419612Y1084090D02*
Y1086199D01*
X419611Y1086200D01*
G01X430711Y1084090D02*
Y1086199D01*
X430710Y1086200D01*
G01X425161Y1080885D02*
X425162Y1080886D01*
Y1082995D01*
G01X419612Y1090498D02*
Y1092606D01*
X419611Y1092607D01*
Y1092608D01*
G01X425161Y1093703D02*
Y1095812D01*
X425162Y1095813D01*
G01X430711Y1090498D02*
Y1092608D01*
G01X423312Y1084090D02*
Y1086199D01*
X423311Y1086200D01*
G01X428861Y1087294D02*
Y1089404D01*
G01X427012Y1084090D02*
Y1086200D01*
G01X419612Y1103316D02*
Y1105425D01*
X419611Y1105426D01*
G01X419612Y1109724D02*
Y1111833D01*
X419611Y1111834D01*
G01X1186760Y642062D02*
X1185570Y643252D01*
Y645715D01*
X1150654Y680631D01*
X1008048Y739701D01*
X985501Y762248D01*
X981074Y777993D01*
X983520Y969812D01*
Y1037808D01*
X978408Y1085279D01*
X848061Y1364697D01*
X724196Y1498771D01*
X684136Y1522702D01*
X655782Y1531217D01*
X446763Y1540620D01*
X442010Y1543419D01*
X438820Y1548602D01*
Y1557548D01*
X437932Y1559694D01*
X435644Y1561982D01*
X421630Y1567787D01*
X420595Y1568822D01*
Y1592875D01*
X421920Y1594200D01*
Y1601542D01*
X423180Y1602802D01*
G01X421690Y1632842D02*
X422970Y1634122D01*
X423471D01*
X426088Y1631505D01*
X426646D01*
X429079Y1629072D01*
X431430D01*
X431926Y1628576D01*
X432640D01*
G01X421690Y1636842D02*
Y1636762D01*
X423310Y1635142D01*
X423894D01*
X426511Y1632525D01*
X427069D01*
X429502Y1630092D01*
X431620D01*
X432073Y1630545D01*
X432640D01*
G01X421690Y1624692D02*
X423080Y1626082D01*
X424872D01*
X427218Y1624516D01*
X430543Y1623135D01*
X431426D01*
X431890Y1622671D01*
X432640D01*
G01X421690Y1628692D02*
X423280Y1627102D01*
X425182D01*
X427701Y1625420D01*
X430747Y1624155D01*
X431494D01*
X431978Y1624639D01*
X432640D01*
G01X450629Y847081D02*
Y844972D01*
X450628Y844971D01*
G01X446928Y847081D02*
Y844972D01*
X446927Y844971D01*
Y844671D01*
G01X448779Y850286D02*
Y848177D01*
X448778Y848176D01*
G01X443228Y847081D02*
Y844972D01*
X443227Y844971D01*
Y844671D01*
G01X435829Y847081D02*
Y844671D01*
G01X437679Y850286D02*
Y848177D01*
X437678Y848176D01*
G01X445079Y869511D02*
Y867402D01*
X445078Y867401D01*
G01X437679Y869511D02*
X437678Y869510D01*
Y867401D01*
G01X437679Y856694D02*
Y854584D01*
G01X435829Y857789D02*
Y859899D01*
G01X450629Y857789D02*
Y859899D01*
G01X445079Y856694D02*
Y854585D01*
X445078Y854584D01*
G01X443228Y859899D02*
Y857790D01*
X443229Y857789D01*
G01X448779Y863103D02*
Y860993D01*
G01X446928Y859899D02*
Y857790D01*
X446929Y857789D01*
G01X441379Y863103D02*
Y860994D01*
X441378Y860993D01*
G01X448779Y875920D02*
Y873810D01*
G01X446928Y872716D02*
X446929Y872715D01*
Y870606D01*
G01X441379Y875920D02*
Y873811D01*
X441378Y873810D01*
G01X439528Y872716D02*
Y870607D01*
X439529Y870606D01*
G01X450629D02*
Y872716D01*
G01X443228D02*
Y870607D01*
X443229Y870606D01*
G01X435829D02*
Y872716D01*
G01X446928Y885533D02*
X446929Y885532D01*
Y883423D01*
G01X445079Y882329D02*
X445078Y882328D01*
Y880219D01*
G01X439528Y885533D02*
X439529Y885532D01*
Y883423D01*
G01X437679Y882329D02*
X437678Y882328D01*
Y880219D01*
G01X450629Y885533D02*
Y883423D01*
G01X443228Y885533D02*
Y883424D01*
X443229Y883423D01*
G01X435829Y885533D02*
Y883423D01*
G01X448779Y888737D02*
Y886628D01*
X448778Y886627D01*
G01X441379Y888737D02*
Y886628D01*
X441378Y886627D01*
G01X460910Y1629172D02*
X459720Y1627982D01*
X455156D01*
X453307Y1626133D01*
X452299D01*
X451824Y1626608D01*
X451340D01*
G01Y1624639D02*
X452017D01*
X452491Y1625113D01*
X453730D01*
X455579Y1626962D01*
X459720D01*
X460910Y1625772D01*
G01X437990Y1647352D02*
X439530Y1648892D01*
Y1651076D01*
X438340Y1652266D01*
G01X441990Y1647352D02*
X440550Y1648792D01*
Y1651076D01*
X441740Y1652266D01*
G01X437990Y1644202D02*
X439511Y1642681D01*
Y1638394D01*
X439037Y1637920D01*
Y1636942D01*
G01X441990Y1644202D02*
X440531Y1642743D01*
Y1638362D01*
X441006Y1637887D01*
Y1636942D01*
G01X467279Y843877D02*
Y841467D01*
G01X463579Y850286D02*
Y848177D01*
X463578Y848176D01*
G01X459879Y843877D02*
Y841467D01*
G01X458028Y847081D02*
Y844972D01*
X458027Y844971D01*
G01X454328Y847081D02*
Y844972D01*
X454327Y844971D01*
G01X465428Y847081D02*
Y844972D01*
X465427Y844971D01*
G01X461728Y847081D02*
Y844972D01*
X461727Y844971D01*
G01X456179Y850286D02*
Y848177D01*
X456178Y848176D01*
G01X452479Y843877D02*
Y841467D01*
G01X467279Y869511D02*
Y867402D01*
X467278Y867401D01*
G01X459879Y869511D02*
Y867402D01*
X459878Y867401D01*
G01X452479Y869511D02*
Y867402D01*
X452478Y867401D01*
G01X467279Y856694D02*
Y854585D01*
X467278Y854584D01*
G01X465428Y859899D02*
Y857790D01*
X465429Y857789D01*
G01X459879Y856694D02*
Y854585D01*
X459878Y854584D01*
G01X458028Y859899D02*
Y857790D01*
X458029Y857789D01*
G01X452479Y856694D02*
Y854585D01*
X452478Y854584D01*
G01X463579Y863103D02*
Y860994D01*
X463578Y860993D01*
G01X461728Y859899D02*
Y857790D01*
X461729Y857789D01*
G01X456179Y863103D02*
Y860994D01*
X456178Y860993D01*
G01X454328Y859899D02*
Y857790D01*
X454329Y857789D01*
G01X463579Y875920D02*
Y873811D01*
X463578Y873810D01*
G01X461728Y872716D02*
Y870607D01*
X461729Y870606D01*
G01X456179Y875920D02*
Y873811D01*
X456178Y873810D01*
G01X454328Y872716D02*
Y870607D01*
X454329Y870606D01*
G01X465428Y872716D02*
Y870607D01*
X465429Y870606D01*
G01X458028Y872716D02*
Y870607D01*
X458029Y870606D01*
G01X467279Y882329D02*
Y880220D01*
X467278Y880219D01*
G01X461728Y885533D02*
X461729Y885532D01*
Y883423D01*
G01X459879Y882329D02*
Y880220D01*
X459878Y880219D01*
G01X454328Y885533D02*
X454329Y885532D01*
Y883423D01*
G01X452479Y882329D02*
Y880219D01*
G01X465428Y885533D02*
X465429Y885532D01*
Y883423D01*
G01X458028Y885533D02*
X458029Y885532D01*
Y883423D01*
G01X463579Y888737D02*
Y886628D01*
X463578Y886627D01*
G01X456179Y888737D02*
X456178Y888736D01*
Y886627D01*
G01X483928Y847081D02*
Y844972D01*
X483927Y844971D01*
G01X480228Y847081D02*
Y844972D01*
X480227Y844971D01*
G01X476528Y847081D02*
Y844972D01*
X476527Y844971D01*
G01X470979Y850286D02*
Y848177D01*
X470978Y848176D01*
G01X482079Y843877D02*
Y841467D01*
G01X478379Y850286D02*
Y848177D01*
X478378Y848176D01*
G01X474679Y843877D02*
Y841467D01*
G01X472828Y847081D02*
Y844972D01*
X472827Y844971D01*
G01X469128Y847081D02*
Y844972D01*
X469127Y844971D01*
G01X474679Y869511D02*
Y867402D01*
X474678Y867401D01*
G01X482079Y869511D02*
Y867402D01*
X482078Y867401D01*
G01X482079Y856694D02*
Y854585D01*
X482078Y854584D01*
G01X480228Y859899D02*
Y857790D01*
X480229Y857789D01*
G01X474679Y856694D02*
Y854585D01*
X474678Y854584D01*
G01X472828Y859899D02*
Y857790D01*
X472829Y857789D01*
G01X483928Y859899D02*
Y857790D01*
X483929Y857789D01*
G01X478379Y863103D02*
Y860994D01*
X478378Y860993D01*
G01X476528Y859899D02*
Y857790D01*
X476529Y857789D01*
G01X470979Y863103D02*
Y860994D01*
X470978Y860993D01*
G01X469128Y859899D02*
Y857790D01*
X469129Y857789D01*
G01X472828Y872716D02*
Y870606D01*
G01X469128Y872716D02*
Y870607D01*
X469129Y870606D01*
G01X469128Y885533D02*
X469129Y885532D01*
Y883423D01*
G01X480228Y872716D02*
Y870607D01*
X480229Y870606D01*
G01X476528Y872716D02*
Y870607D01*
X476529Y870606D01*
G01X478379Y875920D02*
Y873811D01*
X478378Y873810D01*
G01X483928Y872716D02*
Y870607D01*
X483929Y870606D01*
G01X474679Y882329D02*
Y880220D01*
X474678Y880219D01*
G01X476528Y885533D02*
Y883424D01*
X476529Y883423D01*
G01X482079Y882329D02*
Y880220D01*
X482078Y880219D01*
G01X483928Y885533D02*
X483929Y885532D01*
Y883423D01*
G01X472828Y885533D02*
Y883424D01*
X472829Y883423D01*
G01X480228Y885533D02*
X480229Y885532D01*
Y883423D01*
G01X470979Y888737D02*
X470978Y888736D01*
Y886627D01*
G01X478379Y888737D02*
Y886628D01*
X478378Y886627D01*
G01X480228Y930393D02*
X480229Y930392D01*
Y928283D01*
G01X478379Y933598D02*
Y931489D01*
X478378Y931488D01*
G01X478379Y927189D02*
X478378Y927188D01*
Y925079D01*
G01X482079Y927189D02*
X482078Y927188D01*
Y925079D01*
G01X478379Y940006D02*
X478378Y940005D01*
Y937896D01*
G01X480228Y943210D02*
X480229Y943209D01*
Y941100D01*
G01X484361Y1119337D02*
X484362Y1121447D01*
G01X480661Y1125746D02*
Y1127855D01*
X480662Y1127856D01*
G01X476961Y1119337D02*
X476962Y1121447D01*
G01X473261Y1125746D02*
Y1127855D01*
X473262Y1127856D01*
G01X469561Y1119337D02*
X469562Y1121447D01*
G01X482512Y1122541D02*
Y1124650D01*
X482511Y1124651D01*
G01X478812Y1122541D02*
Y1124650D01*
X478811Y1124651D01*
G01X475112Y1122541D02*
Y1124650D01*
X475111Y1124651D01*
G01X471412Y1122541D02*
Y1124650D01*
X471411Y1124651D01*
G01X484361Y1132154D02*
Y1134263D01*
X484362Y1134264D01*
G01X482512Y1135359D02*
Y1137469D01*
G01X476961Y1132154D02*
Y1134263D01*
X476962Y1134264D01*
G01X475112Y1135359D02*
Y1137469D01*
G01X480661Y1138563D02*
Y1140973D01*
G01X478812Y1135359D02*
Y1137469D01*
G01X473261Y1138563D02*
Y1140973D01*
G01X476451Y1578182D02*
X475274Y1579359D01*
Y1581811D01*
X476551Y1583088D01*
G01X473051Y1578182D02*
X474254Y1579385D01*
Y1581803D01*
X472969Y1583088D01*
X472951D01*
G01X476451Y1590094D02*
X475264Y1588907D01*
Y1586475D01*
X476551Y1585188D01*
G01X473051Y1590094D02*
X474244Y1588901D01*
Y1586468D01*
X472964Y1585188D01*
X472951D01*
G01X478351Y1614292D02*
X479544Y1613099D01*
Y1610666D01*
X478264Y1609386D01*
X478251D01*
G01X481751Y1614292D02*
X480564Y1613105D01*
Y1610673D01*
X481851Y1609386D01*
G01X478351Y1602380D02*
X479554Y1603583D01*
Y1606001D01*
X478269Y1607286D01*
X478251D01*
G01X481751Y1602380D02*
X480574Y1603557D01*
Y1606009D01*
X481851Y1607286D01*
G01X513177Y53544D02*
Y51704D01*
X513847Y51034D01*
Y47889D01*
X512940Y46982D01*
X509090D01*
X507626Y48446D01*
X505776Y52914D01*
X506041Y53554D01*
X505451Y54978D01*
X504810Y55243D01*
X504811Y55244D01*
X503783Y57726D01*
X504048Y58365D01*
X503458Y59789D01*
X502818Y60054D01*
X501248Y63843D01*
X501247Y63845D01*
X501513Y64485D01*
X500923Y65909D01*
X500282Y66174D01*
X500283Y66175D01*
X495705Y77227D01*
X494976Y80889D01*
Y150276D01*
X508944Y196322D01*
X519145Y206523D01*
X527154Y232924D01*
Y256352D01*
X531905Y272014D01*
X537499Y285516D01*
X541050Y303368D01*
Y303450D01*
X541051Y303456D01*
X543060Y323799D01*
Y414400D01*
X554300Y441536D01*
Y488225D01*
X549840Y492685D01*
Y565739D01*
X554300Y570199D01*
Y584998D01*
X579666Y610364D01*
X580359D01*
X581448Y611453D01*
Y612146D01*
X584496Y615194D01*
X585189D01*
X586278Y616283D01*
Y616976D01*
X590391Y621089D01*
X591084D01*
X592173Y622178D01*
Y622871D01*
X595946Y626644D01*
X596639D01*
X597728Y627733D01*
Y628426D01*
X601496Y632194D01*
X602189D01*
X603278Y633283D01*
Y633977D01*
X630824Y661523D01*
X658379Y672939D01*
X658381D01*
X736049Y688389D01*
X859284Y739434D01*
X867173Y744706D01*
X902600Y780134D01*
Y914810D01*
X903090Y915300D01*
Y916800D01*
X902600Y917290D01*
Y918790D01*
X894581Y969690D01*
Y976820D01*
X895071Y977310D01*
Y978810D01*
X894581Y979300D01*
Y980800D01*
X895071Y981290D01*
Y982790D01*
X894581Y983280D01*
Y984780D01*
X895981Y986180D01*
X896674D01*
X897736Y987242D01*
Y987935D01*
X900175Y990374D01*
X903474D01*
X904914Y988934D01*
G01X515539Y53544D02*
Y51682D01*
X514867Y51010D01*
Y47466D01*
X513363Y45962D01*
X508667D01*
X506761Y47868D01*
X494724Y76929D01*
X493956Y80788D01*
Y150428D01*
X508042Y196863D01*
X518243Y207064D01*
X526134Y233076D01*
Y256504D01*
X530943Y272358D01*
X536518Y285814D01*
X540022Y303436D01*
X540023D01*
X540028Y303457D01*
X540030Y303471D01*
Y303491D01*
X540034Y303541D01*
Y303546D01*
X540035Y303551D01*
Y303557D01*
X542040Y323850D01*
Y414603D01*
X553280Y441739D01*
Y487802D01*
X548820Y492262D01*
Y566162D01*
X553280Y570622D01*
Y585421D01*
X630246Y662388D01*
X658083Y673920D01*
X735751Y689370D01*
X858800Y740339D01*
X866522Y745499D01*
X901580Y780557D01*
Y918710D01*
X893561Y969610D01*
Y985203D01*
X899752Y991394D01*
X903474D01*
X904914Y992834D01*
G01X493179Y850286D02*
Y848177D01*
X493178Y848176D01*
G01X489479Y843877D02*
Y841768D01*
X489478Y841767D01*
Y841467D01*
G01X487628Y847081D02*
Y844972D01*
X487627Y844971D01*
G01X500579Y850286D02*
Y848177D01*
X500578Y848176D01*
G01X496879Y843877D02*
Y841768D01*
X496878Y841767D01*
Y841467D01*
G01X495028Y847081D02*
Y844972D01*
X495027Y844971D01*
G01X491328Y847081D02*
Y844972D01*
X491327Y844971D01*
G01X485779Y850286D02*
Y848177D01*
X485778Y848176D01*
G01X498728Y847081D02*
Y844972D01*
X498727Y844971D01*
G01X489479Y869511D02*
Y867402D01*
X489478Y867401D01*
G01X496879Y869511D02*
Y867402D01*
X496878Y867401D01*
G01X489479Y856694D02*
Y854585D01*
X489478Y854584D01*
G01X487628Y859899D02*
Y857790D01*
X487629Y857789D01*
G01X500579Y863103D02*
Y860994D01*
X500578Y860993D01*
G01X498728Y859899D02*
Y857790D01*
X498729Y857789D01*
G01X495028Y859899D02*
Y857790D01*
X495029Y857789D01*
G01X491328Y859899D02*
Y857790D01*
X491329Y857789D01*
G01X485779Y863103D02*
Y860994D01*
X485778Y860993D01*
G01X496879Y856694D02*
Y854585D01*
X496878Y854584D01*
G01X493179Y863103D02*
Y860994D01*
X493178Y860993D01*
G01X487628Y872716D02*
Y870607D01*
X487629Y870606D01*
G01X495028Y872716D02*
Y870607D01*
X495029Y870606D01*
G01X485779Y875920D02*
Y873811D01*
X485778Y873810D01*
G01X491328Y872716D02*
Y870607D01*
X491329Y870606D01*
G01X493179Y875920D02*
Y873811D01*
X493178Y873810D01*
G01X498728Y872716D02*
Y870607D01*
X498729Y870606D01*
G01X500579Y875920D02*
Y873811D01*
X500578Y873810D01*
G01X489479Y882329D02*
X489478Y882328D01*
Y880219D01*
G01X491328Y885533D02*
X491329Y885532D01*
Y883423D01*
G01X496879Y882329D02*
X496878Y882328D01*
Y880219D01*
G01X498728Y885533D02*
X498729Y885532D01*
Y883423D01*
G01X487628Y885533D02*
X487629Y885532D01*
Y883423D01*
G01X495028Y885533D02*
Y883424D01*
X495029Y883423D01*
G01X485779Y888737D02*
Y886628D01*
X485778Y886627D01*
G01X493179Y888737D02*
Y886628D01*
X493178Y886627D01*
G01X500579Y888737D02*
X500578Y888736D01*
Y886627D01*
G01X488061Y1125746D02*
Y1127855D01*
X488062Y1127856D01*
G01X499161Y1119337D02*
X499162Y1121447D01*
G01X495461Y1125746D02*
Y1127855D01*
X495462Y1127856D01*
G01X491761Y1119337D02*
X491762Y1121447D01*
G01X489912Y1122541D02*
Y1124650D01*
X489911Y1124651D01*
G01X486212Y1122541D02*
Y1124650D01*
X486211Y1124651D01*
G01X497312Y1122541D02*
Y1124650D01*
X497311Y1124651D01*
G01X493612Y1122541D02*
Y1124650D01*
X493611Y1124651D01*
G01X493612Y1135359D02*
Y1137469D01*
G01X488061Y1138563D02*
Y1140973D01*
G01X495461Y1138563D02*
Y1140973D01*
G01X491761Y1132154D02*
Y1134263D01*
X491762Y1134264D01*
G01X489912Y1135359D02*
Y1137469D01*
G01X486212Y1135359D02*
Y1137469D01*
G01X499161Y1132154D02*
Y1134263D01*
X499162Y1134264D01*
G01X497312Y1135359D02*
Y1137469D01*
G01X500571Y1578182D02*
X499394Y1579359D01*
Y1581811D01*
X500671Y1583088D01*
G01X488511Y1578182D02*
X487334Y1579359D01*
Y1581811D01*
X488611Y1583088D01*
G01X497171Y1578182D02*
X498374Y1579385D01*
Y1581803D01*
X497089Y1583088D01*
X497071D01*
G01X485111Y1578182D02*
X486314Y1579385D01*
Y1581803D01*
X485029Y1583088D01*
X485011D01*
G01X500571Y1590094D02*
X499384Y1588907D01*
Y1586475D01*
X500671Y1585188D01*
G01X488511Y1590094D02*
X487324Y1588907D01*
Y1586475D01*
X488611Y1585188D01*
G01X497171Y1590094D02*
X498364Y1588901D01*
Y1586468D01*
X497084Y1585188D01*
X497071D01*
G01X485111Y1590094D02*
X486304Y1588901D01*
Y1586468D01*
X485024Y1585188D01*
X485011D01*
G01X490411Y1614292D02*
X491604Y1613099D01*
Y1610666D01*
X490324Y1609386D01*
X490311D01*
G01X493811Y1614292D02*
X492624Y1613105D01*
Y1610673D01*
X493911Y1609386D01*
G01X490411Y1602380D02*
X491614Y1603583D01*
Y1606001D01*
X490329Y1607286D01*
X490311D01*
G01X493811Y1602380D02*
X492634Y1603557D01*
Y1606009D01*
X493911Y1607286D01*
G01X511679Y843877D02*
Y841467D01*
G01X509828Y847081D02*
Y844972D01*
X509827Y844971D01*
G01X504279Y843877D02*
Y841467D01*
G01X515379Y850286D02*
Y848177D01*
X515378Y848176D01*
G01X513528Y847081D02*
Y844972D01*
X513527Y844971D01*
G01X507979Y850286D02*
Y848177D01*
X507978Y848176D01*
G01X506128Y847081D02*
Y844972D01*
X506127Y844971D01*
G01X502428Y847081D02*
Y844972D01*
X502427Y844971D01*
G01X511679Y869511D02*
Y867402D01*
X511678Y867401D01*
G01X504279Y869511D02*
Y867402D01*
X504278Y867401D01*
G01X513528Y859899D02*
Y857790D01*
X513529Y857789D01*
G01X509828Y859899D02*
Y857790D01*
X509829Y857789D01*
G01X506128Y859899D02*
Y857790D01*
X506129Y857789D01*
G01X515379Y863103D02*
Y860994D01*
X515378Y860993D01*
G01X511679Y856694D02*
Y854585D01*
X511678Y854584D01*
G01X507979Y863103D02*
Y860994D01*
X507978Y860993D01*
G01X504279Y856694D02*
Y854585D01*
X504278Y854584D01*
G01X502428Y859899D02*
Y857790D01*
X502429Y857789D01*
G01X502428Y872716D02*
Y870607D01*
X502429Y870606D01*
G01X509828Y872716D02*
Y870607D01*
X509829Y870606D01*
G01X513528Y872716D02*
Y870607D01*
X513529Y870606D01*
G01X515379Y875920D02*
Y873811D01*
X515378Y873810D01*
G01X506128Y872716D02*
Y870607D01*
X506129Y870606D01*
G01X507979Y875920D02*
Y873811D01*
X507978Y873810D01*
G01X511679Y882329D02*
Y880220D01*
X511678Y880219D01*
G01X513528Y885533D02*
Y883424D01*
X513529Y883423D01*
G01X504279Y882329D02*
Y880220D01*
X504278Y880219D01*
G01X506128Y885533D02*
X506129Y885532D01*
Y883423D01*
G01X509828Y885533D02*
Y883424D01*
X509829Y883423D01*
G01X502428Y885533D02*
X502429Y885532D01*
Y883423D01*
G01X515379Y888737D02*
Y886628D01*
X515378Y886627D01*
G01X507979Y888737D02*
Y886628D01*
X507978Y886627D01*
G01X513961Y1119337D02*
X513962Y1121447D01*
G01X510261Y1125746D02*
Y1127855D01*
X510262Y1127856D01*
G01X506561Y1119337D02*
X506562Y1121447D01*
G01X502861Y1125746D02*
Y1127855D01*
X502862Y1127856D01*
G01X515812Y1122541D02*
Y1124650D01*
X515811Y1124651D01*
G01X512112Y1122541D02*
Y1124650D01*
X512111Y1124651D01*
G01X508412Y1122541D02*
Y1124650D01*
X508411Y1124651D01*
G01X504712Y1122541D02*
Y1124650D01*
X504711Y1124651D01*
G01X501012Y1122541D02*
Y1124650D01*
X501011Y1124651D01*
G01X513961Y1132154D02*
Y1134263D01*
X513962Y1134264D01*
G01X512112Y1135359D02*
Y1137469D01*
G01X506561Y1132154D02*
Y1134263D01*
X506562Y1134264D01*
G01X504712Y1135359D02*
Y1137469D01*
G01X501012Y1135359D02*
Y1137469D01*
G01X515812Y1135359D02*
Y1137469D01*
G01X510261Y1138563D02*
Y1140973D01*
G01X508412Y1135359D02*
Y1137469D01*
G01X502861Y1138563D02*
Y1140973D01*
G01X512631Y1578182D02*
X511454Y1579359D01*
Y1581811D01*
X512731Y1583088D01*
G01X509231Y1578182D02*
X510434Y1579385D01*
Y1581803D01*
X509149Y1583088D01*
X509131D01*
G01X512631Y1590094D02*
X511444Y1588907D01*
Y1586475D01*
X512731Y1585188D01*
G01X509231Y1590094D02*
X510424Y1588901D01*
Y1586468D01*
X509144Y1585188D01*
X509131D01*
G01X514531Y1614292D02*
X515724Y1613099D01*
Y1610666D01*
X514444Y1609386D01*
X514431D01*
G01X502471Y1614292D02*
X503664Y1613099D01*
Y1610666D01*
X502384Y1609386D01*
X502371D01*
G01X517931Y1614292D02*
X516744Y1613105D01*
Y1610673D01*
X518031Y1609386D01*
G01X505871Y1614292D02*
X504684Y1613105D01*
Y1610673D01*
X505971Y1609386D01*
G01X514531Y1602380D02*
X515734Y1603583D01*
Y1606001D01*
X514449Y1607286D01*
X514431D01*
G01X502471Y1602380D02*
X503674Y1603583D01*
Y1606001D01*
X502389Y1607286D01*
X502371D01*
G01X517931Y1602380D02*
X516754Y1603557D01*
Y1606009D01*
X518031Y1607286D01*
G01X505871Y1602380D02*
X504694Y1603557D01*
Y1606009D01*
X505971Y1607286D01*
G01X520264Y53544D02*
Y51288D01*
X520934Y50618D01*
Y44128D01*
X520950Y44112D01*
Y41514D01*
X519764Y40328D01*
G01X522626Y53544D02*
Y51258D01*
X521954Y50586D01*
Y44551D01*
X521970Y44535D01*
Y41522D01*
X523164Y40328D01*
G01X520264Y65158D02*
Y67278D01*
X520932Y67946D01*
Y70246D01*
X519742Y71436D01*
G01X522626Y65158D02*
Y67222D01*
X521952Y67896D01*
Y70246D01*
X523142Y71436D01*
G01X534437Y65158D02*
Y67599D01*
X535100Y68262D01*
Y70821D01*
X533612Y74411D01*
X528576Y79448D01*
X523130Y92593D01*
Y95112D01*
X524965Y96947D01*
X526110D01*
X527310Y98147D01*
G01X536799Y65158D02*
Y67573D01*
X536120Y68252D01*
Y71025D01*
X534477Y74989D01*
X532199Y77268D01*
Y78017D01*
X531194Y79022D01*
X530444D01*
X529441Y80026D01*
X528629Y81986D01*
X528916Y82678D01*
X528373Y83991D01*
X527679Y84278D01*
X527136Y85589D01*
X527423Y86282D01*
X526880Y87595D01*
X526186Y87882D01*
X525643Y89193D01*
X525930Y89885D01*
X525387Y91198D01*
X524693Y91485D01*
X524150Y92796D01*
Y94689D01*
X525388Y95927D01*
X526130D01*
X527310Y94747D01*
G01X532028Y847081D02*
Y844671D01*
G01X526479Y850286D02*
Y848177D01*
X526478Y848176D01*
G01X524628Y847081D02*
Y844972D01*
X524627Y844971D01*
G01X519079Y843877D02*
Y841467D01*
G01X517228Y847081D02*
Y844972D01*
X517227Y844971D01*
G01X530179Y850286D02*
Y848177D01*
X530178Y848176D01*
G01X522779Y850286D02*
Y848177D01*
X522778Y848176D01*
G01X520928Y847081D02*
Y844972D01*
X520927Y844971D01*
G01X519079Y869511D02*
Y867402D01*
X519078Y867401D01*
G01X526479Y869511D02*
Y867401D01*
G01X528329Y859899D02*
Y857789D01*
G01X522779Y863103D02*
Y860994D01*
X522778Y860993D01*
G01X520928Y859899D02*
Y857790D01*
X520929Y857789D01*
G01X517228Y859899D02*
Y857790D01*
X517229Y857789D01*
G01X526479Y856694D02*
Y854585D01*
X526478Y854584D01*
G01X524628Y859899D02*
Y857790D01*
X524629Y857789D01*
G01X519079Y856694D02*
Y854585D01*
X519078Y854584D01*
G01X517228Y872716D02*
X517229Y872715D01*
Y870606D01*
G01X524628Y872716D02*
X524629Y872715D01*
Y870606D01*
G01X532028Y872716D02*
X532029Y872715D01*
Y870606D01*
G01X520928Y872716D02*
Y870607D01*
X520929Y870606D01*
G01X522779Y875920D02*
Y873811D01*
X522778Y873810D01*
G01X528329Y870606D02*
Y872716D01*
G01X530179Y875920D02*
Y873811D01*
X530178Y873810D01*
G01X519079Y882329D02*
Y880220D01*
X519078Y880219D01*
G01X520928Y885533D02*
X520929Y885532D01*
Y883423D01*
G01X526479Y882329D02*
Y880219D01*
G01X528329Y885533D02*
Y883423D01*
G01X517228Y885533D02*
Y883424D01*
X517229Y883423D01*
G01X524628Y885533D02*
Y883424D01*
X524629Y883423D01*
G01X522779Y888737D02*
Y886628D01*
X522778Y886627D01*
G01X530179Y888737D02*
Y886627D01*
G01X526912Y1122541D02*
Y1124650D01*
X526911Y1124651D01*
G01X521361Y1119337D02*
X521362Y1121447D01*
G01X517661Y1125746D02*
Y1127855D01*
X517662Y1127856D01*
G01X525061Y1125746D02*
Y1127855D01*
X525062Y1127856D01*
G01X523212Y1122541D02*
Y1124650D01*
X523211Y1124651D01*
G01X519512Y1122541D02*
Y1124650D01*
X519511Y1124651D01*
G01X532461Y1132154D02*
Y1134263D01*
X532462Y1134264D01*
G01X525061Y1138563D02*
Y1140973D01*
G01X523212Y1135359D02*
Y1137469D01*
G01X517661Y1138563D02*
Y1140973D01*
G01X526912Y1137469D02*
Y1135359D01*
G01X521361Y1132154D02*
Y1134263D01*
X521362Y1134264D01*
G01X519512Y1135359D02*
Y1137469D01*
G01X524691Y1578182D02*
X523514Y1579359D01*
Y1581811D01*
X524791Y1583088D01*
G01X533351Y1578182D02*
X534554Y1579385D01*
Y1581803D01*
X533269Y1583088D01*
X533251D01*
G01X521291Y1578182D02*
X522494Y1579385D01*
Y1581803D01*
X521209Y1583088D01*
X521191D01*
G01X524691Y1590094D02*
X523504Y1588907D01*
Y1586475D01*
X524791Y1585188D01*
G01X533351Y1590094D02*
X534544Y1588901D01*
Y1586468D01*
X533264Y1585188D01*
X533251D01*
G01X521291Y1590094D02*
X522484Y1588901D01*
Y1586468D01*
X521204Y1585188D01*
X521191D01*
G01X526591Y1614292D02*
X527784Y1613099D01*
Y1610666D01*
X526504Y1609386D01*
X526491D01*
G01X529991Y1614292D02*
X528804Y1613105D01*
Y1610673D01*
X530091Y1609386D01*
G01X526591Y1602380D02*
X527794Y1603583D01*
Y1606001D01*
X526509Y1607286D01*
X526491D01*
G01X529991Y1602380D02*
X528814Y1603557D01*
Y1606009D01*
X530091Y1607286D01*
G01X534437Y53544D02*
Y55664D01*
X535105Y56332D01*
Y58632D01*
X533915Y59822D01*
G01X536799Y53544D02*
Y55668D01*
X536125Y56342D01*
Y58632D01*
X537315Y59822D01*
G01X548610Y65158D02*
Y67277D01*
G01X549264Y67931D02*
Y78178D01*
X548070Y79372D01*
G01X542192Y67946D02*
Y70246D01*
X541002Y71436D01*
G01X543212Y67896D02*
Y70246D01*
X544402Y71436D01*
G01X533879Y850286D02*
Y848177D01*
X533878Y848176D01*
G01X543561Y1106520D02*
Y1108630D01*
G01X534311Y1135359D02*
Y1137468D01*
X534312Y1137469D01*
G01X536751Y1578182D02*
X535574Y1579359D01*
Y1581811D01*
X536851Y1583088D01*
G01X548811Y1578182D02*
X547634Y1579359D01*
Y1581811D01*
X548911Y1583088D01*
G01X545411Y1578182D02*
X546614Y1579385D01*
Y1581803D01*
X545329Y1583088D01*
X545311D01*
G01X536751Y1590094D02*
X535564Y1588907D01*
Y1586475D01*
X536851Y1585188D01*
G01X548811Y1590094D02*
X547624Y1588907D01*
Y1586475D01*
X548911Y1585188D01*
G01X545411Y1590094D02*
X546604Y1588901D01*
Y1586468D01*
X545324Y1585188D01*
X545311D01*
G01X538651Y1614292D02*
X539844Y1613099D01*
Y1610666D01*
X538564Y1609386D01*
X538551D01*
G01X542051Y1614292D02*
X540864Y1613105D01*
Y1610673D01*
X542151Y1609386D01*
G01X538651Y1602380D02*
X539854Y1603583D01*
Y1606001D01*
X538569Y1607286D01*
X538551D01*
G01X542051Y1602380D02*
X540874Y1603557D01*
Y1606009D01*
X542151Y1607286D01*
G01X550284Y67931D02*
Y78186D01*
X551470Y79372D01*
G01X555697Y65158D02*
Y67278D01*
X556365Y67946D01*
Y70246D01*
X555175Y71436D01*
G01X558059Y65158D02*
Y67222D01*
X557385Y67896D01*
Y70246D01*
X558575Y71436D01*
G01X560871Y1578182D02*
X559694Y1579359D01*
Y1581811D01*
X560971Y1583088D01*
G01X557471Y1578182D02*
X558674Y1579385D01*
Y1581803D01*
X557389Y1583088D01*
X557371D01*
G01X560871Y1590094D02*
X559684Y1588907D01*
Y1586475D01*
X560971Y1585188D01*
G01X557471Y1590094D02*
X558664Y1588901D01*
Y1586468D01*
X557384Y1585188D01*
X557371D01*
G01X562771Y1614292D02*
X563964Y1613099D01*
Y1610666D01*
X562684Y1609386D01*
X562671D01*
G01X550711Y1614292D02*
X551904Y1613099D01*
Y1610666D01*
X550624Y1609386D01*
X550611D01*
G01X566171Y1614292D02*
X564984Y1613105D01*
Y1610673D01*
X566271Y1609386D01*
G01X554111Y1614292D02*
X552924Y1613105D01*
Y1610673D01*
X554211Y1609386D01*
G01X562771Y1602380D02*
X563974Y1603583D01*
Y1606001D01*
X562689Y1607286D01*
X562671D01*
G01X550711Y1602380D02*
X551914Y1603583D01*
Y1606001D01*
X550629Y1607286D01*
X550611D01*
G01X566171Y1602380D02*
X564994Y1603557D01*
Y1606009D01*
X566271Y1607286D01*
G01X554111Y1602380D02*
X552934Y1603557D01*
Y1606009D01*
X554211Y1607286D01*
G01X572931Y1578182D02*
X571754Y1579359D01*
Y1581811D01*
X573031Y1583088D01*
G01X581591Y1578182D02*
X582794Y1579385D01*
Y1581803D01*
X581509Y1583088D01*
X581491D01*
G01X569531Y1578182D02*
X570734Y1579385D01*
Y1581803D01*
X569449Y1583088D01*
X569431D01*
G01X572931Y1590094D02*
X571744Y1588907D01*
Y1586475D01*
X573031Y1585188D01*
G01X581591Y1590094D02*
X582784Y1588901D01*
Y1586468D01*
X581504Y1585188D01*
X581491D01*
G01X569531Y1590094D02*
X570724Y1588901D01*
Y1586468D01*
X569444Y1585188D01*
X569431D01*
G01X574831Y1614292D02*
X576024Y1613099D01*
Y1610666D01*
X574744Y1609386D01*
X574731D01*
G01X578231Y1614292D02*
X577044Y1613105D01*
Y1610673D01*
X578331Y1609386D01*
G01X574831Y1602380D02*
X576034Y1603583D01*
Y1606001D01*
X574749Y1607286D01*
X574731D01*
G01X578231Y1602380D02*
X577054Y1603557D01*
Y1606009D01*
X578331Y1607286D01*
G01X597051Y1578182D02*
X595874Y1579359D01*
Y1581811D01*
X597151Y1583088D01*
G01X584991Y1578182D02*
X583814Y1579359D01*
Y1581811D01*
X585091Y1583088D01*
G01X593651Y1578182D02*
X594854Y1579385D01*
Y1581803D01*
X593569Y1583088D01*
X593551D01*
G01X597051Y1590094D02*
X595864Y1588907D01*
Y1586475D01*
X597151Y1585188D01*
G01X584991Y1590094D02*
X583804Y1588907D01*
Y1586475D01*
X585091Y1585188D01*
G01X593651Y1590094D02*
X594844Y1588901D01*
Y1586468D01*
X593564Y1585188D01*
X593551D01*
G01X586891Y1614292D02*
X588084Y1613099D01*
Y1610666D01*
X586804Y1609386D01*
X586791D01*
G01X590291Y1614292D02*
X589104Y1613105D01*
Y1610673D01*
X590391Y1609386D01*
G01X586891Y1602380D02*
X588094Y1603583D01*
Y1606001D01*
X586809Y1607286D01*
X586791D01*
G01X590291Y1602380D02*
X589114Y1603557D01*
Y1606009D01*
X590391Y1607286D01*
G01X613660Y168966D02*
X615150Y167475D01*
X615149Y167474D01*
Y165163D01*
X619118Y161194D01*
Y159741D01*
X618644Y159267D01*
Y158279D01*
G01X612740Y180522D02*
Y183892D01*
X612910Y184062D01*
G01X613970Y188752D02*
X615230Y187492D01*
Y186382D01*
X612910Y184062D01*
G01X612736Y177350D02*
X613036Y177650D01*
X614364D01*
X615572Y176442D01*
G01X612736Y174200D02*
X615152Y171784D01*
Y170458D01*
X613660Y168966D01*
G01X609111Y1578182D02*
X607934Y1579359D01*
Y1581811D01*
X609211Y1583088D01*
G01X605711Y1578182D02*
X606914Y1579385D01*
Y1581803D01*
X605629Y1583088D01*
X605611D01*
G01X609111Y1590094D02*
X607924Y1588907D01*
Y1586475D01*
X609211Y1585188D01*
G01X605711Y1590094D02*
X606904Y1588901D01*
Y1586468D01*
X605624Y1585188D01*
X605611D01*
G01X611011Y1614292D02*
X612204Y1613099D01*
Y1610666D01*
X610924Y1609386D01*
X610911D01*
G01X598951Y1614292D02*
X600144Y1613099D01*
Y1610666D01*
X598864Y1609386D01*
X598851D01*
G01X614411Y1614292D02*
X613224Y1613105D01*
Y1610673D01*
X614511Y1609386D01*
G01X602351Y1614292D02*
X601164Y1613105D01*
Y1610673D01*
X602451Y1609386D01*
G01X611011Y1602380D02*
X612214Y1603583D01*
Y1606001D01*
X610929Y1607286D01*
X610911D01*
G01X598951Y1602380D02*
X600154Y1603583D01*
Y1606001D01*
X598869Y1607286D01*
X598851D01*
G01X614411Y1602380D02*
X613234Y1603557D01*
Y1606009D01*
X614511Y1607286D01*
G01X602351Y1602380D02*
X601174Y1603557D01*
Y1606009D01*
X602451Y1607286D01*
G01X617660Y168965D02*
X616169Y167475D01*
Y165586D01*
X620138Y161617D01*
Y159793D01*
X620612Y159319D01*
Y158279D01*
G01X626929Y163506D02*
X624824D01*
X624822Y163508D01*
X624821D01*
X624076Y162763D01*
Y159677D01*
X624550Y159203D01*
Y158279D01*
G01X626929Y163506D02*
Y165616D01*
X626935D01*
X628800Y167481D01*
Y168101D01*
X631025Y170326D01*
Y170994D01*
G01X624101Y166335D02*
X624100Y164230D01*
X623056Y163186D01*
Y159549D01*
X622581Y159074D01*
Y158279D01*
G01X624101Y166335D02*
X626211D01*
X627780Y167904D01*
Y168092D01*
X625596Y170276D01*
Y170994D01*
G01X631025Y174144D02*
X629965D01*
X628195Y175914D01*
G01X625596Y174144D02*
X626922D01*
X628194Y172872D01*
G01X618352Y180562D02*
Y183902D01*
X618232Y184022D01*
G01X617370Y188752D02*
X616250Y187632D01*
Y186004D01*
X618232Y184022D01*
G01X631025Y177294D02*
Y179287D01*
X628850Y181462D01*
Y187562D01*
X630040Y188752D01*
G01X625596Y177294D02*
Y179228D01*
X627830Y181462D01*
Y187562D01*
X626640Y188752D01*
G01X618352Y177412D02*
X617645D01*
X615573Y179484D01*
G01X618352Y174262D02*
Y174032D01*
X616168Y171848D01*
Y170457D01*
X617660Y168965D01*
G01X621171Y1578182D02*
X619994Y1579359D01*
Y1581811D01*
X621271Y1583088D01*
G01X629831Y1578182D02*
X631034Y1579385D01*
Y1581803D01*
X629749Y1583088D01*
X629731D01*
G01X617771Y1578182D02*
X618974Y1579385D01*
Y1581803D01*
X617689Y1583088D01*
X617671D01*
G01X621171Y1590094D02*
X619984Y1588907D01*
Y1586475D01*
X621271Y1585188D01*
G01X629831Y1590094D02*
X631024Y1588901D01*
Y1586468D01*
X629744Y1585188D01*
X629731D01*
G01X617771Y1590094D02*
X618964Y1588901D01*
Y1586468D01*
X617684Y1585188D01*
X617671D01*
G01X623071Y1614292D02*
X624264Y1613099D01*
Y1610666D01*
X622984Y1609386D01*
X622971D01*
G01X626471Y1614292D02*
X625284Y1613105D01*
Y1610673D01*
X626571Y1609386D01*
G01X623071Y1602380D02*
X624274Y1603583D01*
Y1606001D01*
X622989Y1607286D01*
X622971D01*
G01X626471Y1602380D02*
X625294Y1603557D01*
Y1606009D01*
X626571Y1607286D01*
G01X645291Y1578182D02*
X644114Y1579359D01*
Y1581811D01*
X645391Y1583088D01*
G01X633231Y1578182D02*
X632054Y1579359D01*
Y1581811D01*
X633331Y1583088D01*
G01X641891Y1578182D02*
X643094Y1579385D01*
Y1581803D01*
X641809Y1583088D01*
X641791D01*
G01X645291Y1590094D02*
X644104Y1588907D01*
Y1586475D01*
X645391Y1585188D01*
G01X633231Y1590094D02*
X632044Y1588907D01*
Y1586475D01*
X633331Y1585188D01*
G01X641891Y1590094D02*
X643084Y1588901D01*
Y1586468D01*
X641804Y1585188D01*
X641791D01*
G01X647191Y1614292D02*
X648384Y1613099D01*
Y1610666D01*
X647104Y1609386D01*
X647091D01*
G01X635131Y1614292D02*
X636324Y1613099D01*
Y1610666D01*
X635044Y1609386D01*
X635031D01*
G01X638531Y1614292D02*
X637344Y1613105D01*
Y1610673D01*
X638631Y1609386D01*
G01X647191Y1602380D02*
X648394Y1603583D01*
Y1606001D01*
X647109Y1607286D01*
X647091D01*
G01X635131Y1602380D02*
X636334Y1603583D01*
Y1606001D01*
X635049Y1607286D01*
X635031D01*
G01X638531Y1602380D02*
X637354Y1603557D01*
Y1606009D01*
X638631Y1607286D01*
G01X656957Y53544D02*
Y51476D01*
X657629Y50804D01*
Y48454D01*
X656439Y47264D01*
G01X659319Y53544D02*
Y51424D01*
X658649Y50754D01*
Y48454D01*
X659839Y47264D01*
G01X664043Y53544D02*
Y51488D01*
X664714Y50817D01*
Y44499D01*
X663543Y43328D01*
G01X657351Y1578182D02*
X656174Y1579359D01*
Y1581811D01*
X657451Y1583088D01*
G01X653951Y1578182D02*
X655154Y1579385D01*
Y1581803D01*
X653869Y1583088D01*
X653851D01*
G01X657351Y1590094D02*
X656164Y1588907D01*
Y1586475D01*
X657451Y1585188D01*
G01X653951Y1590094D02*
X655144Y1588901D01*
Y1586468D01*
X653864Y1585188D01*
X653851D01*
G01X662651Y1614292D02*
X661464Y1613105D01*
Y1610673D01*
X662751Y1609386D01*
G01X659251Y1614292D02*
X660444Y1613099D01*
Y1610666D01*
X659164Y1609386D01*
X659151D01*
G01X650591Y1614292D02*
X649404Y1613105D01*
Y1610673D01*
X650691Y1609386D01*
G01X662651Y1602380D02*
X661474Y1603557D01*
Y1606009D01*
X662751Y1607286D01*
G01X659251Y1602380D02*
X660454Y1603583D01*
Y1606001D01*
X659169Y1607286D01*
X659151D01*
G01X650591Y1602380D02*
X649414Y1603557D01*
Y1606009D01*
X650691Y1607286D01*
G01X666406Y53544D02*
Y51469D01*
X665734Y50797D01*
Y44537D01*
X666943Y43328D01*
G01X671130Y53544D02*
Y51476D01*
X671802Y50804D01*
Y48454D01*
X670612Y47264D01*
G01X673492Y53544D02*
Y51424D01*
X672822Y50754D01*
Y48454D01*
X674012Y47264D01*
G01X705800Y167788D02*
X704610Y168978D01*
X700336D01*
X699862Y168504D01*
X697276D01*
G01X705800Y171188D02*
X704610Y169998D01*
X700274D01*
X699800Y170472D01*
X697276D01*
G01Y182283D02*
X699866D01*
X700340Y181809D01*
X703580D01*
X704770Y182999D01*
G01X697276Y180315D02*
X699606D01*
X700080Y180789D01*
X703580D01*
X704770Y179599D01*
G01X697276Y174409D02*
X699868D01*
X700342Y174883D01*
X708396D01*
X709692Y173587D01*
G01X697276Y176378D02*
X699803D01*
X700278Y175903D01*
X708408D01*
X709692Y177187D01*
G01X716698Y173687D02*
X715508Y174877D01*
X713082D01*
X711792Y173587D01*
G01X716698Y177087D02*
X715508Y175897D01*
X713082D01*
X711792Y177187D01*
G01X697276Y194094D02*
X699866D01*
X700340Y193620D01*
X703580D01*
X704770Y194810D01*
G01X697276Y192126D02*
X699606D01*
X700080Y192600D01*
X703580D01*
X704770Y191410D01*
G01X697276Y198031D02*
X699888D01*
X700362Y198505D01*
X708274D01*
X709692Y197087D01*
G01X697276Y186220D02*
X699878D01*
X700352Y186694D01*
X708620D01*
X709692Y185622D01*
Y185587D01*
G01X697276Y200000D02*
X699783D01*
X700258Y199525D01*
X708530D01*
X709692Y200687D01*
G01Y189187D02*
X708219Y187714D01*
X700268D01*
X699793Y188189D01*
X697276D01*
G01X716698Y197187D02*
X715443Y198442D01*
X713147D01*
X711792Y197087D01*
G01X716698Y185687D02*
X715513Y186872D01*
X713077D01*
X711792Y185587D01*
G01X716698Y200587D02*
X715573Y199462D01*
X713017D01*
X711792Y200687D01*
G01X716698Y189087D02*
X715503Y187892D01*
X713087D01*
X711792Y189187D01*
G01X697276Y217716D02*
X699866D01*
X700340Y217242D01*
X703580D01*
X704770Y218432D01*
G01X697276Y205905D02*
X699866D01*
X700340Y205431D01*
X703580D01*
X704770Y206621D01*
G01X697276Y215748D02*
X699606D01*
X700080Y216222D01*
X703580D01*
X704770Y215032D01*
G01X697276Y203937D02*
X699606D01*
X700080Y204411D01*
X703580D01*
X704770Y203221D01*
G01X697276Y209842D02*
X699700D01*
X700174Y210316D01*
X708297D01*
X709692Y208921D01*
G01X697276Y211811D02*
X699771D01*
X700246Y211336D01*
X708507D01*
X709692Y212521D01*
G01X716698Y209021D02*
Y209124D01*
X715580Y210242D01*
X713113D01*
X711792Y208921D01*
G01X716698Y212421D02*
Y212380D01*
X715580Y211262D01*
X713051D01*
X711792Y212521D01*
G01X720360Y-12484D02*
X723041Y-13200D01*
G01X720360Y-10516D02*
X723041Y-9800D01*
G01X733315Y65158D02*
X733314Y65159D01*
Y67486D01*
X733985Y68157D01*
Y70244D01*
X732793Y71436D01*
G01X735677Y65158D02*
X735676Y65159D01*
Y67456D01*
X735005Y68127D01*
Y70248D01*
X736193Y71436D01*
G01X933773Y530479D02*
X932762Y531490D01*
Y535234D01*
X931766Y536230D01*
X929746Y537247D01*
X813150Y554543D01*
X749271Y581004D01*
X746540Y583735D01*
Y584428D01*
X745479Y585489D01*
X744786D01*
X743196Y587079D01*
Y587772D01*
X742134Y588834D01*
X741441D01*
X740381Y589894D01*
Y590587D01*
X739319Y591649D01*
X738626D01*
X737566Y592709D01*
Y593402D01*
X736504Y594464D01*
X735811D01*
X734040Y596235D01*
Y604040D01*
X735032Y605032D01*
X735520D01*
X736710Y603842D01*
G01Y607242D02*
X735520Y606052D01*
X734609D01*
X733020Y604463D01*
Y595812D01*
X748693Y580139D01*
X812876Y553552D01*
X929434Y536262D01*
X931160Y535392D01*
X931742Y534811D01*
Y531490D01*
X930731Y530479D01*
G01X837320Y19484D02*
X840001Y20200D01*
G01X837320Y17516D02*
X840001Y16800D01*
G01X899073Y489299D02*
X897583Y490789D01*
X890629D01*
X889439Y489599D01*
G01X899073Y493299D02*
X897583Y491809D01*
X890629D01*
X889439Y492999D01*
G01X881680Y504742D02*
X882790Y505852D01*
X903142D01*
X911202Y502513D01*
X913888D01*
X914362Y502039D01*
G01X881680Y508142D02*
X882950Y506872D01*
X903345D01*
X911405Y503533D01*
X913883D01*
X913893Y503543D01*
X913898D01*
X914362Y504007D01*
G01X888130Y532612D02*
X889310Y531432D01*
Y526259D01*
X894867Y520702D01*
X900635D01*
X908397Y517486D01*
X914837Y511046D01*
Y510388D01*
X914362Y509913D01*
G01X891530Y532612D02*
X890340Y531422D01*
Y526672D01*
X895290Y521722D01*
X900838D01*
X908975Y518351D01*
X915857Y511469D01*
Y510393D01*
X915867Y510383D01*
Y510377D01*
X916331Y509913D01*
G01X902350Y208294D02*
X903575Y207069D01*
X910851D01*
X911518Y207736D01*
X913386D01*
G01X907470Y211980D02*
X908689Y213199D01*
X910997D01*
X911735Y212461D01*
X913386D01*
G01X902350Y204894D02*
X903505Y206049D01*
X910957D01*
X911632Y205374D01*
X913386D01*
G01X907470Y215380D02*
X908631Y214219D01*
X911040D01*
X911644Y214823D01*
X913386D01*
G01Y219547D02*
X911633D01*
X910922Y220258D01*
X903540D01*
X902350Y219068D01*
G01X913386Y226634D02*
X911736D01*
X911026Y227344D01*
X908660D01*
X907470Y226154D01*
G01X913386Y221909D02*
X911529D01*
X910898Y221278D01*
X903540D01*
X902350Y222468D01*
G01X913386Y228996D02*
X911658D01*
X911026Y228364D01*
X908660D01*
X907470Y229554D01*
G01X902223Y489299D02*
X903836Y490912D01*
X906573D01*
X908331Y492670D01*
X913888D01*
X914362Y492196D01*
G01X902223Y493299D02*
X903590Y491932D01*
X906150D01*
X907908Y493690D01*
X913887D01*
X914362Y494165D01*
G01X899278Y480913D02*
X897819Y482372D01*
X897210D01*
X896060Y481222D01*
G01X899278Y484913D02*
X897757Y483392D01*
X897290D01*
X896060Y484622D01*
G01X902428Y480913D02*
X903977Y482462D01*
X907747D01*
X911160Y485875D01*
Y487873D01*
X912020Y488733D01*
X913888D01*
X914362Y488259D01*
G01X902428Y484913D02*
X903859Y483482D01*
X907324D01*
X910140Y486298D01*
Y488296D01*
X911597Y489753D01*
X913887D01*
X914362Y490228D01*
G01X899058Y497573D02*
X897599Y499032D01*
X896490D01*
X895340Y497882D01*
G01X899058Y501573D02*
X897537Y500052D01*
X896561D01*
X895340Y501273D01*
Y501282D01*
G01X914362Y498102D02*
X913878Y498586D01*
X907209D01*
X906698Y499097D01*
X903732D01*
X902208Y497573D01*
G01Y501573D02*
X903664Y500117D01*
X907121D01*
X907632Y499606D01*
X913898D01*
X914362Y500070D01*
G01X901829Y512730D02*
X903019Y513920D01*
X904319D01*
X911789Y506450D01*
X913888D01*
X914362Y505976D01*
G01X901829Y516130D02*
X903019Y514940D01*
X904742D01*
X912212Y507470D01*
X913883D01*
X913893Y507480D01*
X913898D01*
X914362Y507944D01*
G01X901230Y531612D02*
X902440Y530402D01*
Y528359D01*
X903657Y527142D01*
X917913D01*
X919985Y525756D01*
X922740Y519104D01*
Y510417D01*
X922236Y509913D01*
G01X904630Y531612D02*
X903460Y530442D01*
Y528782D01*
X904080Y528162D01*
X918223D01*
X920810Y526433D01*
X923760Y519307D01*
Y510417D01*
X923770Y510407D01*
Y510348D01*
X924205Y509913D01*
G01X904914Y971234D02*
X903468Y972680D01*
X901026D01*
X899830Y971484D01*
G01X904914Y975134D02*
X903480Y973700D01*
X901014D01*
X899830Y974884D01*
G01X912984Y458135D02*
X911810Y459309D01*
Y460370D01*
X913293Y461853D01*
G01X909584Y458135D02*
X910790Y459341D01*
Y460356D01*
X909293Y461853D01*
G01X913293Y465003D02*
X912829D01*
X911820Y466012D01*
Y467017D01*
X912902Y468099D01*
X913948D01*
X917820Y471971D01*
Y487780D01*
X918299Y488259D01*
G01X909293Y465003D02*
X909791D01*
X910800Y466012D01*
Y467440D01*
X912479Y469119D01*
X913525D01*
X916800Y472394D01*
Y487790D01*
X916331Y488259D01*
G01X924747Y467652D02*
X923257Y466162D01*
Y464202D01*
X924447Y463012D01*
G01X920747Y467652D02*
X922237Y466162D01*
Y464202D01*
X921047Y463012D01*
G01X924747Y470802D02*
X923240Y472309D01*
Y475539D01*
X925699Y477998D01*
Y487785D01*
X926173Y488259D01*
G01X920747Y470802D02*
X922220Y472275D01*
Y475962D01*
X924679Y478421D01*
Y487785D01*
X924205Y488259D01*
G01X913394Y521662D02*
X914580Y520476D01*
Y517776D01*
X918784Y513572D01*
Y510399D01*
X918774Y510389D01*
Y510388D01*
X918299Y509913D01*
G01X916794Y521662D02*
X915600Y520468D01*
Y518199D01*
X919804Y513995D01*
Y510389D01*
X919803Y510388D01*
Y510378D01*
X920268Y509913D01*
G01X919407Y981813D02*
X918829D01*
X918442Y982200D01*
X916233D01*
X914230Y980197D01*
Y974567D01*
X912313Y972650D01*
X909480D01*
X908064Y971234D01*
G01X919407Y983781D02*
X918869D01*
X918308Y983220D01*
X915810D01*
X913210Y980620D01*
Y974990D01*
X911890Y973670D01*
X909528D01*
X908064Y975134D01*
G01X919407Y989687D02*
X918785D01*
X918311Y990161D01*
X909291D01*
X908064Y988934D01*
G01X919407Y991655D02*
X918703D01*
X918229Y991181D01*
X909717D01*
X908064Y992834D01*
G01X944250Y194489D02*
X943050Y195689D01*
X940477D01*
X937168Y198998D01*
X933879D01*
X933168Y198287D01*
X931496D01*
G01Y200649D02*
X933220D01*
X933851Y200018D01*
X937591D01*
X940900Y196709D01*
X943070D01*
X944250Y197889D01*
G01X931496Y207736D02*
X933163D01*
X933795Y207104D01*
X939225D01*
X940496Y208375D01*
G01X931496Y214823D02*
X933147D01*
X933779Y214191D01*
X939190D01*
X940496Y215497D01*
G01X931496Y205374D02*
X933075D01*
X933785Y206084D01*
X939187D01*
X940496Y204775D01*
G01X931496Y212461D02*
X933081D01*
X933791Y213171D01*
X939222D01*
X940496Y211897D01*
G01X931496Y219547D02*
X933248D01*
X933959Y220258D01*
X945886D01*
X947196Y218948D01*
G01X931496Y226634D02*
X933105D01*
X933815Y227344D01*
X939187D01*
X940496Y226035D01*
G01X931496Y221909D02*
X933390D01*
X934021Y221278D01*
X945926D01*
X947196Y222548D01*
G01X931496Y228996D02*
X933163D01*
X933795Y228364D01*
X939225D01*
X940496Y229635D01*
G01X937747Y467652D02*
X936257Y466162D01*
Y459052D01*
X937447Y457862D01*
G01X933747Y467652D02*
X935237Y466162D01*
Y459052D01*
X934047Y457862D01*
G01X937747Y470802D02*
X936220Y472329D01*
Y475962D01*
X929636Y482546D01*
Y487785D01*
X930110Y488259D01*
G01X933747Y470802D02*
X935200Y472255D01*
Y475539D01*
X928616Y482123D01*
Y487785D01*
X928142Y488259D01*
G01X945747Y470802D02*
X944320Y472229D01*
Y476662D01*
X941120Y479862D01*
X939120D01*
X933573Y485409D01*
Y487785D01*
X934047Y488259D01*
G01X941747Y470802D02*
X943300Y472355D01*
Y476239D01*
X940697Y478842D01*
X938697D01*
X932553Y484986D01*
Y487785D01*
X932079Y488259D01*
G01X955270Y484271D02*
Y484171D01*
X953850Y482752D01*
X946753D01*
X939751Y489754D01*
X936490D01*
X936016Y490228D01*
G01X955245Y480262D02*
X953775Y481732D01*
X946330D01*
X939328Y488734D01*
X936491D01*
X936016Y488259D01*
G01Y505976D02*
X936491Y505501D01*
X940007D01*
X943052Y506762D01*
X945537D01*
X946727Y507952D01*
G01X936016Y504007D02*
X936490Y504481D01*
X940210D01*
X943255Y505742D01*
X945537D01*
X946727Y504552D01*
G01X936016Y509913D02*
X936491Y509438D01*
X937498D01*
X942165Y510367D01*
X949637Y513462D01*
X953230D01*
X954420Y514652D01*
G01X936016Y507944D02*
X936490Y508418D01*
X937599D01*
X942463Y509386D01*
X949840Y512442D01*
X953230D01*
X954420Y511252D01*
G01X932079Y509913D02*
X932553Y510387D01*
Y514338D01*
X939587Y521372D01*
X957630D01*
X965120Y528862D01*
Y532172D01*
X963930Y533362D01*
G01X934047Y509913D02*
X933573Y510387D01*
Y513915D01*
X940010Y520352D01*
X958053D01*
X966140Y528439D01*
Y532172D01*
X967330Y533362D01*
G01X928142Y509913D02*
X928616Y510387D01*
Y516862D01*
X936766Y525012D01*
X955036D01*
X955580Y525556D01*
Y526406D01*
X954390Y527596D01*
G01X930110Y509913D02*
X929636Y510387D01*
Y516439D01*
X937189Y523992D01*
X955459D01*
X956600Y525133D01*
Y526406D01*
X957790Y527596D01*
G01X936016Y502039D02*
X936485Y501570D01*
X940976D01*
X944565Y500084D01*
X945277Y499372D01*
X953240D01*
X954420Y500552D01*
G01Y497152D02*
X953220Y498352D01*
X944854D01*
X943987Y499219D01*
X940773Y500550D01*
X936496D01*
X936016Y500070D01*
G01X953970Y208275D02*
X952780Y207085D01*
X943786D01*
X942596Y208275D01*
Y208375D01*
G01X947496Y215397D02*
X946306Y214207D01*
X943786D01*
X942596Y215397D01*
Y215497D01*
G01X953970Y204875D02*
X952780Y206065D01*
X943786D01*
X942596Y204875D01*
Y204775D01*
G01X947496Y211997D02*
X946306Y213187D01*
X943786D01*
X942596Y211997D01*
Y211897D01*
G01X949296Y218948D02*
X950586Y220238D01*
X951739D01*
X953000Y221499D01*
Y227136D01*
X954217Y228353D01*
X955966D01*
X957156Y227163D01*
G01X947496Y226135D02*
X946306Y227325D01*
X943786D01*
X942596Y226135D01*
Y226035D01*
G01X949296Y222548D02*
X950586Y221258D01*
X951316D01*
X951980Y221922D01*
Y227559D01*
X953794Y229373D01*
X955966D01*
X957156Y230563D01*
G01X947496Y229535D02*
X946306Y228345D01*
X943786D01*
X942596Y229535D01*
Y229635D01*
G01X991369Y398871D02*
X990593D01*
X990119Y398397D01*
X989430D01*
X977803Y404989D01*
X956070Y426721D01*
X952960D01*
X951557Y428124D01*
G01X991369Y396902D02*
X990614D01*
X990139Y397377D01*
X989160D01*
X977179Y404169D01*
X955647Y425701D01*
X953037D01*
X951634Y424298D01*
G01X948407Y428124D02*
X947004Y426721D01*
X942249D01*
X941059Y427911D01*
G01X948484Y424298D02*
X947081Y425701D01*
X942249D01*
X941059Y424511D01*
G01X991369Y402808D02*
X990593D01*
X990119Y402334D01*
X989680D01*
X989567Y402381D01*
X989452Y402429D01*
X987736Y404146D01*
X973111Y416148D01*
X970982Y421288D01*
X955829Y436441D01*
X952933D01*
X951530Y437844D01*
G01X991369Y400839D02*
X990614D01*
X990139Y401314D01*
X989477D01*
X988874Y401563D01*
X987049Y403389D01*
X974792Y413449D01*
X974791D01*
X972266Y415521D01*
X970117Y420710D01*
X965358Y425468D01*
X956523Y434303D01*
X955406Y435421D01*
X953010D01*
X951607Y434018D01*
G01X948380Y437844D02*
X946977Y436441D01*
X945222D01*
X944032Y437631D01*
G01X948457Y434018D02*
X947054Y435421D01*
X945222D01*
X944032Y434231D01*
G01X945747Y467652D02*
X944257Y466162D01*
Y464202D01*
X945447Y463012D01*
G01X941747Y467652D02*
X943237Y466162D01*
Y464202D01*
X942047Y463012D01*
G01X958420Y484271D02*
X959958Y482733D01*
X967060Y482715D01*
X968286Y483941D01*
G01X958395Y480262D02*
X959846Y481713D01*
X959956D01*
X967058Y481695D01*
X967132D01*
X968286Y480541D01*
G01X983580Y-12484D02*
X980899Y-13200D01*
G01X983580Y-10516D02*
X980899Y-9800D01*
G01X983580Y19484D02*
X980899Y20200D01*
G01X983580Y17516D02*
X980899Y16800D01*
G01X993830Y407237D02*
Y408217D01*
X994304Y408691D01*
Y409501D01*
X988517Y415288D01*
Y423003D01*
X987139Y424381D01*
G01Y427531D02*
X988580Y428972D01*
Y430064D01*
X987451Y431193D01*
X987440D01*
G01X995798Y407237D02*
Y408111D01*
X995324Y408585D01*
Y409924D01*
X989537Y415711D01*
Y422778D01*
X991140Y424381D01*
G01Y427531D02*
X989600Y429071D01*
Y429953D01*
X990840Y431193D01*
G01X1011546Y407237D02*
Y408092D01*
X1011077Y408561D01*
Y411130D01*
X1013841Y413894D01*
Y420518D01*
X1015081Y421758D01*
Y422804D01*
X1016506Y424229D01*
G01X1009578Y407237D02*
Y408084D01*
X1010057Y408563D01*
Y411553D01*
X1012821Y414317D01*
Y420941D01*
X1014061Y422181D01*
Y422674D01*
X1012506Y424229D01*
G01X1016506Y427379D02*
X1015130Y428755D01*
Y431757D01*
X1016261Y432888D01*
G01X1012506Y427379D02*
X1014110Y428983D01*
Y431639D01*
X1012861Y432888D01*
G01X1029752Y-22495D02*
X1032433Y-23211D01*
G01X1029752Y-20527D02*
X1032433Y-19811D01*
G01X1029752Y-2495D02*
X1032433Y-3211D01*
G01X1029752Y-527D02*
X1032433Y189D01*
G01X1029752Y17505D02*
X1030210D01*
X1030730Y18025D01*
X1045255D01*
X1046781Y16746D01*
X1048291Y8177D01*
X1049585Y7272D01*
X1055233Y8267D01*
X1056142Y9562D01*
X1052400Y30777D01*
X1052822Y31378D01*
X1057638Y32228D01*
X1058239Y31806D01*
X1062388Y8282D01*
X1063682Y7376D01*
X1069330Y8371D01*
X1070239Y9666D01*
X1066535Y30664D01*
X1066957Y31265D01*
X1071773Y32115D01*
X1072374Y31693D01*
X1076485Y8386D01*
X1077779Y7480D01*
X1083427Y8475D01*
X1084336Y9770D01*
X1080673Y30538D01*
X1081095Y31140D01*
X1085911Y31990D01*
X1086511Y31568D01*
X1090582Y8490D01*
X1091876Y7584D01*
X1097524Y8579D01*
X1098433Y9874D01*
X1094741Y30805D01*
X1095163Y31406D01*
X1099979Y32256D01*
X1100580Y31834D01*
X1104679Y8594D01*
X1105973Y7688D01*
X1111621Y8683D01*
X1112530Y9978D01*
X1108846Y30862D01*
X1109268Y31462D01*
X1114084Y32312D01*
X1114685Y31891D01*
X1118805Y8530D01*
X1120099Y7622D01*
X1125748Y8618D01*
X1126656Y9913D01*
X1122957Y30886D01*
X1123363Y31465D01*
X1128217Y32321D01*
X1128796Y31915D01*
X1132916Y8549D01*
X1134210Y7641D01*
X1139860Y8637D01*
X1140766Y9933D01*
X1137068Y30907D01*
X1137474Y31486D01*
X1142328Y32342D01*
X1142907Y31936D01*
X1147097Y8168D01*
X1148393Y7262D01*
X1154042Y8257D01*
X1154947Y9551D01*
X1151158Y31040D01*
X1151564Y31619D01*
X1156418Y32475D01*
X1156997Y32069D01*
X1161152Y8501D01*
X1162448Y7595D01*
X1168096Y8591D01*
X1169003Y9886D01*
X1165289Y30946D01*
X1165695Y31525D01*
X1170549Y32381D01*
X1171128Y31975D01*
X1175249Y8607D01*
X1176544Y7701D01*
X1182192Y8696D01*
X1183098Y9992D01*
X1179377Y31101D01*
X1179782Y31681D01*
X1184637Y32537D01*
X1185238Y32116D01*
X1189342Y8850D01*
X1190636Y7944D01*
X1196284Y8939D01*
X1197193Y10234D01*
X1193555Y30860D01*
X1193977Y31461D01*
X1198793Y32311D01*
X1199394Y31890D01*
X1203468Y8786D01*
X1204763Y7878D01*
X1210411Y8874D01*
X1211319Y10169D01*
X1207657Y30934D01*
X1208063Y31513D01*
X1212917Y32369D01*
X1213495Y31963D01*
X1217579Y8805D01*
X1218874Y7897D01*
X1224523Y8893D01*
X1225429Y10189D01*
X1221780Y30884D01*
X1222186Y31463D01*
X1227040Y32319D01*
X1227619Y31913D01*
X1231760Y8424D01*
X1233056Y7518D01*
X1238705Y8513D01*
X1239610Y9807D01*
X1235892Y30892D01*
X1236298Y31471D01*
X1241152Y32327D01*
X1241731Y31921D01*
X1245815Y8757D01*
X1247111Y7851D01*
X1252759Y8847D01*
X1253666Y10142D01*
X1249989Y30989D01*
X1250395Y31568D01*
X1255249Y32424D01*
X1255828Y32018D01*
X1259911Y8863D01*
X1261207Y7957D01*
X1266855Y8952D01*
X1267761Y10248D01*
X1264094Y31049D01*
X1264500Y31628D01*
X1269355Y32484D01*
X1269934Y32078D01*
X1271977Y20489D01*
X1274487Y17979D01*
X1292062D01*
X1292536Y17505D01*
X1292972D01*
G01X1029752Y19473D02*
X1030188D01*
X1030616Y19045D01*
X1045627D01*
X1047721Y17289D01*
X1049223Y8771D01*
X1049824Y8350D01*
X1054640Y9199D01*
X1055063Y9802D01*
X1051321Y31017D01*
X1052229Y32310D01*
X1057878Y33307D01*
X1059171Y32399D01*
X1063320Y8876D01*
X1063921Y8454D01*
X1068737Y9303D01*
X1069160Y9906D01*
X1065456Y30904D01*
X1066364Y32197D01*
X1072013Y33194D01*
X1073306Y32286D01*
X1077417Y8980D01*
X1078018Y8558D01*
X1082834Y9407D01*
X1083257Y10010D01*
X1079594Y30777D01*
X1080502Y32072D01*
X1086151Y33069D01*
X1087443Y32161D01*
X1091514Y9084D01*
X1092115Y8662D01*
X1096931Y9511D01*
X1097354Y10114D01*
X1093662Y31045D01*
X1094570Y32338D01*
X1100219Y33335D01*
X1101512Y32427D01*
X1105611Y9188D01*
X1106212Y8766D01*
X1111028Y9615D01*
X1111451Y10218D01*
X1107767Y31102D01*
X1108675Y32394D01*
X1114323Y33390D01*
X1115617Y32485D01*
X1119737Y9123D01*
X1120339Y8701D01*
X1125155Y9550D01*
X1125577Y10153D01*
X1121878Y31126D01*
X1122770Y32397D01*
X1128457Y33400D01*
X1129728Y32508D01*
X1133848Y9142D01*
X1134450Y8720D01*
X1139266Y9569D01*
X1139688Y10172D01*
X1135989Y31147D01*
X1136881Y32418D01*
X1142568Y33421D01*
X1143839Y32529D01*
X1148029Y8762D01*
X1148632Y8340D01*
X1153448Y9189D01*
X1153869Y9790D01*
X1150079Y31280D01*
X1150971Y32551D01*
X1156658Y33554D01*
X1157929Y32662D01*
X1162084Y9097D01*
X1162687Y8673D01*
Y8674D01*
X1167502Y9523D01*
X1167925Y10125D01*
X1164210Y31186D01*
X1165102Y32457D01*
X1170789Y33460D01*
X1172060Y32568D01*
X1176181Y9201D01*
X1176783Y8779D01*
X1181598Y9628D01*
X1182020Y10231D01*
X1178299Y31339D01*
X1179188Y32613D01*
X1184876Y33615D01*
X1186170Y32710D01*
X1190274Y9444D01*
X1190875Y9022D01*
X1195691Y9871D01*
X1196114Y10474D01*
X1192477Y31099D01*
X1193383Y32393D01*
X1199032Y33390D01*
X1200326Y32483D01*
X1204400Y9379D01*
X1205002Y8957D01*
X1209818Y9806D01*
X1210240Y10408D01*
X1206579Y31173D01*
X1207469Y32445D01*
X1213156Y33447D01*
X1214427Y32557D01*
X1218511Y9398D01*
X1219113Y8976D01*
X1223929Y9825D01*
X1224351Y10428D01*
X1220702Y31123D01*
X1221592Y32395D01*
X1227279Y33397D01*
X1228551Y32507D01*
X1232692Y9018D01*
X1233295Y8596D01*
X1238111Y9445D01*
X1238532Y10046D01*
X1234814Y31131D01*
X1235704Y32403D01*
X1241391Y33405D01*
X1242663Y32515D01*
X1246747Y9351D01*
X1247350Y8929D01*
X1252165Y9779D01*
X1252587Y10381D01*
X1248911Y31228D01*
X1249801Y32500D01*
X1255488Y33502D01*
X1256760Y32612D01*
X1260843Y9457D01*
X1261446Y9035D01*
X1266261Y9884D01*
X1266683Y10487D01*
X1263015Y31289D01*
X1263907Y32560D01*
X1269595Y33563D01*
X1270866Y32671D01*
X1272926Y20983D01*
X1274910Y18999D01*
X1292040D01*
X1292514Y19473D01*
X1292972D01*
G01X1021881Y387060D02*
X1022549D01*
X1023081Y387592D01*
X1024380D01*
X1027040Y384932D01*
X1030789D01*
X1031950Y383771D01*
G01X1021881Y389028D02*
X1022604D01*
X1023020Y388612D01*
X1023071D01*
X1023074Y388615D01*
X1023078D01*
X1023081Y388612D01*
X1024803D01*
X1027463Y385952D01*
X1030731D01*
X1031950Y387171D01*
G01X1196772Y1578182D02*
X1197975Y1579385D01*
Y1581803D01*
X1196690Y1583088D01*
X1196672D01*
G01X1200172Y1578182D02*
X1198995Y1579359D01*
Y1581811D01*
X1200272Y1583088D01*
G01X1196772Y1590094D02*
X1197965Y1588901D01*
Y1586468D01*
X1196685Y1585188D01*
X1196672D01*
G01X1200172Y1590094D02*
X1198985Y1588907D01*
Y1586475D01*
X1200272Y1585188D01*
G01X1212232Y1578182D02*
X1211055Y1579359D01*
Y1581811D01*
X1212332Y1583088D01*
G01X1208832Y1578182D02*
X1210035Y1579385D01*
Y1581803D01*
X1208750Y1583088D01*
X1208732D01*
G01X1212232Y1590094D02*
X1211045Y1588907D01*
Y1586475D01*
X1212332Y1585188D01*
G01X1208832Y1590094D02*
X1210025Y1588901D01*
Y1586468D01*
X1208745Y1585188D01*
X1208732D01*
G01X1214132Y1614292D02*
X1215325Y1613099D01*
Y1610666D01*
X1214045Y1609386D01*
X1214032D01*
G01X1202072Y1614292D02*
X1203265Y1613099D01*
Y1610666D01*
X1201985Y1609386D01*
X1201972D01*
G01X1217532Y1614292D02*
X1216345Y1613105D01*
Y1610673D01*
X1217632Y1609386D01*
G01X1205472Y1614292D02*
X1204285Y1613105D01*
Y1610673D01*
X1205572Y1609386D01*
G01X1214132Y1602380D02*
X1215335Y1603583D01*
Y1606001D01*
X1214050Y1607286D01*
X1214032D01*
G01X1202072Y1602380D02*
X1203275Y1603583D01*
Y1606001D01*
X1201990Y1607286D01*
X1201972D01*
G01X1217532Y1602380D02*
X1216355Y1603557D01*
Y1606009D01*
X1217632Y1607286D01*
G01X1205472Y1602380D02*
X1204295Y1603557D01*
Y1606009D01*
X1205572Y1607286D01*
G01X1220892Y1578182D02*
X1222095Y1579385D01*
Y1581803D01*
X1220810Y1583088D01*
X1220792D01*
G01X1232952Y1578182D02*
X1234155Y1579385D01*
Y1581803D01*
X1232870Y1583088D01*
X1232852D01*
G01X1224292Y1578182D02*
X1223115Y1579359D01*
Y1581811D01*
X1224392Y1583088D01*
G01X1220892Y1590094D02*
X1222085Y1588901D01*
Y1586468D01*
X1220805Y1585188D01*
X1220792D01*
G01X1232952Y1590094D02*
X1234145Y1588901D01*
Y1586468D01*
X1232865Y1585188D01*
X1232852D01*
G01X1224292Y1590094D02*
X1223105Y1588907D01*
Y1586475D01*
X1224392Y1585188D01*
G01X1226192Y1614292D02*
X1227385Y1613099D01*
Y1610666D01*
X1226105Y1609386D01*
X1226092D01*
G01X1229592Y1614292D02*
X1228405Y1613105D01*
Y1610673D01*
X1229692Y1609386D01*
G01X1226192Y1602380D02*
X1227395Y1603583D01*
Y1606001D01*
X1226110Y1607286D01*
X1226092D01*
G01X1229592Y1602380D02*
X1228415Y1603557D01*
Y1606009D01*
X1229692Y1607286D01*
G01X1245012Y1578182D02*
X1246215Y1579385D01*
Y1581803D01*
X1244930Y1583088D01*
X1244912D01*
G01X1236352Y1578182D02*
X1235175Y1579359D01*
Y1581811D01*
X1236452Y1583088D01*
G01X1248412Y1578182D02*
X1247235Y1579359D01*
Y1581811D01*
X1248512Y1583088D01*
G01X1245012Y1590094D02*
X1246205Y1588901D01*
Y1586468D01*
X1244925Y1585188D01*
X1244912D01*
G01X1236352Y1590094D02*
X1235165Y1588907D01*
Y1586475D01*
X1236452Y1585188D01*
G01X1248412Y1590094D02*
X1247225Y1588907D01*
Y1586475D01*
X1248512Y1585188D01*
G01X1238252Y1614292D02*
X1239445Y1613099D01*
Y1610666D01*
X1238165Y1609386D01*
X1238152D01*
G01X1241652Y1614292D02*
X1240465Y1613105D01*
Y1610673D01*
X1241752Y1609386D01*
G01X1238252Y1602380D02*
X1239455Y1603583D01*
Y1606001D01*
X1238170Y1607286D01*
X1238152D01*
G01X1241652Y1602380D02*
X1240475Y1603557D01*
Y1606009D01*
X1241752Y1607286D01*
G01X1257072Y1578182D02*
X1258275Y1579385D01*
Y1581803D01*
X1256990Y1583088D01*
X1256972D01*
G01X1260472Y1578182D02*
X1259295Y1579359D01*
Y1581811D01*
X1260572Y1583088D01*
G01X1257072Y1590094D02*
X1258265Y1588901D01*
Y1586468D01*
X1256985Y1585188D01*
X1256972D01*
G01X1260472Y1590094D02*
X1259285Y1588907D01*
Y1586475D01*
X1260572Y1585188D01*
G01X1262372Y1614292D02*
X1263565Y1613099D01*
Y1610666D01*
X1262285Y1609386D01*
X1262272D01*
G01X1250312Y1614292D02*
X1251505Y1613099D01*
Y1610666D01*
X1250225Y1609386D01*
X1250212D01*
G01X1265772Y1614292D02*
X1264585Y1613105D01*
Y1610673D01*
X1265872Y1609386D01*
G01X1253712Y1614292D02*
X1252525Y1613105D01*
Y1610673D01*
X1253812Y1609386D01*
G01X1262372Y1602380D02*
X1263575Y1603583D01*
Y1606001D01*
X1262290Y1607286D01*
X1262272D01*
G01X1250312Y1602380D02*
X1251515Y1603583D01*
Y1606001D01*
X1250230Y1607286D01*
X1250212D01*
G01X1265772Y1602380D02*
X1264595Y1603557D01*
Y1606009D01*
X1265872Y1607286D01*
G01X1253712Y1602380D02*
X1252535Y1603557D01*
Y1606009D01*
X1253812Y1607286D01*
G01X1269132Y1578182D02*
X1270335Y1579385D01*
Y1581803D01*
X1269050Y1583088D01*
X1269032D01*
G01X1281192Y1578182D02*
X1282395Y1579385D01*
Y1581803D01*
X1281110Y1583088D01*
X1281092D01*
G01X1272532Y1578182D02*
X1271355Y1579359D01*
Y1581811D01*
X1272632Y1583088D01*
G01X1269132Y1590094D02*
X1270325Y1588901D01*
Y1586468D01*
X1269045Y1585188D01*
X1269032D01*
G01X1281192Y1590094D02*
X1282385Y1588901D01*
Y1586468D01*
X1281105Y1585188D01*
X1281092D01*
G01X1272532Y1590094D02*
X1271345Y1588907D01*
Y1586475D01*
X1272632Y1585188D01*
G01X1274432Y1614292D02*
X1275625Y1613099D01*
Y1610666D01*
X1274345Y1609386D01*
X1274332D01*
G01X1277832Y1614292D02*
X1276645Y1613105D01*
Y1610673D01*
X1277932Y1609386D01*
G01X1274432Y1602380D02*
X1275635Y1603583D01*
Y1606001D01*
X1274350Y1607286D01*
X1274332D01*
G01X1277832Y1602380D02*
X1276655Y1603557D01*
Y1606009D01*
X1277932Y1607286D01*
G01X1292972Y-22495D02*
X1290291Y-23211D01*
G01X1292972Y-20527D02*
X1290291Y-19811D01*
G01X1292972Y-2495D02*
X1290291Y-3211D01*
G01X1292972Y-527D02*
X1290291Y189D01*
G01X1297342Y287832D02*
X1296990D01*
X1295940Y286782D01*
G01Y286662D02*
Y285442D01*
X1297340Y284042D01*
Y280243D01*
X1297830Y279753D01*
Y278213D01*
X1297340Y277723D01*
Y276183D01*
X1297830Y275693D01*
Y274153D01*
X1297340Y273663D01*
Y272123D01*
X1297830Y271633D01*
Y270093D01*
X1297340Y269603D01*
Y268063D01*
X1297830Y267573D01*
Y266033D01*
X1297340Y265543D01*
Y264003D01*
X1297830Y263513D01*
Y261973D01*
X1297340Y261483D01*
Y259943D01*
X1298428Y258855D01*
X1299121D01*
X1300211Y257765D01*
Y257072D01*
X1301299Y255984D01*
X1301992D01*
X1303082Y254894D01*
Y254201D01*
X1304170Y253113D01*
X1304863D01*
X1305953Y252023D01*
Y251330D01*
X1307041Y250242D01*
X1307734D01*
X1308824Y249152D01*
Y248459D01*
X1311319Y245964D01*
X1311320D01*
G01X1293398Y287832D02*
X1293630D01*
X1294920Y286542D01*
Y285019D01*
X1296320Y283619D01*
Y259520D01*
X1310598Y245242D01*
G01X1297342Y290982D02*
X1296700D01*
X1295720Y291962D01*
Y293209D01*
X1295208Y294444D01*
X1293722Y295930D01*
X1293310Y296924D01*
Y298502D01*
X1294500Y299692D01*
G01X1293398Y290982D02*
X1293720D01*
X1294700Y291962D01*
Y293005D01*
X1294343Y293866D01*
X1292857Y295352D01*
X1292290Y296720D01*
Y298502D01*
X1291100Y299692D01*
G01X1293252Y1578182D02*
X1294455Y1579385D01*
Y1581803D01*
X1293170Y1583088D01*
X1293152D01*
G01X1284592Y1578182D02*
X1283415Y1579359D01*
Y1581811D01*
X1284692Y1583088D01*
G01X1296652Y1578182D02*
X1295475Y1579359D01*
Y1581811D01*
X1296752Y1583088D01*
G01X1293252Y1590094D02*
X1294445Y1588901D01*
Y1586468D01*
X1293165Y1585188D01*
X1293152D01*
G01X1284592Y1590094D02*
X1283405Y1588907D01*
Y1586475D01*
X1284692Y1585188D01*
G01X1296652Y1590094D02*
X1295465Y1588907D01*
Y1586475D01*
X1296752Y1585188D01*
G01X1286492Y1614292D02*
X1287685Y1613099D01*
Y1610666D01*
X1286405Y1609386D01*
X1286392D01*
G01X1289892Y1614292D02*
X1288705Y1613105D01*
Y1610673D01*
X1289992Y1609386D01*
G01X1286492Y1602380D02*
X1287695Y1603583D01*
Y1606001D01*
X1286410Y1607286D01*
X1286392D01*
G01X1289892Y1602380D02*
X1288715Y1603557D01*
Y1606009D01*
X1289992Y1607286D01*
G01X1308736Y284948D02*
X1309993Y283691D01*
Y265099D01*
G01X1312136Y284948D02*
X1311013Y283825D01*
Y265099D01*
G01X1307542Y298242D02*
X1307203D01*
X1305857Y296896D01*
Y293821D01*
X1307042Y292636D01*
G01X1303542Y298242D02*
Y298181D01*
X1304837Y296886D01*
Y293831D01*
X1303642Y292636D01*
G01X1307542Y301392D02*
X1307390D01*
X1306147Y302635D01*
Y305703D01*
X1307442Y306998D01*
G01X1303542Y301392D02*
X1303886D01*
X1305127Y302633D01*
Y305913D01*
X1304042Y306998D01*
G01X1312503Y1119337D02*
Y1121447D01*
G01X1305312Y1578182D02*
X1306515Y1579385D01*
Y1581803D01*
X1305230Y1583088D01*
X1305212D01*
G01X1308712Y1578182D02*
X1307535Y1579359D01*
Y1581811D01*
X1308812Y1583088D01*
G01X1305312Y1590094D02*
X1306505Y1588901D01*
Y1586468D01*
X1305225Y1585188D01*
X1305212D01*
G01X1308712Y1590094D02*
X1307525Y1588907D01*
Y1586475D01*
X1308812Y1585188D01*
G01X1310612Y1614292D02*
X1311805Y1613099D01*
Y1610666D01*
X1310525Y1609386D01*
X1310512D01*
G01X1298552Y1614292D02*
X1299745Y1613099D01*
Y1610666D01*
X1298465Y1609386D01*
X1298452D01*
G01X1314012Y1614292D02*
X1312825Y1613105D01*
Y1610673D01*
X1314112Y1609386D01*
G01X1301952Y1614292D02*
X1300765Y1613105D01*
Y1610673D01*
X1302052Y1609386D01*
G01X1310612Y1602380D02*
X1311815Y1603583D01*
Y1606001D01*
X1310530Y1607286D01*
X1310512D01*
G01X1298552Y1602380D02*
X1299755Y1603583D01*
Y1606001D01*
X1298470Y1607286D01*
X1298452D01*
G01X1314012Y1602380D02*
X1312835Y1603557D01*
Y1606009D01*
X1314112Y1607286D01*
G01X1301952Y1602380D02*
X1300775Y1603557D01*
Y1606009D01*
X1302052Y1607286D01*
G01X1324775Y216649D02*
X1322652D01*
G01X1324775Y220349D02*
X1322652D01*
G01X1330994Y261469D02*
Y277918D01*
X1330464Y279198D01*
X1321124Y288538D01*
Y297955D01*
X1319903Y299176D01*
G01X1332014Y261469D02*
Y264562D01*
X1332504Y265052D01*
Y266552D01*
X1332014Y267042D01*
Y268932D01*
X1332494Y269412D01*
Y270972D01*
X1332014Y271452D01*
Y273222D01*
X1332504Y273712D01*
Y275212D01*
X1332014Y275702D01*
Y278121D01*
X1331329Y279776D01*
X1322144Y288961D01*
Y298017D01*
X1323303Y299176D01*
G01X1325414Y293556D02*
X1326670Y292300D01*
Y288203D01*
X1334665Y280208D01*
X1335199Y278916D01*
Y264231D01*
G01X1328814Y293556D02*
X1328682D01*
X1327690Y292564D01*
Y288626D01*
X1329146Y287170D01*
X1329839D01*
X1330928Y286081D01*
Y285388D01*
X1332256Y284060D01*
X1332949D01*
X1334038Y282971D01*
Y282279D01*
X1335531Y280786D01*
X1336219Y279119D01*
Y276171D01*
X1336709Y275681D01*
Y274181D01*
X1336219Y273691D01*
Y272191D01*
X1336709Y271701D01*
Y270201D01*
X1336219Y269711D01*
Y268211D01*
X1336709Y267721D01*
Y266221D01*
X1336219Y265731D01*
Y264231D01*
G01X1330101Y540049D02*
Y539581D01*
X1331220Y538462D01*
Y536061D01*
X1333507Y533774D01*
X1341160D01*
X1344374Y534748D01*
X1369286Y551392D01*
Y551393D01*
X1448245Y604148D01*
X1455183Y609842D01*
X1462604Y617263D01*
Y617262D01*
X1466469Y621127D01*
X1470270Y629162D01*
Y632212D01*
X1471460Y633402D01*
G01X1326870Y853490D02*
Y851381D01*
X1326869Y851380D01*
G01X1330570Y847081D02*
Y844972D01*
X1330569Y844971D01*
G01X1325021Y850286D02*
Y848177D01*
X1325020Y848176D01*
G01X1328721Y850286D02*
Y848177D01*
X1328720Y848176D01*
G01X1326870Y859899D02*
Y857790D01*
X1326871Y857789D01*
G01X1328721Y863103D02*
Y860994D01*
X1328720Y860993D01*
G01X1330570Y859899D02*
Y857790D01*
X1330571Y857789D01*
G01X1326870Y872716D02*
Y870607D01*
X1326871Y870606D01*
G01X1330570Y872716D02*
Y870607D01*
X1330571Y870606D01*
G01X1328721Y875920D02*
Y873811D01*
X1328720Y873810D01*
G01X1330570Y885533D02*
Y883424D01*
X1330571Y883423D01*
G01X1329153Y1103316D02*
Y1105426D01*
G01X1325454Y1111834D02*
Y1109724D01*
G01X1327303Y1100111D02*
Y1102221D01*
G01X1321753Y1109724D02*
Y1111834D01*
G01X1318054Y1109724D02*
Y1111834D01*
G01Y1103316D02*
Y1105425D01*
X1318053Y1105426D01*
G01X1327303Y1106520D02*
Y1108629D01*
X1327304Y1108630D01*
G01X1329153Y1109724D02*
X1329154Y1109725D01*
Y1111834D01*
G01X1319903Y1106520D02*
Y1108629D01*
X1319904Y1108630D01*
G01X1321753Y1103316D02*
Y1105426D01*
G01X1329153Y1122541D02*
Y1124651D01*
G01X1323603Y1119337D02*
Y1121447D01*
G01X1319903Y1125746D02*
Y1127856D01*
G01X1316203Y1125746D02*
Y1127856D01*
G01X1318054Y1116133D02*
Y1118243D01*
G01X1321753Y1122541D02*
Y1124651D01*
G01X1323603Y1125746D02*
Y1127856D01*
G01X1319903Y1119337D02*
Y1121447D01*
G01X1316203Y1119337D02*
Y1121447D01*
G01X1323603Y1112929D02*
Y1115039D01*
G01X1325454Y1135359D02*
Y1137467D01*
X1325452Y1137469D01*
G01X1327303Y1132154D02*
Y1134264D01*
G01X1318054Y1128950D02*
Y1131059D01*
X1318053Y1131060D01*
G01X1317372Y1578182D02*
X1318575Y1579385D01*
Y1581803D01*
X1317290Y1583088D01*
X1317272D01*
G01X1320772Y1578182D02*
X1319595Y1579359D01*
Y1581811D01*
X1320872Y1583088D01*
G01X1329432Y1578182D02*
X1330635Y1579385D01*
Y1581803D01*
X1329350Y1583088D01*
X1329332D01*
G01X1317372Y1590094D02*
X1318565Y1588901D01*
Y1586468D01*
X1317285Y1585188D01*
X1317272D01*
G01X1320772Y1590094D02*
X1319585Y1588907D01*
Y1586475D01*
X1320872Y1585188D01*
G01X1329432Y1590094D02*
X1330625Y1588901D01*
Y1586468D01*
X1329345Y1585188D01*
X1329332D01*
G01X1322672Y1614292D02*
X1323865Y1613099D01*
Y1610666D01*
X1322585Y1609386D01*
X1322572D01*
G01X1326072Y1614292D02*
X1324885Y1613105D01*
Y1610673D01*
X1326172Y1609386D01*
G01X1322672Y1602380D02*
X1323875Y1603583D01*
Y1606001D01*
X1322590Y1607286D01*
X1322572D01*
G01X1326072Y1602380D02*
X1324895Y1603557D01*
Y1606009D01*
X1326172Y1607286D01*
G01X1339071Y-20527D02*
X1341752Y-19811D01*
G01X1339071Y-22495D02*
X1341752Y-23211D01*
G01X1339071Y-527D02*
X1341752Y189D01*
G01X1339071Y-2495D02*
X1341752Y-3211D01*
G01X1339071Y19473D02*
X1339507D01*
X1339981Y18999D01*
X1352575D01*
X1354463Y20885D01*
X1352645Y31154D01*
X1353551Y32448D01*
X1359201Y33444D01*
X1360502Y32533D01*
X1364592Y9339D01*
X1365195Y8917D01*
X1370010Y9766D01*
X1370432Y10369D01*
X1366688Y31605D01*
X1367594Y32900D01*
X1373243Y33896D01*
X1374536Y32990D01*
X1378689Y9443D01*
X1379290Y9022D01*
X1384106Y9871D01*
X1384529Y10474D01*
X1380784Y31710D01*
X1381690Y33004D01*
X1387339Y34001D01*
X1388633Y33094D01*
X1392815Y9379D01*
X1393417Y8957D01*
X1398233Y9806D01*
X1398655Y10408D01*
X1394892Y31749D01*
X1395782Y33021D01*
X1401469Y34023D01*
X1402741Y33133D01*
X1406926Y9398D01*
X1407528Y8976D01*
X1412344Y9825D01*
X1412766Y10428D01*
X1409003Y31769D01*
X1409893Y33041D01*
X1415580Y34043D01*
X1416852Y33153D01*
X1421107Y9018D01*
X1421710Y8596D01*
X1426526Y9445D01*
X1426947Y10046D01*
X1423098Y31874D01*
X1423988Y33146D01*
X1429675Y34148D01*
X1430947Y33258D01*
X1435162Y9351D01*
X1435765Y8929D01*
X1440580Y9779D01*
X1441002Y10381D01*
X1437269Y31552D01*
X1438159Y32824D01*
X1443846Y33826D01*
X1445118Y32936D01*
X1449258Y9457D01*
X1449861Y9035D01*
X1454676Y9884D01*
X1455098Y10487D01*
X1451327Y31877D01*
X1452217Y33149D01*
X1452634Y33223D01*
Y33222D01*
X1457906Y34152D01*
X1459177Y33260D01*
X1461341Y20983D01*
X1463325Y18999D01*
X1484399D01*
X1484873Y19473D01*
X1485331D01*
G01X1339071Y17505D02*
X1339529D01*
X1340003Y17979D01*
X1352998D01*
X1355561Y20539D01*
X1353724Y30915D01*
X1354145Y31516D01*
X1358962Y32366D01*
X1359570Y31939D01*
X1363660Y8745D01*
X1364956Y7839D01*
X1370604Y8834D01*
X1371510Y10130D01*
X1367766Y31366D01*
X1368188Y31968D01*
X1373004Y32817D01*
X1373604Y32396D01*
X1377757Y8850D01*
X1379051Y7944D01*
X1384699Y8939D01*
X1385608Y10234D01*
X1381862Y31471D01*
X1382284Y32072D01*
X1387100Y32922D01*
X1387701Y32501D01*
X1391883Y8786D01*
X1393177Y7878D01*
X1398826Y8874D01*
X1399734Y10169D01*
X1395970Y31510D01*
X1396376Y32089D01*
X1401230Y32945D01*
X1401809Y32539D01*
X1405994Y8805D01*
X1407288Y7897D01*
X1412938Y8893D01*
X1413844Y10189D01*
X1410081Y31530D01*
X1410487Y32109D01*
X1415341Y32965D01*
X1415920Y32559D01*
X1420175Y8424D01*
X1421471Y7518D01*
X1427120Y8513D01*
X1428025Y9807D01*
X1424176Y31635D01*
X1424582Y32214D01*
X1429436Y33070D01*
X1430015Y32664D01*
X1434230Y8757D01*
X1435526Y7851D01*
X1441174Y8847D01*
X1442081Y10142D01*
X1438347Y31313D01*
X1438753Y31892D01*
X1443607Y32748D01*
X1444186Y32342D01*
X1448327Y8863D01*
X1449622Y7957D01*
X1455270Y8952D01*
X1456176Y10248D01*
X1452405Y31638D01*
X1452811Y32217D01*
X1457666Y33073D01*
X1458245Y32667D01*
X1460392Y20489D01*
X1462902Y17979D01*
X1484421D01*
X1484895Y17505D01*
X1485331D01*
G01X1346137Y175949D02*
X1347207Y177799D01*
X1347210D01*
G01X1344005Y179649D02*
X1342937Y177799D01*
G01X1346137Y183349D02*
X1347207Y185199D01*
X1347210D01*
G01X1346137Y179649D02*
X1347207Y181499D01*
X1347210D01*
G01X1346137Y187049D02*
X1347207Y188899D01*
X1347210D01*
G01X1336527Y214799D02*
X1336957Y215542D01*
X1337304Y216142D01*
X1337597Y216649D01*
X1337594D01*
G01X1340799Y218499D02*
X1339727Y216649D01*
G01X1347210Y214799D02*
X1346147Y212949D01*
G01X1347210Y218499D02*
X1346147Y216649D01*
G01X1342937Y214799D02*
X1343366Y215542D01*
X1343712Y216142D01*
X1344005Y216649D01*
G01X1336761Y293404D02*
X1337915Y292250D01*
Y282853D01*
X1339329Y279439D01*
Y260109D01*
G01X1340161Y293404D02*
X1338935Y292178D01*
Y289530D01*
X1339415Y289050D01*
Y287490D01*
X1338935Y287010D01*
Y283056D01*
X1340349Y279642D01*
Y276429D01*
X1340829Y275949D01*
Y274389D01*
X1340349Y273909D01*
Y272349D01*
X1340829Y271869D01*
Y270309D01*
X1340349Y269829D01*
Y268269D01*
X1340829Y267789D01*
Y266229D01*
X1340349Y265749D01*
Y264189D01*
X1340829Y263709D01*
Y262149D01*
X1340349Y261669D01*
Y260109D01*
G01X1340799Y222199D02*
X1339727Y220349D01*
G01X1336527Y218499D02*
X1337597Y220349D01*
X1337594D01*
G01X1336527Y222199D02*
X1337597Y224049D01*
X1337594D01*
G01X1344005Y220349D02*
X1342937Y218499D01*
G01X1347210Y222199D02*
X1346147Y220349D01*
G01X1344764Y258862D02*
Y262592D01*
X1345244Y263072D01*
Y264632D01*
X1344764Y265112D01*
Y267171D01*
X1346904Y272340D01*
Y273409D01*
X1348185Y274690D01*
G01X1349306Y258299D02*
Y259859D01*
X1349786Y260339D01*
Y261899D01*
X1349306Y262379D01*
Y263939D01*
X1349786Y264419D01*
Y265979D01*
X1349306Y266459D01*
Y267545D01*
X1349734Y268578D01*
X1350580Y269424D01*
X1351258D01*
X1352362Y270528D01*
Y271206D01*
X1355561Y274405D01*
Y275266D01*
X1356885Y276590D01*
G01X1364985Y272060D02*
X1363684Y270759D01*
Y269333D01*
X1361733Y267382D01*
X1358477D01*
X1355451Y264356D01*
Y260899D01*
G01X1343744Y258862D02*
Y267374D01*
X1345884Y272543D01*
Y273391D01*
X1344585Y274690D01*
G01X1353285Y276590D02*
X1354541Y275334D01*
Y274828D01*
X1348869Y269156D01*
X1348286Y267748D01*
Y258299D01*
G01X1354431Y260899D02*
Y264779D01*
X1358054Y268402D01*
X1361310D01*
X1362664Y269756D01*
Y270781D01*
X1361385Y272060D01*
G01X1344684Y280259D02*
X1345874Y279069D01*
Y278079D01*
X1344585Y276790D01*
G01X1333143Y540049D02*
Y539485D01*
X1332240Y538582D01*
Y536484D01*
X1333930Y534794D01*
X1341008D01*
X1343933Y535681D01*
X1345309Y536600D01*
X1345445Y537280D01*
X1346726Y538137D01*
X1347406Y538001D01*
X1348939Y539025D01*
X1349075Y539705D01*
X1350356Y540562D01*
X1351036Y540426D01*
X1352685Y541527D01*
X1352820Y542207D01*
X1354101Y543064D01*
X1354781Y542928D01*
X1357560Y544785D01*
X1357695Y545464D01*
X1358977Y546321D01*
X1359656Y546186D01*
X1361877Y547669D01*
X1362012Y548349D01*
X1363293Y549206D01*
X1363973Y549070D01*
X1366623Y550840D01*
X1366758Y551520D01*
X1368039Y552376D01*
X1368719Y552241D01*
X1447636Y604969D01*
X1454497Y610599D01*
X1461584Y617686D01*
Y618379D01*
X1462673Y619468D01*
X1463366D01*
X1465622Y621724D01*
X1466788Y624189D01*
X1466555Y624842D01*
X1467213Y626235D01*
X1467867Y626468D01*
X1469250Y629392D01*
Y632212D01*
X1468060Y633402D01*
G01X1332421Y843877D02*
Y841467D01*
G01X1337970Y847081D02*
Y844972D01*
X1337969Y844971D01*
G01X1339821Y843877D02*
Y841467D01*
G01X1345370Y847081D02*
Y844972D01*
X1345369Y844971D01*
G01X1334270Y847081D02*
Y844972D01*
X1334269Y844971D01*
G01X1336121Y850286D02*
Y848177D01*
X1336120Y848176D01*
G01X1341670Y847081D02*
Y844972D01*
X1341669Y844971D01*
G01X1343521Y850286D02*
Y848177D01*
X1343520Y848176D01*
G01X1332421Y869511D02*
Y867402D01*
X1332420Y867401D01*
G01X1339821Y869511D02*
Y867402D01*
X1339820Y867401D01*
G01X1332421Y856694D02*
Y854585D01*
X1332420Y854584D01*
G01X1334270Y859899D02*
Y857790D01*
X1334271Y857789D01*
G01X1337970Y859899D02*
Y857790D01*
X1337971Y857789D01*
G01X1341670Y859899D02*
Y857790D01*
X1341671Y857789D01*
G01X1345370Y859899D02*
Y857790D01*
X1345371Y857789D01*
G01X1336121Y863103D02*
Y860994D01*
X1336120Y860993D01*
G01X1339821Y856694D02*
Y854585D01*
X1339820Y854584D01*
G01X1343521Y863103D02*
Y860994D01*
X1343520Y860993D01*
G01X1334270Y872716D02*
Y870607D01*
X1334271Y870606D01*
G01X1337970Y872716D02*
Y870607D01*
X1337971Y870606D01*
G01X1341670Y872716D02*
Y870607D01*
X1341671Y870606D01*
G01X1336121Y875920D02*
Y873811D01*
X1336120Y873810D01*
G01X1343521Y875920D02*
Y873811D01*
X1343520Y873810D01*
G01X1345370Y872716D02*
Y870607D01*
X1345371Y870606D01*
G01X1332421Y882329D02*
Y880220D01*
X1332420Y880219D01*
G01X1334270Y885533D02*
Y883424D01*
X1334271Y883423D01*
G01X1339821Y882329D02*
Y880220D01*
X1339820Y880219D01*
G01X1341670Y885533D02*
Y883424D01*
X1341671Y883423D01*
G01X1337970Y885533D02*
Y883424D01*
X1337971Y883423D01*
G01X1345370Y885533D02*
Y883424D01*
X1345371Y883423D01*
G01X1336121Y888737D02*
Y886628D01*
X1336120Y886627D01*
G01X1343521Y888737D02*
Y886628D01*
X1343520Y886627D01*
G01X1345803Y1106520D02*
Y1108630D01*
G01X1340254Y1103316D02*
X1340255Y1103317D01*
Y1105425D01*
X1340254Y1105426D01*
G01X1336554Y1109724D02*
X1336555Y1109725D01*
Y1111833D01*
X1336554Y1111834D01*
G01X1334703Y1106520D02*
X1334704Y1106521D01*
Y1108629D01*
X1334703Y1108630D01*
G01X1343954Y1109724D02*
X1343955Y1109725D01*
Y1111833D01*
X1343954Y1111834D01*
G01X1342103Y1106520D02*
X1342104Y1106521D01*
Y1108629D01*
X1342103Y1108630D01*
G01X1338403Y1106520D02*
X1338404Y1106521D01*
Y1108629D01*
X1338403Y1108630D01*
G01X1331003Y1100111D02*
Y1102221D01*
G01X1334703Y1119337D02*
Y1121447D01*
G01X1336554Y1122541D02*
Y1124651D01*
G01X1340254Y1122541D02*
Y1124650D01*
X1340253Y1124651D01*
G01X1343954Y1122541D02*
Y1124650D01*
X1343953Y1124651D01*
G01X1331003Y1125746D02*
Y1127856D01*
G01X1332854Y1122541D02*
Y1124651D01*
G01X1338403Y1125746D02*
Y1127855D01*
X1338404Y1127856D01*
G01X1342103Y1119337D02*
Y1121446D01*
X1342104Y1121447D01*
G01X1345803Y1125746D02*
Y1127855D01*
X1345804Y1127856D01*
G01X1342103Y1112929D02*
Y1115039D01*
G01X1345803Y1112929D02*
Y1115039D01*
G01X1334703Y1112929D02*
Y1115039D01*
G01Y1132154D02*
Y1134264D01*
G01X1338403Y1138563D02*
Y1140973D01*
G01X1342103Y1132154D02*
Y1134263D01*
X1342104Y1134264D01*
G01X1345803Y1138563D02*
Y1140973D01*
G01X1332854Y1135359D02*
Y1137469D01*
G01X1336554Y1135359D02*
Y1137469D01*
G01X1340254Y1135359D02*
Y1137469D01*
G01X1343954Y1135359D02*
Y1137469D01*
G01X1332832Y1578182D02*
X1331655Y1579359D01*
Y1581811D01*
X1332932Y1583088D01*
G01X1341492Y1578182D02*
X1342695Y1579385D01*
Y1581803D01*
X1341410Y1583088D01*
X1341392D01*
G01X1344892Y1578182D02*
X1343715Y1579359D01*
Y1581811D01*
X1344992Y1583088D01*
G01X1332832Y1590094D02*
X1331645Y1588907D01*
Y1586475D01*
X1332932Y1585188D01*
G01X1341492Y1590094D02*
X1342685Y1588901D01*
Y1586468D01*
X1341405Y1585188D01*
X1341392D01*
G01X1344892Y1590094D02*
X1343705Y1588907D01*
Y1586475D01*
X1344992Y1585188D01*
G01X1346792Y1614292D02*
X1347985Y1613099D01*
Y1610666D01*
X1346705Y1609386D01*
X1346692D01*
G01X1334732Y1614292D02*
X1335925Y1613099D01*
Y1610666D01*
X1334645Y1609386D01*
X1334632D01*
G01X1338132Y1614292D02*
X1336945Y1613105D01*
Y1610673D01*
X1338232Y1609386D01*
G01X1346792Y1602380D02*
X1347995Y1603583D01*
Y1606001D01*
X1346710Y1607286D01*
X1346692D01*
G01X1334732Y1602380D02*
X1335935Y1603583D01*
Y1606001D01*
X1334650Y1607286D01*
X1334632D01*
G01X1338132Y1602380D02*
X1336955Y1603557D01*
Y1606009D01*
X1338232Y1607286D01*
G01X1353620Y170399D02*
X1352557Y168548D01*
G01X1355762Y166698D02*
X1356459Y167912D01*
X1356825Y168549D01*
G01X1435013Y147636D02*
X1433823Y146446D01*
X1421872D01*
X1421795Y146369D01*
X1419774Y145532D01*
X1413015Y142732D01*
X1397206D01*
X1393482Y146456D01*
G01X1406970Y138742D02*
X1408160Y137552D01*
Y136515D01*
X1407301Y135656D01*
X1396832D01*
X1390280Y142208D01*
X1385590D01*
X1380491Y147307D01*
Y150804D01*
G01X1352557Y172248D02*
X1352554Y172258D01*
X1353620Y174099D01*
G01X1349351Y177798D02*
X1350421Y179648D01*
X1350414Y179649D01*
G01X1349351Y170398D02*
X1350421Y172248D01*
X1350414Y172249D01*
G01X1349351Y174098D02*
X1350418Y175942D01*
X1350414Y175949D01*
G01X1397014Y154942D02*
X1405839D01*
X1407029Y156132D01*
G01X1397344Y169236D02*
X1404410D01*
X1404953Y169779D01*
Y170509D01*
X1403778Y171684D01*
G01X1352557Y175948D02*
X1353627Y177798D01*
X1353620Y177799D01*
G01X1349351Y181498D02*
X1350421Y183348D01*
X1350414Y183349D01*
G01X1356825Y175949D02*
X1355761Y174098D01*
G01X1356825Y183349D02*
X1355761Y181498D01*
G01X1352557Y183348D02*
X1353519Y185012D01*
X1353627Y185198D01*
X1353620Y185199D01*
G01X1352551Y187048D02*
Y187050D01*
X1353620Y188899D01*
G01X1356825Y190749D02*
X1355761Y188898D01*
G01X1423110Y184263D02*
X1424270Y185423D01*
Y186732D01*
X1418672Y192330D01*
X1411232D01*
X1409800Y193762D01*
X1406500D01*
G01X1352561Y198148D02*
X1353620Y199995D01*
Y199999D01*
G01X1356825Y198149D02*
X1355771Y196298D01*
G01X1356825Y201849D02*
X1355765Y199999D01*
G01X1356825Y187049D02*
X1355761Y185198D01*
G01X1349351D02*
X1350421Y187048D01*
X1350414Y187049D01*
G01X1355766Y214798D02*
X1356192Y215542D01*
X1356825Y216649D01*
G01X1353620Y218499D02*
X1352561Y216648D01*
G01X1392427Y217321D02*
X1402086Y226980D01*
X1402085D01*
X1402794Y227689D01*
X1403474Y229331D01*
Y240018D01*
X1404385Y240929D01*
G01X1356825Y205549D02*
X1355765Y203699D01*
G01X1418630Y220018D02*
X1419820Y218828D01*
Y214522D01*
X1418870Y213572D01*
X1399110D01*
X1396719Y211181D01*
X1394387D01*
G01X1353620Y222199D02*
X1352561Y220348D01*
G01X1356825Y224049D02*
X1355766Y222198D01*
G01X1349351Y218498D02*
X1350421Y220348D01*
X1350414Y220349D01*
G01X1356825D02*
X1355766Y218498D01*
G01X1373021Y268570D02*
Y270012D01*
X1372501Y270532D01*
X1371636D01*
X1367819Y266715D01*
Y266037D01*
X1366715Y264933D01*
X1366037D01*
X1364934Y263830D01*
Y263152D01*
X1363830Y262048D01*
X1363152D01*
X1362049Y260945D01*
Y260267D01*
X1360945Y259163D01*
X1360267D01*
X1359164Y258060D01*
Y257149D01*
X1358308Y256293D01*
Y255615D01*
X1357204Y254511D01*
X1356526D01*
X1355423Y253408D01*
Y252730D01*
X1354319Y251626D01*
X1353641D01*
X1352538Y250523D01*
Y249845D01*
X1351434Y248741D01*
X1350756D01*
X1349653Y247638D01*
Y246749D01*
G01X1352326Y243394D02*
Y243807D01*
X1353415Y244896D01*
X1354094D01*
X1355156Y245958D01*
Y246637D01*
X1356216Y247697D01*
X1356895D01*
X1357957Y248759D01*
Y249438D01*
X1359017Y250498D01*
X1359696D01*
X1360758Y251560D01*
Y252239D01*
X1361818Y253299D01*
X1362497D01*
X1363559Y254361D01*
Y255040D01*
X1364619Y256100D01*
X1365298D01*
X1366360Y257162D01*
Y257841D01*
X1367420Y258901D01*
X1368099D01*
X1369161Y259963D01*
Y260642D01*
X1370611Y262092D01*
X1372344D01*
X1372816Y261620D01*
Y260136D01*
G01X1362070Y247471D02*
X1362388Y247789D01*
X1363685Y248655D01*
X1364350Y248523D01*
X1365648Y249391D01*
X1365781Y250056D01*
X1367078Y250922D01*
X1367743Y250790D01*
X1369041Y251658D01*
X1369174Y252324D01*
X1370471Y253190D01*
X1371143Y253057D01*
X1372441Y253924D01*
X1372575Y254597D01*
X1373959Y255522D01*
X1375484D01*
X1375963Y255043D01*
X1377525D01*
X1378004Y255522D01*
X1382980D01*
X1383500Y255002D01*
Y253703D01*
G01X1364580Y243256D02*
X1365534Y243803D01*
X1366196Y243624D01*
X1367151Y244171D01*
X1367330Y244834D01*
X1368284Y245381D01*
X1368946Y245202D01*
X1369901Y245749D01*
X1370080Y246412D01*
X1372256Y247662D01*
X1372900D01*
X1373300Y247262D01*
Y245662D01*
G01X1379624Y238551D02*
Y239976D01*
X1379074Y240526D01*
X1378298D01*
X1377813Y240041D01*
X1376713D01*
X1376228Y240526D01*
X1374971D01*
X1374486Y240041D01*
X1373386D01*
X1372901Y240526D01*
X1372431D01*
X1371279Y239374D01*
X1369461D01*
G01X1373021Y272170D02*
X1372403Y271552D01*
X1371213D01*
X1358144Y258483D01*
Y257572D01*
X1348633Y248061D01*
Y246749D01*
G01X1372816Y263736D02*
X1372192Y263112D01*
X1370188D01*
X1351306Y244230D01*
Y243384D01*
G01X1361348Y248193D02*
X1361737Y248582D01*
X1373649Y256542D01*
X1382739D01*
X1383500Y257303D01*
G01X1373300Y249262D02*
X1372720Y248682D01*
X1371983D01*
X1369572Y247297D01*
Y247298D01*
X1364072Y244141D01*
G01X1369461Y240394D02*
X1370856D01*
X1372008Y241546D01*
X1379019D01*
X1379624Y242151D01*
G01X1348185Y276790D02*
X1346894Y278081D01*
Y279069D01*
X1348084Y280259D01*
G01X1358624Y284644D02*
X1357484Y283504D01*
Y282570D01*
X1355595Y280681D01*
Y279980D01*
X1356885Y278690D01*
G01X1353285D02*
X1354575Y279980D01*
Y281104D01*
X1356464Y282993D01*
Y283404D01*
X1355224Y284644D01*
G01X1365124Y282744D02*
X1366244Y281624D01*
Y279002D01*
X1364554Y277312D01*
X1363774D01*
X1362674Y276212D01*
Y275449D01*
X1361385Y274160D01*
G01X1347221Y843877D02*
Y841467D01*
G01X1352770Y847081D02*
Y844972D01*
X1352769Y844971D01*
G01X1356470Y847081D02*
Y844972D01*
X1356469Y844971D01*
G01X1360170Y847081D02*
Y844972D01*
X1360169Y844971D01*
G01X1362021Y843877D02*
Y841467D01*
G01X1349070Y847081D02*
Y844972D01*
X1349069Y844971D01*
G01X1350921Y850286D02*
Y848177D01*
X1350920Y848176D01*
G01X1354621Y843877D02*
Y841467D01*
G01X1358321Y850286D02*
Y848177D01*
X1358320Y848176D01*
G01X1347221Y869511D02*
Y867402D01*
X1347220Y867401D01*
G01X1354621Y869511D02*
Y867402D01*
X1354620Y867401D01*
G01X1362021Y869511D02*
Y867402D01*
X1362020Y867401D01*
G01X1349070Y859899D02*
Y857790D01*
X1349071Y857789D01*
G01X1354621Y856694D02*
Y854585D01*
X1354620Y854584D01*
G01X1356470Y859899D02*
Y857790D01*
X1356471Y857789D01*
G01X1360170Y859899D02*
Y857790D01*
X1360171Y857789D01*
G01X1347221Y856694D02*
Y854585D01*
X1347220Y854584D01*
G01X1350921Y863103D02*
Y860994D01*
X1350920Y860993D01*
G01X1352770Y859899D02*
Y857790D01*
X1352771Y857789D01*
G01X1358321Y863103D02*
Y860994D01*
X1358320Y860993D01*
G01X1362021Y856694D02*
Y854585D01*
X1362020Y854584D01*
G01X1349070Y872716D02*
Y870607D01*
X1349071Y870606D01*
G01X1356470Y872716D02*
Y870607D01*
X1356471Y870606D01*
G01X1350921Y875920D02*
Y873811D01*
X1350920Y873810D01*
G01X1352770Y872716D02*
Y870607D01*
X1352771Y870606D01*
G01X1358321Y875920D02*
Y873811D01*
X1358320Y873810D01*
G01X1360170Y872716D02*
Y870607D01*
X1360171Y870606D01*
G01X1347221Y882329D02*
Y880220D01*
X1347220Y880219D01*
G01X1349070Y885533D02*
Y883424D01*
X1349071Y883423D01*
G01X1354621Y882329D02*
Y880220D01*
X1354620Y880219D01*
G01X1356470Y885533D02*
Y883424D01*
X1356471Y883423D01*
G01X1362021Y882329D02*
Y880220D01*
X1362020Y880219D01*
G01X1352770Y885533D02*
Y883424D01*
X1352771Y883423D01*
G01X1360170Y885533D02*
Y883424D01*
X1360171Y883423D01*
G01X1350921Y888737D02*
Y886628D01*
X1350920Y886627D01*
G01X1358321Y888737D02*
Y886628D01*
X1358320Y886627D01*
G01X1362454Y1109724D02*
Y1111833D01*
X1362453Y1111834D01*
G01X1362454Y1103316D02*
Y1105425D01*
X1362453Y1105426D01*
G01X1358754Y1103316D02*
Y1105425D01*
X1358753Y1105426D01*
G01X1351354Y1109724D02*
Y1111833D01*
X1351353Y1111834D01*
G01X1351354Y1103316D02*
Y1105425D01*
X1351353Y1105426D01*
G01X1358754Y1109724D02*
Y1111833D01*
X1358753Y1111834D01*
G01X1360603Y1106520D02*
Y1108629D01*
X1360604Y1108630D01*
G01X1355054Y1109724D02*
Y1111833D01*
X1355053Y1111834D01*
G01X1356903Y1100111D02*
Y1102220D01*
X1356904Y1102221D01*
G01X1353203Y1106520D02*
Y1108629D01*
X1353204Y1108630D01*
G01X1355054Y1105426D02*
Y1103316D01*
G01X1347654Y1122541D02*
Y1124650D01*
X1347653Y1124651D01*
G01X1351354Y1122541D02*
Y1124650D01*
X1351353Y1124651D01*
G01X1355054Y1122541D02*
Y1124650D01*
X1355053Y1124651D01*
G01X1358754Y1122541D02*
Y1124650D01*
X1358753Y1124651D01*
G01X1362454Y1122541D02*
Y1124650D01*
X1362453Y1124651D01*
G01X1349503Y1119337D02*
Y1121446D01*
X1349504Y1121447D01*
G01X1353203Y1125746D02*
Y1127855D01*
X1353204Y1127856D01*
G01X1356903Y1119337D02*
Y1121446D01*
X1356904Y1121447D01*
G01X1360603Y1125746D02*
Y1127855D01*
X1360604Y1127856D01*
G01X1356903Y1112929D02*
Y1115038D01*
X1356904Y1115039D01*
G01X1349503Y1132154D02*
Y1134263D01*
X1349504Y1134264D01*
G01X1353203Y1138563D02*
Y1140973D01*
G01X1356903Y1132154D02*
Y1134263D01*
X1356904Y1134264D01*
G01X1360603Y1138563D02*
Y1140973D01*
G01X1347654Y1135359D02*
Y1137469D01*
G01X1351354Y1135359D02*
Y1137469D01*
G01X1355054Y1135359D02*
Y1137469D01*
G01X1358754Y1135359D02*
Y1137469D01*
G01X1362454Y1135359D02*
Y1137469D01*
G01X1353552Y1578182D02*
X1354755Y1579385D01*
Y1581803D01*
X1353470Y1583088D01*
X1353452D01*
G01X1356952Y1578182D02*
X1355775Y1579359D01*
Y1581811D01*
X1357052Y1583088D01*
G01X1353552Y1590094D02*
X1354745Y1588901D01*
Y1586468D01*
X1353465Y1585188D01*
X1353452D01*
G01X1356952Y1590094D02*
X1355765Y1588907D01*
Y1586475D01*
X1357052Y1585188D01*
G01X1358852Y1614292D02*
X1360045Y1613099D01*
Y1610666D01*
X1358765Y1609386D01*
X1358752D01*
G01X1362252Y1614292D02*
X1361065Y1613105D01*
Y1610673D01*
X1362352Y1609386D01*
G01X1350192Y1614292D02*
X1349005Y1613105D01*
Y1610673D01*
X1350292Y1609386D01*
G01X1358852Y1602380D02*
X1360055Y1603583D01*
Y1606001D01*
X1358770Y1607286D01*
X1358752D01*
G01X1362252Y1602380D02*
X1361075Y1603557D01*
Y1606009D01*
X1362352Y1607286D01*
G01X1350192Y1602380D02*
X1349015Y1603557D01*
Y1606009D01*
X1350292Y1607286D01*
G01X1435013Y153882D02*
X1433823Y155072D01*
X1429427D01*
X1420791Y151495D01*
X1418557Y150569D01*
X1414492Y148886D01*
X1397128D01*
G01X1435060Y159212D02*
Y157329D01*
X1433823Y156092D01*
X1429224D01*
X1420010Y152276D01*
X1417776Y151350D01*
X1414289Y149906D01*
X1397128D01*
G01X1435220Y141942D02*
Y144029D01*
X1433823Y145426D01*
X1422185D01*
X1419774Y144427D01*
X1413218Y141712D01*
X1396782D01*
X1395660Y142834D01*
X1394967D01*
X1393863Y143938D01*
Y144631D01*
X1392760Y145734D01*
G01X1410370Y138742D02*
X1409180Y137552D01*
Y136092D01*
X1407724Y134636D01*
X1396409D01*
X1389857Y141188D01*
X1385167D01*
X1379471Y146884D01*
Y150804D01*
G01X1397014Y153922D02*
X1405839D01*
X1407029Y152732D01*
G01X1415684Y171696D02*
X1414510Y170522D01*
Y166662D01*
X1411844Y163996D01*
X1395447D01*
G01X1412284Y171696D02*
X1413490Y170490D01*
Y167085D01*
X1411421Y165016D01*
X1395447D01*
G01X1397344Y168216D02*
X1404833D01*
X1405973Y169356D01*
Y170479D01*
X1407178Y171684D01*
G01X1401640Y158194D02*
X1400204Y159630D01*
X1395184D01*
G01X1407290Y160650D02*
X1395184D01*
G01X1413950Y184263D02*
X1415140Y185453D01*
Y186956D01*
X1414447Y187649D01*
X1410671D01*
X1409850Y188470D01*
G01X1410572Y189192D02*
X1411095Y188669D01*
X1414870D01*
X1416160Y187379D01*
Y185453D01*
X1417350Y184263D01*
G01X1406500Y194782D02*
X1410223D01*
X1411655Y193350D01*
X1419095D01*
X1425290Y187155D01*
Y185483D01*
X1426510Y184263D01*
G01X1436060Y220018D02*
X1434870Y218828D01*
Y216309D01*
X1425889Y207328D01*
X1408347D01*
G01Y208348D02*
X1409847D01*
X1410337Y208838D01*
X1411837D01*
X1412327Y208348D01*
X1413827D01*
X1414317Y208838D01*
X1415817D01*
X1416307Y208348D01*
X1417807D01*
X1418297Y208838D01*
X1419797D01*
X1420287Y208348D01*
X1421663D01*
X1422153Y208838D01*
X1423653D01*
X1424143Y208348D01*
X1425466D01*
X1426312Y209194D01*
Y209886D01*
X1427409Y210983D01*
X1428101D01*
X1429197Y212079D01*
Y212771D01*
X1430294Y213868D01*
X1430986D01*
X1433850Y216732D01*
Y218828D01*
X1432660Y220018D01*
G01X1407420D02*
X1408610Y221208D01*
Y222822D01*
X1408590Y222842D01*
X1404505D01*
X1398580Y216917D01*
G01X1410820Y220018D02*
X1409630Y221208D01*
Y223245D01*
X1409013Y223862D01*
X1404081D01*
X1397858Y217639D01*
G01X1400985Y240929D02*
X1401454D01*
X1402454Y239929D01*
Y236862D01*
X1401969Y236377D01*
Y234817D01*
X1402454Y234332D01*
Y232772D01*
X1401969Y232287D01*
Y230727D01*
X1402454Y230242D01*
Y229534D01*
X1401929Y228267D01*
X1401662Y228000D01*
X1400977D01*
X1399872Y226896D01*
Y226210D01*
X1398769Y225107D01*
X1398084D01*
X1396979Y224003D01*
Y223317D01*
X1395876Y222214D01*
X1395191D01*
X1394086Y221110D01*
Y220424D01*
X1391705Y218043D01*
G01X1422030Y220018D02*
X1420840Y218828D01*
Y214099D01*
X1419293Y212552D01*
X1399533D01*
X1397142Y210161D01*
X1394387D01*
G01X1375400Y245662D02*
X1376620Y246882D01*
X1379450D01*
X1380638Y245694D01*
G01X1375400Y249262D02*
X1376760Y247902D01*
X1379446D01*
X1380638Y249094D01*
G01X1374916Y260136D02*
X1376262Y261421D01*
X1376272Y261431D01*
X1379327D01*
X1380522Y260236D01*
G01X1374916Y263736D02*
X1376262Y262451D01*
X1379337D01*
X1380522Y263636D01*
G01X1364985Y274160D02*
X1363694Y275450D01*
Y275789D01*
X1364197Y276292D01*
X1364977D01*
X1367264Y278579D01*
Y281484D01*
X1368524Y282744D01*
G01X1375121Y268570D02*
X1376411Y269860D01*
X1385083D01*
X1386273Y268670D01*
G01X1375121Y272170D02*
X1376411Y270880D01*
X1385083D01*
X1386273Y272070D01*
G01X1434588Y807894D02*
Y789219D01*
X1438165Y771233D01*
X1449149Y744715D01*
X1451234Y734232D01*
Y720240D01*
X1449145Y709735D01*
X1447119Y704846D01*
X1446168Y703895D01*
X1400731Y666605D01*
X1400041Y666673D01*
X1398834Y665683D01*
X1398766Y664993D01*
X1393006Y660266D01*
X1389127Y659088D01*
X1386284D01*
X1380367Y661885D01*
X1378437D01*
X1377422Y661301D01*
X1376842Y660297D01*
X1374668Y659708D01*
G01X1425307Y807894D02*
Y787900D01*
X1429066Y769000D01*
X1439965Y742688D01*
X1441724Y733845D01*
Y722947D01*
X1439034Y716452D01*
X1409611Y687029D01*
X1393892Y674125D01*
X1388779Y672575D01*
X1385664D01*
X1385147Y673092D01*
X1379411D01*
X1378013Y672281D01*
X1377725Y671786D01*
X1377724Y671783D01*
X1378306Y669608D01*
G01X1435608Y807894D02*
Y789321D01*
X1439146Y771533D01*
X1450131Y745013D01*
X1452254Y734333D01*
Y720139D01*
X1450126Y709437D01*
X1447984Y704268D01*
X1446854Y703138D01*
X1393497Y659348D01*
X1389279Y658068D01*
X1386055D01*
X1380137Y660865D01*
X1378710D01*
X1378168Y660553D01*
X1377726Y659788D01*
X1377727Y659787D01*
X1377724Y659783D01*
X1378306Y657608D01*
G01X1424287Y807894D02*
Y787721D01*
X1424306Y787702D01*
X1428085Y768702D01*
X1438984Y742390D01*
X1440704Y733744D01*
Y723150D01*
X1438169Y717030D01*
X1408925Y687786D01*
X1400250Y680665D01*
X1399560Y680733D01*
X1398353Y679742D01*
X1398285Y679053D01*
X1393401Y675043D01*
X1388627Y673595D01*
X1386087D01*
X1385570Y674112D01*
X1379136D01*
X1377266Y673028D01*
X1376842Y672297D01*
X1374668Y671708D01*
G01X1413987Y807894D02*
Y786555D01*
X1414006Y786536D01*
X1418106Y765926D01*
X1427421Y743438D01*
X1429530Y732836D01*
Y723984D01*
X1429114Y722979D01*
X1400309Y694175D01*
X1399013Y693309D01*
X1398333Y693444D01*
X1397035Y692576D01*
X1396900Y691896D01*
X1393174Y689406D01*
X1379621Y686709D01*
X1377543Y685509D01*
X1376843Y684297D01*
X1374668Y683708D01*
G01X1415007Y807894D02*
Y786734D01*
X1419087Y766224D01*
X1428402Y743736D01*
X1430550Y732937D01*
Y723780D01*
X1429979Y722401D01*
X1400960Y693382D01*
X1393572Y688445D01*
X1379985Y685741D01*
X1378290Y684762D01*
X1377726Y683786D01*
X1377724Y683783D01*
X1378306Y681608D01*
G01X1403687Y807894D02*
Y784499D01*
X1403706Y784480D01*
X1407782Y763979D01*
X1407788Y763965D01*
X1412204Y753305D01*
X1416957Y741829D01*
Y731883D01*
X1413298Y723049D01*
X1399249Y709000D01*
X1398556D01*
X1397452Y707896D01*
Y707203D01*
X1395982Y705734D01*
X1393144Y703838D01*
X1377602Y697402D01*
X1376869Y696304D01*
X1374668Y695708D01*
G01X1404707Y807894D02*
Y784678D01*
X1408764Y764277D01*
X1408893Y763965D01*
X1417977Y742032D01*
Y731680D01*
X1414163Y722471D01*
X1396633Y704941D01*
X1393628Y702933D01*
X1378279Y696578D01*
X1377732Y695757D01*
X1378306Y693608D01*
G01X1394407Y807894D02*
Y783129D01*
X1398660Y761752D01*
X1407397Y740657D01*
Y733666D01*
X1404992Y727861D01*
X1395789Y718658D01*
X1394308Y717668D01*
X1389109Y715362D01*
X1378389Y708936D01*
X1377727Y707787D01*
X1377724Y707783D01*
X1378306Y705608D01*
G01X1393387Y807894D02*
Y782950D01*
X1393406Y782931D01*
X1397678Y761454D01*
X1406377Y740454D01*
Y733869D01*
X1404127Y728439D01*
X1399948Y724261D01*
X1399255D01*
X1398151Y723157D01*
Y722464D01*
X1395138Y719451D01*
X1393814Y718565D01*
X1388638Y716269D01*
X1377637Y709675D01*
X1376874Y708350D01*
X1376831Y708294D01*
X1374668Y707708D01*
G01X1383087Y807894D02*
Y781416D01*
X1383888Y777386D01*
X1385332Y770114D01*
X1386554Y763965D01*
X1387579Y758811D01*
X1389857Y753305D01*
X1390714Y751232D01*
X1390449Y750592D01*
X1391045Y749150D01*
X1391686Y748884D01*
X1395013Y740843D01*
Y737736D01*
X1394529Y736568D01*
X1393251Y735337D01*
X1387390Y731341D01*
X1377515Y721465D01*
X1376842Y720296D01*
X1374668Y719708D01*
G01X1384107Y807894D02*
Y781517D01*
X1384756Y778254D01*
X1387595Y763965D01*
X1388560Y759108D01*
X1392467Y749666D01*
X1392468Y749665D01*
X1396033Y741046D01*
Y737533D01*
X1395390Y735981D01*
X1393897Y734542D01*
X1388044Y730552D01*
X1378332Y720839D01*
X1377726Y719787D01*
Y719786D01*
X1377724Y719783D01*
X1378306Y717608D01*
G01X1419370Y847081D02*
X1420710Y845741D01*
Y843168D01*
X1419228Y841686D01*
X1402156Y834614D01*
X1377937Y810395D01*
Y780449D01*
X1384387Y740176D01*
X1385221Y738490D01*
X1385222Y738489D01*
X1385220Y738488D01*
X1385221Y738487D01*
X1385919Y737270D01*
X1385338Y735098D01*
G01X1423070Y847081D02*
X1421730Y845741D01*
Y842745D01*
X1419806Y840821D01*
X1402734Y833749D01*
X1378957Y809972D01*
Y780531D01*
X1385370Y740490D01*
X1386134Y738945D01*
X1386138Y738941D01*
X1386798Y737789D01*
X1386800Y737786D01*
X1388976Y737198D01*
G01X1363870Y847081D02*
Y844972D01*
X1363869Y844971D01*
G01X1367570Y847081D02*
Y844972D01*
X1367569Y844971D01*
G01X1369421Y843877D02*
Y841467D01*
G01X1373121Y850286D02*
Y848177D01*
X1373120Y848176D01*
G01X1376821Y843877D02*
Y841467D01*
G01X1365721Y850286D02*
Y848177D01*
X1365720Y848176D01*
G01X1371270Y847081D02*
Y844972D01*
X1371269Y844971D01*
G01X1374970Y847081D02*
Y844972D01*
X1374969Y844971D01*
G01X1378670Y847081D02*
Y844972D01*
X1378669Y844971D01*
G01X1376821Y869511D02*
Y867402D01*
X1376820Y867401D01*
G01X1369421Y869511D02*
Y867402D01*
X1369420Y867401D01*
G01X1365721Y863103D02*
Y860994D01*
X1365720Y860993D01*
G01X1367570Y859899D02*
Y857790D01*
X1367571Y857789D01*
G01X1373121Y863103D02*
Y860994D01*
X1373120Y860993D01*
G01X1374970Y859899D02*
Y857790D01*
X1374971Y857789D01*
G01X1363870Y859899D02*
Y857790D01*
X1363871Y857789D01*
G01X1369421Y856694D02*
Y854585D01*
X1369420Y854584D01*
G01X1371270Y859899D02*
Y857790D01*
X1371271Y857789D01*
G01X1376821Y856694D02*
Y854585D01*
X1376820Y854584D01*
G01X1378670Y859899D02*
Y857790D01*
X1378671Y857789D01*
G01X1363870Y872716D02*
Y870607D01*
X1363871Y870606D01*
G01X1367570Y872716D02*
Y870607D01*
X1367571Y870606D01*
G01X1371270Y872716D02*
Y870607D01*
X1371271Y870606D01*
G01X1378670Y872716D02*
Y870607D01*
X1378671Y870606D01*
G01X1365721Y875920D02*
Y873811D01*
X1365720Y873810D01*
G01X1373121Y875920D02*
Y873811D01*
X1373120Y873810D01*
G01X1374970Y872716D02*
Y870607D01*
X1374971Y870606D01*
G01X1369421Y882329D02*
Y880220D01*
X1369420Y880219D01*
G01X1371270Y885533D02*
Y883424D01*
X1371271Y883423D01*
G01X1376821Y882329D02*
Y880220D01*
X1376820Y880219D01*
G01X1378670Y885533D02*
Y883424D01*
X1378671Y883423D01*
G01X1363870Y885533D02*
Y883424D01*
X1363871Y883423D01*
G01X1367570Y885533D02*
Y883424D01*
X1367571Y883423D01*
G01X1374970Y885533D02*
Y883424D01*
X1374971Y883423D01*
G01X1373121Y888737D02*
Y886628D01*
X1373120Y886627D01*
G01X1365721Y888737D02*
Y886628D01*
X1365720Y886627D01*
G01X1376821Y933598D02*
Y931489D01*
X1376820Y931488D01*
G01X1378670Y930393D02*
X1378671Y930392D01*
Y928283D01*
G01X1374970Y936801D02*
X1374971D01*
Y934691D01*
G01X1378670Y936801D02*
X1378671D01*
Y934691D01*
G01X1379103Y1080885D02*
Y1082994D01*
X1379104Y1082995D01*
G01X1379103Y1089404D02*
Y1087294D01*
G01X1369854Y1109724D02*
Y1111833D01*
X1369853Y1111834D01*
G01X1368003Y1106520D02*
Y1108629D01*
X1368004Y1108630D01*
G01X1377254Y1096907D02*
Y1099016D01*
X1377253Y1099017D01*
G01X1379103Y1106520D02*
Y1108629D01*
X1379104Y1108630D01*
G01X1373554Y1103316D02*
Y1105425D01*
X1373553Y1105426D01*
G01X1371703Y1106520D02*
Y1108629D01*
X1371704Y1108630D01*
G01X1379103Y1100111D02*
X1379104Y1100112D01*
Y1102221D01*
G01X1377254Y1109724D02*
Y1111833D01*
X1377253Y1111834D01*
G01X1375403Y1106520D02*
Y1108629D01*
X1375404Y1108630D01*
G01X1366154Y1122541D02*
Y1124650D01*
X1366153Y1124651D01*
G01X1371703Y1119337D02*
Y1121446D01*
X1371704Y1121447D01*
G01X1373554Y1122541D02*
Y1124650D01*
X1373553Y1124651D01*
G01X1377254Y1122541D02*
Y1124650D01*
X1377253Y1124651D01*
G01X1368003Y1125746D02*
Y1127855D01*
X1368004Y1127856D01*
G01X1369854Y1122541D02*
Y1124650D01*
X1369853Y1124651D01*
G01X1375403Y1125746D02*
Y1127855D01*
X1375404Y1127856D01*
G01X1379103Y1119337D02*
Y1121446D01*
X1379104Y1121447D01*
G01X1364303Y1119337D02*
Y1121446D01*
X1364304Y1121447D01*
G01X1375403Y1112929D02*
Y1115038D01*
X1375404Y1115039D01*
G01X1368003Y1112929D02*
Y1115038D01*
X1368004Y1115039D01*
G01X1379103Y1112929D02*
Y1115038D01*
X1379104Y1115039D01*
G01X1368003Y1138563D02*
Y1140973D01*
G01X1371703Y1132154D02*
Y1134263D01*
X1371704Y1134264D01*
G01X1375403Y1138563D02*
Y1140973D01*
G01X1379103Y1132154D02*
Y1134263D01*
X1379104Y1134264D01*
G01X1364303Y1132154D02*
Y1134263D01*
X1364304Y1134264D01*
G01X1366154Y1135359D02*
Y1137469D01*
G01X1369854Y1135359D02*
Y1137469D01*
G01X1373554Y1135359D02*
Y1137469D01*
G01X1377254Y1135359D02*
Y1137469D01*
G01X1365612Y1578182D02*
X1366815Y1579385D01*
Y1581803D01*
X1365530Y1583088D01*
X1365512D01*
G01X1377672Y1578182D02*
X1378875Y1579385D01*
Y1581803D01*
X1377590Y1583088D01*
X1377572D01*
G01X1369012Y1578182D02*
X1367835Y1579359D01*
Y1581811D01*
X1369112Y1583088D01*
G01X1365612Y1590094D02*
X1366805Y1588901D01*
Y1586468D01*
X1365525Y1585188D01*
X1365512D01*
G01X1377672Y1590094D02*
X1378865Y1588901D01*
Y1586468D01*
X1377585Y1585188D01*
X1377572D01*
G01X1369012Y1590094D02*
X1367825Y1588907D01*
Y1586475D01*
X1369112Y1585188D01*
G01X1370912Y1614292D02*
X1372105Y1613099D01*
Y1610666D01*
X1370825Y1609386D01*
X1370812D01*
G01X1374312Y1614292D02*
X1373125Y1613105D01*
Y1610673D01*
X1374412Y1609386D01*
G01X1370912Y1602380D02*
X1372115Y1603583D01*
Y1606001D01*
X1370830Y1607286D01*
X1370812D01*
G01X1374312Y1602380D02*
X1373135Y1603557D01*
Y1606009D01*
X1374412Y1607286D01*
G01X1381724Y238551D02*
X1383014Y239841D01*
X1385440D01*
X1386630Y238651D01*
G01X1381724Y242151D02*
X1383014Y240861D01*
X1385440D01*
X1386630Y242051D01*
G01X1385600Y253703D02*
X1386895Y254998D01*
X1387559D01*
X1388754Y253803D01*
G01X1385600Y257303D02*
X1386885Y256018D01*
X1387569D01*
X1388754Y257203D01*
G01X1430458Y807894D02*
Y788762D01*
X1434165Y770123D01*
X1445022Y743912D01*
X1447027Y733831D01*
Y720892D01*
X1444980Y710608D01*
X1443673Y707448D01*
X1406014Y676582D01*
Y676581D01*
X1405958Y676536D01*
X1400110Y672211D01*
X1400109Y672212D01*
X1400007Y671527D01*
X1398752Y670598D01*
X1398067Y670700D01*
X1397307Y670138D01*
X1396404Y669470D01*
X1390659Y667732D01*
X1390382Y667324D01*
X1390476Y666255D01*
X1391026Y665302D01*
X1391030Y665296D01*
X1393206Y664708D01*
G01X1429438Y807894D02*
Y788660D01*
X1433184Y769825D01*
X1444041Y743614D01*
X1446007Y733730D01*
Y720993D01*
X1443999Y710905D01*
X1442828Y708075D01*
X1405387Y677387D01*
X1405372Y677375D01*
X1405331Y677341D01*
X1395939Y670396D01*
X1390016Y668604D01*
X1389334Y667596D01*
X1389479Y665941D01*
X1390142Y664792D01*
X1390144Y664789D01*
X1390146Y664785D01*
X1390149Y664780D01*
X1389568Y662608D01*
G01X1420157Y807894D02*
Y787269D01*
X1424058Y767656D01*
X1435016Y741203D01*
X1436535Y733565D01*
Y724579D01*
X1434354Y719313D01*
X1404688Y689646D01*
X1399556Y686218D01*
X1399421Y685538D01*
X1398122Y684671D01*
X1397443Y684806D01*
X1396146Y683940D01*
X1392153Y682288D01*
X1390858Y680993D01*
X1390762Y680261D01*
X1391028Y679799D01*
X1391030Y679796D01*
X1393206Y679208D01*
G01X1419137Y807894D02*
Y787090D01*
X1419156Y787071D01*
X1423077Y767358D01*
X1434035Y740905D01*
X1435515Y733464D01*
Y724782D01*
X1433489Y719891D01*
X1404037Y690439D01*
X1395663Y684845D01*
X1391573Y683152D01*
X1389891Y681470D01*
X1389705Y680051D01*
X1390141Y679295D01*
Y679294D01*
X1390144Y679289D01*
X1390146Y679285D01*
X1390149Y679280D01*
X1389568Y677108D01*
G01X1409857Y807894D02*
Y785263D01*
X1413754Y765665D01*
X1423247Y742743D01*
Y730521D01*
X1418632Y719380D01*
X1400993Y701742D01*
X1396909Y698712D01*
X1395175Y697994D01*
X1394909Y697353D01*
X1393467Y696756D01*
X1392827Y697021D01*
X1391386Y696425D01*
X1390728Y695673D01*
X1390657Y694940D01*
X1391028Y694299D01*
X1391030Y694296D01*
X1393206Y693708D01*
G01X1408837Y807894D02*
Y785084D01*
X1408856Y785065D01*
X1412772Y765367D01*
X1413353Y763965D01*
X1422227Y742540D01*
Y730724D01*
X1417767Y719958D01*
X1400324Y702517D01*
X1396402Y699607D01*
X1390775Y697276D01*
X1389743Y696098D01*
X1389610Y694712D01*
X1390149Y693780D01*
X1389568Y691608D01*
G01X1399557Y807894D02*
Y783939D01*
X1403529Y763965D01*
X1403716Y763027D01*
X1407743Y753305D01*
X1412557Y741681D01*
Y732202D01*
X1409686Y725270D01*
X1397752Y713336D01*
X1395221Y712289D01*
X1394956Y711648D01*
X1393513Y711052D01*
X1392873Y711317D01*
X1391432Y710721D01*
X1390799Y710088D01*
X1390705Y709358D01*
X1391028Y708799D01*
X1391030Y708796D01*
X1393206Y708208D01*
G01X1398537Y807894D02*
Y783760D01*
X1398556Y783741D01*
X1402488Y763965D01*
X1402734Y762729D01*
X1411537Y741478D01*
Y732405D01*
X1408821Y725848D01*
X1397174Y714201D01*
X1390854Y711586D01*
X1389831Y710564D01*
X1389648Y709147D01*
X1390149Y708280D01*
X1389568Y706108D01*
G01X1388237Y807894D02*
Y782346D01*
X1392666Y760053D01*
X1400420Y741341D01*
Y736344D01*
X1399568Y734288D01*
X1394717Y729437D01*
X1391764Y727859D01*
X1390248Y725745D01*
X1389848Y724933D01*
X1389672Y723592D01*
X1390142Y722780D01*
X1389561Y720608D01*
G01X1389257Y807894D02*
Y782447D01*
X1393648Y760351D01*
X1401440Y741544D01*
Y736141D01*
X1400433Y733710D01*
X1395332Y728608D01*
X1392455Y727071D01*
X1391126Y725219D01*
X1390838Y724633D01*
X1390729Y723803D01*
X1391021Y723299D01*
X1391023Y723296D01*
X1393199Y722708D01*
G01X1380521Y850286D02*
Y848177D01*
X1380520Y848176D01*
G01X1386070Y847081D02*
Y844972D01*
X1386069Y844971D01*
G01X1389770Y847081D02*
Y844972D01*
X1389769Y844971D01*
G01X1393470Y847081D02*
Y844972D01*
X1393469Y844971D01*
G01X1382370Y847081D02*
Y844972D01*
X1382369Y844971D01*
G01X1384221Y843877D02*
Y841467D01*
G01X1387921Y850286D02*
Y848177D01*
X1387920Y848176D01*
G01X1391621Y843877D02*
Y841467D01*
G01X1395321Y850286D02*
Y848177D01*
X1395320Y848176D01*
G01X1384221Y869511D02*
Y867402D01*
X1384220Y867401D01*
G01X1391621Y869511D02*
X1391620Y867401D01*
G01X1380521Y863103D02*
Y860994D01*
X1380520Y860993D01*
G01X1382370Y859899D02*
Y857790D01*
X1382371Y857789D01*
G01X1387921Y863103D02*
Y860994D01*
X1387920Y860993D01*
G01X1389770Y859899D02*
Y857790D01*
X1389771Y857789D01*
G01X1395321Y863103D02*
Y860994D01*
X1395320Y860993D01*
G01X1384221Y856694D02*
Y854585D01*
X1384220Y854584D01*
G01X1386070Y859899D02*
Y857790D01*
X1386071Y857789D01*
G01X1391621Y856694D02*
Y854585D01*
X1391620Y854584D01*
G01X1393470Y859899D02*
Y857790D01*
X1393471Y857789D01*
G01X1380521Y875920D02*
Y873811D01*
X1380520Y873810D01*
G01X1382370Y872716D02*
Y870607D01*
X1382371Y870606D01*
G01X1384221Y882329D02*
Y880220D01*
X1384220Y880219D01*
G01X1386070Y885533D02*
Y883424D01*
X1386071Y883423D01*
G01X1382370Y885533D02*
Y883424D01*
X1382371Y883423D01*
G01X1395321Y875920D02*
X1395320Y873810D01*
G01X1393470Y872716D02*
X1393471Y870606D01*
G01X1387921Y875920D02*
X1387920Y873810D01*
G01X1389770Y872716D02*
X1389771Y870606D01*
G01X1393470Y885533D02*
X1393471Y885532D01*
Y883423D01*
G01X1391621Y882329D02*
X1391620Y882328D01*
Y880219D01*
G01X1389770Y885533D02*
Y883424D01*
X1389771Y883423D01*
G01X1386070Y898350D02*
X1386071Y898349D01*
Y896240D01*
G01X1389770Y898350D02*
X1389771Y898349D01*
Y896240D01*
G01X1393470Y898350D02*
Y896241D01*
X1393471Y896240D01*
G01X1387921Y901555D02*
Y899446D01*
X1387920Y899445D01*
G01X1391621Y895146D02*
Y893037D01*
X1391620Y893036D01*
G01X1395321Y901555D02*
Y899446D01*
X1395320Y899445D01*
G01X1380521Y888737D02*
Y886628D01*
X1380520Y886627D01*
G01X1387921Y888737D02*
Y886628D01*
X1387920Y886627D01*
G01X1395321Y888737D02*
X1395320Y888736D01*
Y886627D01*
G01X1384654Y1077681D02*
X1384653Y1077682D01*
Y1079791D01*
G01X1388354Y1084090D02*
Y1086199D01*
X1388353Y1086200D01*
G01X1386503Y1080885D02*
Y1082994D01*
X1386504Y1082995D01*
G01X1390203Y1087294D02*
Y1089403D01*
X1390204Y1089404D01*
G01X1382803Y1087294D02*
Y1089403D01*
X1382804Y1089404D01*
G01X1390203Y1080885D02*
Y1082994D01*
X1390204Y1082995D01*
G01X1382803Y1080885D02*
Y1082994D01*
X1382804Y1082995D01*
G01X1380954Y1084090D02*
Y1086199D01*
X1380953Y1086200D01*
G01X1386503Y1087294D02*
Y1089403D01*
X1386504Y1089404D01*
G01X1384654Y1090498D02*
Y1092606D01*
X1384653Y1092607D01*
Y1092608D01*
G01X1380954Y1096907D02*
Y1099016D01*
X1380953Y1099017D01*
G01X1393903Y1106520D02*
Y1108629D01*
X1393904Y1108630D01*
G01X1390203Y1100111D02*
X1390204Y1100112D01*
Y1102221D01*
G01X1392054Y1109724D02*
Y1111833D01*
X1392053Y1111834D01*
G01X1388354Y1109724D02*
Y1111833D01*
X1388353Y1111834D01*
G01X1384654Y1103316D02*
Y1105425D01*
X1384653Y1105426D01*
G01X1384654Y1096907D02*
Y1099016D01*
X1384653Y1099017D01*
G01X1392054Y1103316D02*
Y1105425D01*
X1392053Y1105426D01*
G01X1388354Y1103316D02*
Y1105425D01*
X1388353Y1105426D01*
G01X1384654Y1109724D02*
Y1111833D01*
X1384653Y1111834D01*
G01X1386503Y1106520D02*
Y1108629D01*
X1386504Y1108630D01*
G01X1380954Y1122541D02*
Y1124650D01*
X1380953Y1124651D01*
G01X1384654Y1122541D02*
Y1124650D01*
X1384653Y1124651D01*
G01X1382803Y1125746D02*
Y1127855D01*
X1382804Y1127856D01*
G01X1386503Y1119337D02*
Y1121446D01*
X1386504Y1121447D01*
G01X1390203Y1112929D02*
Y1115038D01*
X1390204Y1115039D01*
G01X1382803Y1138563D02*
Y1140973D01*
G01X1386503Y1132154D02*
Y1134263D01*
X1386504Y1134264D01*
G01X1380954Y1135359D02*
Y1137469D01*
G01X1384654Y1135359D02*
Y1137469D01*
G01X1381072Y1578182D02*
X1379895Y1579359D01*
Y1581811D01*
X1381172Y1583088D01*
G01X1381072Y1590094D02*
X1379885Y1588907D01*
Y1586475D01*
X1381172Y1585188D01*
G01X1382972Y1614292D02*
X1384165Y1613099D01*
Y1610666D01*
X1382885Y1609386D01*
X1382872D01*
G01X1386372Y1614292D02*
X1385185Y1613105D01*
Y1610673D01*
X1386472Y1609386D01*
G01X1382972Y1602380D02*
X1384175Y1603583D01*
Y1606001D01*
X1382890Y1607286D01*
X1382872D01*
G01X1386372Y1602380D02*
X1385195Y1603557D01*
Y1606009D01*
X1386472Y1607286D01*
G01X1397170Y847081D02*
Y844972D01*
X1397169Y844971D01*
G01X1399021Y841467D02*
Y843877D01*
G01X1402721Y850286D02*
Y848177D01*
X1402720Y848176D01*
G01X1406421Y850286D02*
Y848177D01*
X1406420Y848176D01*
G01X1400870Y847081D02*
Y844972D01*
X1400869Y844971D01*
G01X1404570Y847081D02*
Y844972D01*
X1404569Y844971D01*
G01X1410121Y850286D02*
Y848177D01*
X1410120Y848176D01*
G01X1406421Y869511D02*
X1406420Y867401D01*
G01X1399021Y869511D02*
X1399020Y867401D01*
G01X1397170Y859899D02*
Y857790D01*
X1397171Y857789D01*
G01X1402721Y863103D02*
Y860994D01*
X1402720Y860993D01*
G01X1404570Y859899D02*
Y857790D01*
X1404571Y857789D01*
G01X1410121Y863103D02*
Y860993D01*
G01X1399021Y856694D02*
Y854585D01*
X1399020Y854584D01*
G01X1400870Y859899D02*
Y857790D01*
X1400871Y857789D01*
G01X1406421Y856694D02*
Y854585D01*
X1406420Y854584D01*
G01X1408270Y859899D02*
Y857790D01*
X1408271Y857789D01*
G01X1408270Y872716D02*
X1408271Y870606D01*
G01X1402721Y875920D02*
X1402720Y873810D01*
G01X1400870Y872716D02*
X1400871Y870606D01*
G01X1410121Y875920D02*
Y873810D01*
G01X1404570Y872716D02*
X1404571Y870606D01*
G01X1397170Y872716D02*
X1397171Y870606D01*
G01X1408270Y885533D02*
X1408271Y885532D01*
Y883423D01*
G01X1406421Y882329D02*
Y880220D01*
X1406420Y880219D01*
G01X1400870Y885533D02*
Y883424D01*
X1400871Y883423D01*
G01X1399021Y882329D02*
Y880220D01*
X1399020Y880219D01*
G01X1404570Y885533D02*
X1404571Y885532D01*
Y883423D01*
G01X1397170Y885533D02*
Y883424D01*
X1397171Y883423D01*
G01X1397170Y898350D02*
X1397171Y898349D01*
Y896240D01*
G01X1402721Y901555D02*
X1402720Y901554D01*
Y899445D01*
G01X1404570Y898350D02*
X1404571Y898349D01*
Y896240D01*
G01X1410121Y901555D02*
X1410120Y901554D01*
Y899445D01*
G01X1399021Y895146D02*
Y893037D01*
X1399020Y893036D01*
G01X1400870Y898350D02*
Y896241D01*
X1400871Y896240D01*
G01X1406421Y895146D02*
X1406420Y895145D01*
Y893036D01*
G01X1408270Y898350D02*
Y896241D01*
X1408271Y896240D01*
G01X1410121Y888737D02*
X1410120Y888736D01*
Y886627D01*
G01X1402721Y888737D02*
Y886628D01*
X1402720Y886627D01*
G01X1405003Y1074477D02*
Y1076587D01*
G01X1406853Y1077681D02*
Y1079791D01*
G01X1401303Y1080885D02*
X1401304Y1082995D01*
G01X1405003Y1087294D02*
Y1089404D01*
G01X1399454Y1084090D02*
Y1086199D01*
X1399453Y1086200D01*
G01X1406853Y1090498D02*
Y1092608D01*
G01X1399454Y1090498D02*
Y1092607D01*
X1399453Y1092608D01*
G01X1397603Y1087294D02*
Y1089403D01*
X1397604Y1089404D01*
G01X1403154Y1086200D02*
Y1084090D01*
G01X1406853D02*
Y1086199D01*
X1406852Y1086200D01*
G01X1395754Y1084090D02*
Y1086199D01*
X1395753Y1086200D01*
G01X1403154Y1090498D02*
X1403153Y1090499D01*
Y1092608D01*
G01X1401303Y1093703D02*
Y1095812D01*
X1401304Y1095813D01*
G01X1395754Y1090498D02*
Y1092606D01*
X1395753Y1092607D01*
Y1092608D01*
G01X1395754Y1103316D02*
Y1105425D01*
X1395753Y1105426D01*
G01X1395754Y1109724D02*
Y1111833D01*
X1395753Y1111834D01*
G01X1411971Y847081D02*
Y844973D01*
X1411969Y844971D01*
G01X1413821Y850286D02*
Y848177D01*
X1413820Y848176D01*
G01X1421221Y869511D02*
X1421220Y867401D01*
G01X1413821Y869511D02*
X1413820Y867401D01*
G01X1424921Y863103D02*
Y860993D01*
G01X1421221Y856694D02*
Y854585D01*
X1421220Y854584D01*
G01X1417521Y863103D02*
Y860994D01*
X1417520Y860993D01*
G01X1426771Y857789D02*
Y859899D01*
G01X1423070D02*
Y857790D01*
X1423071Y857789D01*
G01X1419370Y859899D02*
Y857790D01*
X1419371Y857789D01*
G01X1411971D02*
Y859899D01*
G01X1413821Y856694D02*
Y854584D01*
G01X1424921Y875920D02*
Y873810D01*
G01X1423070Y872716D02*
X1423071Y870606D01*
G01X1417521Y875920D02*
X1417520Y873810D01*
G01X1415670Y872716D02*
X1415671Y870606D01*
G01X1426771Y872716D02*
Y870606D01*
G01X1419370Y872716D02*
X1419371Y870606D01*
G01X1411971Y872716D02*
Y870606D01*
G01X1423070Y885533D02*
X1423071Y885532D01*
Y883423D01*
G01X1421221Y882329D02*
Y880220D01*
X1421220Y880219D01*
G01X1415670Y885533D02*
Y883424D01*
X1415671Y883423D01*
G01X1413821Y882329D02*
Y880220D01*
X1413820Y880219D01*
G01X1426771Y885533D02*
Y883423D01*
G01X1419370Y885533D02*
Y883424D01*
X1419371Y883423D01*
G01X1411971Y885533D02*
Y883423D01*
G01X1413821Y895146D02*
Y893037D01*
X1413820Y893036D01*
G01X1411971Y898350D02*
Y896240D01*
G01X1421221Y901555D02*
X1421220Y901554D01*
Y899445D01*
G01X1419370Y898350D02*
X1419371Y898349D01*
Y896240D01*
G01X1424921Y901555D02*
X1424920Y901554D01*
Y899445D01*
G01X1426771Y898350D02*
X1426772Y898349D01*
Y896240D01*
G01X1417521Y901555D02*
X1417520Y901554D01*
Y899445D01*
G01X1421221Y895146D02*
X1421220Y895145D01*
Y893036D01*
G01X1423070Y898350D02*
X1423071Y898349D01*
Y896240D01*
G01X1424921Y888737D02*
X1424920Y888736D01*
Y886627D01*
G01X1417521Y888737D02*
Y886628D01*
X1417520Y886627D01*
G01X1439738Y807894D02*
Y790263D01*
X1439757Y790244D01*
X1443254Y772659D01*
X1450830Y754368D01*
X1459008Y746190D01*
X1468807Y731691D01*
X1469453Y730573D01*
X1469457Y730564D01*
X1468876Y728392D01*
G01X1440758Y807894D02*
Y790442D01*
X1444236Y772957D01*
X1451695Y754946D01*
X1459799Y746843D01*
X1469653Y732263D01*
X1469656D01*
X1470337Y731082D01*
X1470338Y731080D01*
X1472514Y730492D01*
G01X1443421Y869511D02*
X1443420Y867401D01*
G01X1436021Y869511D02*
X1436020Y867401D01*
G01X1428621Y869511D02*
X1428620Y867401D01*
G01X1439721Y863103D02*
Y860994D01*
X1439720Y860993D01*
G01X1437870Y859899D02*
Y857790D01*
X1437871Y857789D01*
G01X1432321Y863103D02*
Y860994D01*
X1432320Y860993D01*
G01X1430470Y859899D02*
Y857790D01*
X1430471Y857789D01*
G01X1443421Y856694D02*
Y854585D01*
X1443420Y854584D01*
G01X1441570Y859899D02*
Y857790D01*
X1441571Y857789D01*
G01X1436021Y856694D02*
Y854585D01*
X1436020Y854584D01*
G01X1434170Y859899D02*
Y857790D01*
X1434171Y857789D01*
G01X1428621Y856694D02*
Y854585D01*
X1428620Y854584D01*
G01X1439721Y875920D02*
X1439720Y873810D01*
G01X1437870Y872716D02*
X1437871Y870606D01*
G01X1432321Y875920D02*
X1432320Y873810D01*
G01X1430470Y872716D02*
X1430471Y870606D01*
G01X1441570Y872716D02*
X1441571Y870606D01*
G01X1434170Y872716D02*
X1434171Y870606D01*
G01X1443421Y882329D02*
Y880220D01*
X1443420Y880219D01*
G01X1437870Y885533D02*
Y883424D01*
X1437871Y883423D01*
G01X1436021Y882329D02*
Y880220D01*
X1436020Y880219D01*
G01X1430470Y885533D02*
X1430471Y885532D01*
Y883423D01*
G01X1428621Y882329D02*
Y880219D01*
G01X1441570Y885533D02*
Y883424D01*
X1441571Y883423D01*
G01X1434170Y885533D02*
Y883424D01*
X1434171Y883423D01*
G01X1430470Y898350D02*
X1430471Y898349D01*
Y896240D01*
G01X1436021Y895146D02*
X1436020Y895145D01*
Y893036D01*
G01X1437870Y898350D02*
X1437871Y898349D01*
Y896240D01*
G01X1441570Y898350D02*
X1441571Y898349D01*
Y896240D01*
G01X1428621Y895146D02*
Y893036D01*
G01X1432321Y901555D02*
X1432320Y901554D01*
Y899445D01*
G01X1434170Y898350D02*
X1434171Y898349D01*
Y896240D01*
G01X1439721Y901555D02*
X1439720Y901554D01*
Y899445D01*
G01X1443421Y895146D02*
X1443420Y895145D01*
Y893036D01*
G01X1439721Y888737D02*
X1439720Y888736D01*
Y886627D01*
G01X1432321Y888737D02*
X1432320Y888736D01*
Y886627D01*
G01X1497407Y807894D02*
Y797834D01*
X1498526Y792209D01*
X1500929Y786414D01*
X1513601Y773741D01*
X1531231Y761961D01*
X1538257Y754934D01*
Y737646D01*
X1521936Y698244D01*
X1486217Y662524D01*
X1475931Y654083D01*
X1472786Y652957D01*
X1468685D01*
X1462547Y657994D01*
X1461368Y658090D01*
X1460546Y657614D01*
X1460235Y657071D01*
X1460232Y657067D01*
X1460814Y654892D01*
G01X1496387Y807894D02*
Y797733D01*
X1497545Y791911D01*
X1500059Y785841D01*
X1512950Y772948D01*
X1530580Y761168D01*
X1537237Y754511D01*
Y737849D01*
X1521071Y698822D01*
X1485531Y663281D01*
X1483047Y661243D01*
X1482358Y661311D01*
X1481151Y660320D01*
X1481083Y659631D01*
X1480138Y658855D01*
X1475421Y654984D01*
X1472608Y653977D01*
X1469050D01*
X1466499Y656071D01*
X1466431Y656760D01*
X1465224Y657751D01*
X1464535Y657683D01*
X1462948Y658985D01*
X1461133Y659133D01*
X1459797Y658359D01*
X1459350Y657580D01*
X1457176Y656992D01*
G01X1487107Y807894D02*
Y796727D01*
X1488434Y790055D01*
X1488589Y789275D01*
X1492186Y780591D01*
X1515451Y757326D01*
X1523741Y753892D01*
X1527867Y749766D01*
Y744404D01*
X1526078Y735409D01*
X1513069Y704004D01*
X1483581Y674515D01*
X1476781Y668934D01*
X1475707Y668489D01*
X1469758Y667305D01*
X1468244D01*
X1462066Y669955D01*
X1461121D01*
X1460556Y669628D01*
X1460234Y669069D01*
Y669070D01*
X1460232Y669067D01*
X1460814Y666892D01*
G01X1486087Y807894D02*
Y796626D01*
X1487394Y790055D01*
X1487608Y788977D01*
X1491321Y780013D01*
X1514873Y756461D01*
X1523163Y753027D01*
X1526847Y749343D01*
Y744505D01*
X1525097Y735707D01*
X1512204Y704582D01*
X1482895Y675272D01*
X1481690Y674283D01*
X1481000Y674351D01*
X1479793Y673360D01*
X1479725Y672671D01*
X1476250Y669819D01*
X1475409Y669470D01*
X1469657Y668325D01*
X1468454D01*
X1466111Y669330D01*
X1465854Y669974D01*
X1464420Y670589D01*
X1463776Y670332D01*
X1462276Y670975D01*
X1460846D01*
X1459809Y670374D01*
X1459350Y669580D01*
X1457176Y668992D01*
G01X1476807Y807894D02*
Y795553D01*
X1478758Y785745D01*
X1483190Y775046D01*
X1513657Y744579D01*
Y734961D01*
X1510649Y725043D01*
X1504395Y709946D01*
X1480739Y686288D01*
X1476236Y683282D01*
X1471523Y681852D01*
X1461031D01*
X1460621Y681742D01*
X1460235Y681071D01*
X1460232Y681067D01*
X1460814Y678892D01*
G01X1475787Y807894D02*
Y795452D01*
X1477777Y785447D01*
X1482325Y774468D01*
X1512637Y744156D01*
Y735113D01*
X1509687Y725387D01*
X1503530Y710524D01*
X1482988Y689981D01*
X1482295D01*
X1481191Y688877D01*
Y688184D01*
X1480088Y687081D01*
X1475795Y684215D01*
X1471371Y682872D01*
X1460896D01*
X1459948Y682618D01*
X1459351Y681580D01*
X1457176Y680992D01*
G01X1466507Y807894D02*
Y793780D01*
X1467248Y790055D01*
X1468925Y781627D01*
X1473774Y769920D01*
X1494970Y748724D01*
X1500697Y734898D01*
Y728026D01*
X1495675Y715901D01*
X1480207Y700432D01*
X1475803Y697489D01*
X1462271Y694794D01*
X1460711Y693785D01*
X1460232Y693067D01*
X1460814Y690892D01*
G01X1455187Y807894D02*
Y792348D01*
X1455643Y790055D01*
X1458314Y776627D01*
X1463426Y764284D01*
X1485225Y742485D01*
X1488167Y735385D01*
Y727408D01*
X1487093Y724818D01*
X1484667Y721187D01*
X1482350Y718869D01*
X1481657D01*
X1480553Y717765D01*
Y717070D01*
X1479120Y715637D01*
X1475699Y713352D01*
X1461758Y708226D01*
X1459968Y706715D01*
X1459326Y705602D01*
X1458911Y705462D01*
X1457176Y704992D01*
G01X1465487Y807894D02*
Y793679D01*
X1467944Y781329D01*
X1472909Y769342D01*
X1494105Y748146D01*
X1499677Y734695D01*
Y728229D01*
X1494810Y716479D01*
X1482195Y703864D01*
X1481502D01*
X1480398Y702760D01*
Y702067D01*
X1479556Y701225D01*
X1475405Y698450D01*
X1461880Y695757D01*
X1459979Y694527D01*
X1459384Y693634D01*
X1459381Y693635D01*
X1459350Y693580D01*
X1457176Y692992D01*
G01X1456207Y807894D02*
Y792449D01*
X1456683Y790055D01*
X1459295Y776925D01*
X1464291Y764862D01*
X1486090Y743063D01*
X1489187Y735588D01*
Y727205D01*
X1487998Y724334D01*
X1485460Y720536D01*
X1479771Y714844D01*
X1476165Y712436D01*
X1462279Y707330D01*
X1460763Y706051D01*
X1460221Y705110D01*
X1460814Y702892D01*
G01X1444888Y807894D02*
Y790875D01*
X1448227Y774088D01*
X1454694Y758476D01*
X1469122Y744048D01*
Y743355D01*
X1470227Y742250D01*
X1470920D01*
X1476177Y736993D01*
X1477777Y733134D01*
Y729970D01*
X1477641Y729642D01*
X1475092Y727093D01*
X1468556Y724386D01*
X1459961Y718645D01*
X1459350Y717580D01*
X1457176Y716992D01*
G01X1445908Y807894D02*
Y790976D01*
X1449208Y774386D01*
X1455559Y759054D01*
X1477042Y737571D01*
X1478797Y733338D01*
Y729767D01*
X1478506Y729064D01*
X1475670Y726228D01*
X1469039Y723482D01*
X1460727Y717930D01*
X1460235Y717072D01*
X1460232Y717067D01*
X1460814Y714892D01*
G01X1450038Y807894D02*
Y791334D01*
X1450292Y790055D01*
X1453169Y775594D01*
X1459053Y761387D01*
X1480597Y739843D01*
X1482987Y734075D01*
Y728845D01*
X1482174Y726882D01*
X1478000Y722708D01*
X1473393Y720799D01*
X1472267Y719673D01*
Y718240D01*
X1472657Y717564D01*
X1472076Y715392D01*
G01X1451058Y807894D02*
Y791435D01*
X1451333Y790055D01*
X1454150Y775892D01*
X1459918Y761965D01*
X1481462Y740421D01*
X1484007Y734278D01*
Y728642D01*
X1483039Y726304D01*
X1481642Y724907D01*
Y724214D01*
X1480538Y723110D01*
X1479845D01*
X1478578Y721843D01*
X1473971Y719934D01*
X1473287Y719250D01*
Y718514D01*
X1473538Y718080D01*
X1475714Y717492D01*
G01X1460337Y807894D02*
Y793186D01*
X1460960Y790055D01*
X1463145Y779068D01*
X1468259Y766721D01*
X1489653Y745327D01*
X1493377Y736338D01*
Y726495D01*
X1490451Y719432D01*
X1482980Y711960D01*
X1478261Y708807D01*
X1472449Y706616D01*
X1471811Y705824D01*
X1471662Y704794D01*
X1472652Y703072D01*
X1472654Y703069D01*
X1472655Y703066D01*
X1472657Y703064D01*
X1472076Y700892D01*
G01X1450821Y869511D02*
Y867402D01*
X1450820Y867401D01*
G01X1458221Y869511D02*
Y867402D01*
X1458220Y867401D01*
G01X1460070Y859899D02*
Y857790D01*
X1460071Y857789D01*
G01X1454521Y863103D02*
Y860994D01*
X1454520Y860993D01*
G01X1452670Y859899D02*
Y857790D01*
X1452671Y857789D01*
G01X1447121Y863103D02*
Y860994D01*
X1447120Y860993D01*
G01X1445270Y859899D02*
Y857790D01*
X1445271Y857789D01*
G01X1458221Y856694D02*
Y854585D01*
X1458220Y854584D01*
G01X1456370Y859899D02*
Y857790D01*
X1456371Y857789D01*
G01X1450821Y856694D02*
Y854585D01*
X1450820Y854584D01*
G01X1448970Y859899D02*
Y857790D01*
X1448971Y857789D01*
G01X1445270Y872716D02*
X1445271Y870606D01*
G01X1445270Y885533D02*
Y883424D01*
X1445271Y883423D01*
G01X1456370Y872716D02*
Y870607D01*
X1456371Y870606D01*
G01X1452670Y872716D02*
Y870607D01*
X1452671Y870606D01*
G01X1454521Y875920D02*
Y873811D01*
X1454520Y873810D01*
G01X1460070Y872716D02*
Y870607D01*
X1460071Y870606D01*
G01X1450821Y882329D02*
Y880220D01*
X1450820Y880219D01*
G01X1452670Y885533D02*
Y883424D01*
X1452671Y883423D01*
G01X1458221Y882329D02*
Y880220D01*
X1458220Y880219D01*
G01X1460070Y885533D02*
Y883424D01*
X1460071Y883423D01*
G01X1448970Y885533D02*
Y883424D01*
X1448971Y883423D01*
G01X1456370Y885533D02*
Y883424D01*
X1456371Y883423D01*
G01X1447121Y888737D02*
Y886628D01*
X1447120Y886627D01*
G01X1454521Y888737D02*
Y886628D01*
X1454520Y886627D01*
G01X1456370Y930393D02*
X1456371Y930392D01*
Y928283D01*
G01X1454521Y933598D02*
X1454522Y933597D01*
Y931488D01*
G01X1454521Y927189D02*
X1454520Y927188D01*
Y925079D01*
G01X1458221Y927189D02*
X1458220Y927188D01*
Y925079D01*
G01X1454521Y940006D02*
X1454520Y940005D01*
Y937896D01*
G01X1456370Y943210D02*
X1456371Y943209D01*
Y941100D01*
G01X1460503Y1119337D02*
X1460504Y1121447D01*
G01X1456803Y1125746D02*
Y1127855D01*
X1456804Y1127856D01*
G01X1453103Y1119337D02*
X1453104Y1121447D01*
G01X1449403Y1125746D02*
Y1127855D01*
X1449404Y1127856D01*
G01X1445703Y1119337D02*
X1445704Y1121447D01*
G01X1458654Y1122541D02*
Y1124650D01*
X1458653Y1124651D01*
G01X1454954Y1122541D02*
Y1124650D01*
X1454953Y1124651D01*
G01X1451254Y1122541D02*
Y1124650D01*
X1451253Y1124651D01*
G01X1447554Y1122541D02*
X1447553Y1124651D01*
G01X1460503Y1132154D02*
Y1134263D01*
X1460504Y1134264D01*
G01X1458654Y1135359D02*
Y1137469D01*
G01X1453103Y1132154D02*
Y1134263D01*
X1453104Y1134264D01*
G01X1451254Y1135359D02*
Y1137469D01*
G01X1456803Y1138563D02*
Y1140973D01*
G01X1454954Y1135359D02*
Y1137469D01*
G01X1449403Y1138563D02*
Y1140973D01*
G01X1491237Y807894D02*
Y797193D01*
X1492572Y790474D01*
X1492746Y790055D01*
X1495712Y782893D01*
X1510480Y768124D01*
X1528004Y756414D01*
X1531987Y752431D01*
Y738725D01*
X1516665Y701733D01*
X1486512Y671580D01*
X1478742Y665209D01*
X1476940Y664533D01*
X1472576Y663426D01*
X1471828Y662437D01*
X1471879Y660852D01*
X1472653Y659553D01*
Y659551D01*
X1472076Y657392D01*
G01X1480937Y807894D02*
Y795947D01*
X1482109Y790055D01*
X1482596Y787609D01*
X1486939Y777124D01*
X1519507Y744556D01*
Y735646D01*
X1507875Y707565D01*
X1483457Y683148D01*
X1477819Y679379D01*
X1473160Y678043D01*
X1472123Y677006D01*
X1471859Y676262D01*
X1471961Y675273D01*
X1472657Y674064D01*
X1472076Y671892D01*
G01X1475714Y659492D02*
X1473525Y660084D01*
X1472891Y661148D01*
X1472860Y662109D01*
X1473174Y662525D01*
X1477245Y663558D01*
X1479258Y664313D01*
X1480532Y665357D01*
X1481220Y665288D01*
X1482428Y666278D01*
X1482496Y666968D01*
X1487198Y670823D01*
X1517530Y701155D01*
X1533007Y738522D01*
Y752854D01*
X1528655Y757207D01*
X1511131Y768917D01*
X1496577Y783472D01*
Y783471D01*
X1493851Y790055D01*
X1493554Y790772D01*
X1492257Y797295D01*
Y807894D01*
G01X1470637D02*
Y794536D01*
X1470656Y794517D01*
X1472791Y783788D01*
X1477782Y771740D01*
X1498463Y751059D01*
X1504847Y735648D01*
Y727244D01*
X1499163Y713522D01*
X1482933Y697292D01*
X1477262Y693507D01*
X1473063Y692692D01*
X1471890Y691617D01*
Y690087D01*
X1472198Y689362D01*
X1472657Y688564D01*
X1472076Y686392D01*
G01X1481957Y807894D02*
Y796050D01*
X1483150Y790055D01*
X1483577Y787907D01*
X1487804Y777702D01*
X1520527Y744979D01*
Y735443D01*
X1508740Y706987D01*
X1484108Y682355D01*
X1482556Y681318D01*
X1482421Y680638D01*
X1481123Y679770D01*
X1480443Y679905D01*
X1478253Y678442D01*
X1473695Y677135D01*
X1473008Y676447D01*
X1472898Y676138D01*
X1472954Y675594D01*
X1473537Y674580D01*
X1475714Y673992D01*
G01X1471657Y807894D02*
Y794716D01*
X1473772Y784086D01*
X1478647Y772318D01*
X1499328Y751637D01*
X1505867Y735851D01*
Y727041D01*
X1500028Y712944D01*
X1483584Y696499D01*
X1481630Y695195D01*
X1481495Y694516D01*
X1480196Y693649D01*
X1479517Y693784D01*
X1477658Y692544D01*
X1473540Y691745D01*
X1472910Y691168D01*
Y690300D01*
X1473139Y689773D01*
X1473537Y689080D01*
X1475714Y688492D01*
G01X1461357Y807894D02*
Y793287D01*
X1462000Y790055D01*
X1464126Y779366D01*
X1469124Y767299D01*
X1490518Y745905D01*
X1494397Y736541D01*
Y726292D01*
X1491316Y718854D01*
X1491315Y718852D01*
X1483631Y711167D01*
X1478731Y707893D01*
X1473070Y705759D01*
X1472781Y705402D01*
X1472722Y704997D01*
X1473529Y703594D01*
X1473536Y703583D01*
X1473538Y703580D01*
X1475714Y702992D01*
G01X1465621Y869511D02*
Y867402D01*
X1465620Y867401D01*
G01X1473021Y869511D02*
Y867402D01*
X1473020Y867401D01*
G01X1467470Y859899D02*
Y857790D01*
X1467471Y857789D01*
G01X1461921Y863103D02*
Y860994D01*
X1461920Y860993D01*
G01X1476721Y863103D02*
Y860994D01*
X1476720Y860993D01*
G01X1474870Y859899D02*
Y857790D01*
X1474871Y857789D01*
G01X1471170Y859899D02*
Y857790D01*
X1471171Y857789D01*
G01X1465621Y856694D02*
Y854585D01*
X1465620Y854584D01*
G01X1463770Y859899D02*
Y857790D01*
X1463771Y857789D01*
G01X1473021Y856694D02*
Y854585D01*
X1473020Y854584D01*
G01X1469321Y863103D02*
Y860994D01*
X1469320Y860993D01*
G01X1463770Y872716D02*
Y870607D01*
X1463771Y870606D01*
G01X1471170Y872716D02*
Y870607D01*
X1471171Y870606D01*
G01X1461921Y875920D02*
Y873811D01*
X1461920Y873810D01*
G01X1467470Y872716D02*
Y870607D01*
X1467471Y870606D01*
G01X1469321Y875920D02*
Y873811D01*
X1469320Y873810D01*
G01X1474870Y872716D02*
Y870607D01*
X1474871Y870606D01*
G01X1476721Y875920D02*
Y873811D01*
X1476720Y873810D01*
G01X1465621Y882329D02*
Y880220D01*
X1465620Y880219D01*
G01X1467470Y885533D02*
Y883424D01*
X1467471Y883423D01*
G01X1473021Y882329D02*
Y880220D01*
X1473020Y880219D01*
G01X1474870Y885533D02*
Y883424D01*
X1474871Y883423D01*
G01X1463770Y885533D02*
Y883424D01*
X1463771Y883423D01*
G01X1471170Y885533D02*
Y883424D01*
X1471171Y883423D01*
G01X1461921Y888737D02*
Y886628D01*
X1461920Y886627D01*
G01X1469321Y888737D02*
Y886628D01*
X1469320Y886627D01*
G01X1476721Y888737D02*
Y886628D01*
X1476720Y886627D01*
G01X1464203Y1125746D02*
Y1127855D01*
X1464204Y1127856D01*
G01X1475303Y1119337D02*
X1475304Y1121447D01*
G01X1471603Y1125746D02*
Y1127855D01*
X1471604Y1127856D01*
G01X1467903Y1119337D02*
X1467904Y1121447D01*
G01X1466054Y1122541D02*
Y1124650D01*
X1466053Y1124651D01*
G01X1462354Y1122541D02*
Y1124650D01*
X1462353Y1124651D01*
G01X1473454Y1122541D02*
Y1124650D01*
X1473453Y1124651D01*
G01X1469754Y1122541D02*
Y1124650D01*
X1469753Y1124651D01*
G01X1469754Y1135359D02*
Y1137469D01*
G01X1464203Y1138563D02*
Y1140973D01*
G01X1471603Y1138563D02*
Y1140973D01*
G01X1467903Y1132154D02*
Y1134263D01*
X1467904Y1134264D01*
G01X1466054Y1135359D02*
Y1137469D01*
G01X1462354Y1135359D02*
Y1137469D01*
G01X1475303Y1132154D02*
Y1134263D01*
X1475304Y1134264D01*
G01X1473454Y1135359D02*
Y1137469D01*
G01X1477755Y1578182D02*
X1476578Y1579359D01*
Y1581811D01*
X1477855Y1583088D01*
G01X1462295Y1578182D02*
X1463498Y1579385D01*
Y1581803D01*
X1462213Y1583088D01*
X1462195D01*
G01X1474355Y1578182D02*
X1475558Y1579385D01*
Y1581803D01*
X1474273Y1583088D01*
X1474255D01*
G01X1465695Y1578182D02*
X1464518Y1579359D01*
Y1581811D01*
X1465795Y1583088D01*
G01X1477755Y1590094D02*
X1476568Y1588907D01*
Y1586475D01*
X1477855Y1585188D01*
G01X1462295Y1590094D02*
X1463488Y1588901D01*
Y1586468D01*
X1462208Y1585188D01*
X1462195D01*
G01X1474355Y1590094D02*
X1475548Y1588901D01*
Y1586468D01*
X1474268Y1585188D01*
X1474255D01*
G01X1465695Y1590094D02*
X1464508Y1588907D01*
Y1586475D01*
X1465795Y1585188D01*
G01X1467595Y1614292D02*
X1468788Y1613099D01*
Y1610666D01*
X1467508Y1609386D01*
X1467495D01*
G01X1470995Y1614292D02*
X1469808Y1613105D01*
Y1610673D01*
X1471095Y1609386D01*
G01X1467595Y1602380D02*
X1468798Y1603583D01*
Y1606001D01*
X1467513Y1607286D01*
X1467495D01*
G01X1470995Y1602380D02*
X1469818Y1603557D01*
Y1606009D01*
X1471095Y1607286D01*
G01X1485331Y-20527D02*
X1482650Y-19811D01*
G01X1485331Y-22495D02*
X1482650Y-23211D01*
G01X1485331Y-527D02*
X1482650Y189D01*
G01X1485331Y-2495D02*
X1482650Y-3211D01*
G01X1487821Y869511D02*
Y867402D01*
X1487820Y867401D01*
G01X1480421Y869511D02*
Y867402D01*
X1480420Y867401D01*
G01X1491521Y863103D02*
Y860994D01*
X1491520Y860993D01*
G01X1489670Y859899D02*
Y857790D01*
X1489671Y857789D01*
G01X1484121Y863103D02*
Y860994D01*
X1484120Y860993D01*
G01X1482270Y859899D02*
Y857790D01*
X1482271Y857789D01*
G01X1487821Y856694D02*
Y854585D01*
X1487820Y854584D01*
G01X1485970Y859899D02*
Y857790D01*
X1485971Y857789D01*
G01X1480421Y856694D02*
Y854585D01*
X1480420Y854584D01*
G01X1478570Y859899D02*
Y857790D01*
X1478571Y857789D01*
G01X1478570Y872716D02*
Y870607D01*
X1478571Y870606D01*
G01X1485970Y872716D02*
Y870607D01*
X1485971Y870606D01*
G01X1489670Y872716D02*
Y870607D01*
X1489671Y870606D01*
G01X1491521Y875920D02*
Y873811D01*
X1491520Y873810D01*
G01X1482270Y872716D02*
Y870607D01*
X1482271Y870606D01*
G01X1484121Y875920D02*
Y873811D01*
X1484120Y873810D01*
G01X1487821Y882329D02*
Y880220D01*
X1487820Y880219D01*
G01X1489670Y885533D02*
Y883424D01*
X1489671Y883423D01*
G01X1480421Y882329D02*
Y880220D01*
X1480420Y880219D01*
G01X1482270Y885533D02*
Y883424D01*
X1482271Y883423D01*
G01X1485970Y885533D02*
Y883424D01*
X1485971Y883423D01*
G01X1478570Y885533D02*
Y883424D01*
X1478571Y883423D01*
G01X1491521Y888737D02*
Y886628D01*
X1491520Y886627D01*
G01X1484121Y888737D02*
Y886628D01*
X1484120Y886627D01*
G01X1490103Y1119337D02*
X1490104Y1121447D01*
G01X1486403Y1125746D02*
Y1127855D01*
X1486404Y1127856D01*
G01X1482703Y1119337D02*
X1482704Y1121447D01*
G01X1479003Y1125746D02*
Y1127855D01*
X1479004Y1127856D01*
G01X1491954Y1122541D02*
Y1124650D01*
X1491953Y1124651D01*
G01X1488254Y1122541D02*
Y1124650D01*
X1488253Y1124651D01*
G01X1484554Y1122541D02*
Y1124650D01*
X1484553Y1124651D01*
G01X1480854Y1122541D02*
Y1124650D01*
X1480853Y1124651D01*
G01X1477154Y1122541D02*
Y1124650D01*
X1477153Y1124651D01*
G01X1490103Y1132154D02*
Y1134263D01*
X1490104Y1134264D01*
G01X1488254Y1135359D02*
Y1137469D01*
G01X1482703Y1132154D02*
Y1134263D01*
X1482704Y1134264D01*
G01X1480854Y1135359D02*
Y1137469D01*
G01X1477154Y1135359D02*
Y1137469D01*
G01X1491954Y1135359D02*
Y1137469D01*
G01X1486403Y1138563D02*
Y1140973D01*
G01X1484554Y1135359D02*
Y1137469D01*
G01X1479003Y1138563D02*
Y1140973D01*
G01X1489815Y1578182D02*
X1488638Y1579359D01*
Y1581811D01*
X1489915Y1583088D01*
G01X1486415Y1578182D02*
X1487618Y1579385D01*
Y1581803D01*
X1486333Y1583088D01*
X1486315D01*
G01X1489815Y1590094D02*
X1488628Y1588907D01*
Y1586475D01*
X1489915Y1585188D01*
G01X1486415Y1590094D02*
X1487608Y1588901D01*
Y1586468D01*
X1486328Y1585188D01*
X1486315D01*
G01X1491715Y1614292D02*
X1492908Y1613099D01*
Y1610666D01*
X1491628Y1609386D01*
X1491615D01*
G01X1479655Y1614292D02*
X1480848Y1613099D01*
Y1610666D01*
X1479568Y1609386D01*
X1479555D01*
G01X1483055Y1614292D02*
X1481868Y1613105D01*
Y1610673D01*
X1483155Y1609386D01*
G01X1491715Y1602380D02*
X1492918Y1603583D01*
Y1606001D01*
X1491633Y1607286D01*
X1491615D01*
G01X1479655Y1602380D02*
X1480858Y1603583D01*
Y1606001D01*
X1479573Y1607286D01*
X1479555D01*
G01X1483055Y1602380D02*
X1481878Y1603557D01*
Y1606009D01*
X1483155Y1607286D01*
G01X1495221Y869511D02*
Y867402D01*
X1495220Y867401D01*
G01X1502621Y869511D02*
Y867401D01*
G01X1504471Y859899D02*
Y857789D01*
G01X1498921Y863103D02*
Y860994D01*
X1498920Y860993D01*
G01X1497070Y859899D02*
Y857790D01*
X1497071Y857789D01*
G01X1502621Y856694D02*
Y854585D01*
X1502620Y854584D01*
G01X1500770Y859899D02*
Y857790D01*
X1500771Y857789D01*
G01X1495221Y856694D02*
Y854585D01*
X1495220Y854584D01*
G01X1493370Y859899D02*
Y857790D01*
X1493371Y857789D01*
G01X1493370Y872716D02*
Y870607D01*
X1493371Y870606D01*
G01X1500770Y872716D02*
Y870607D01*
X1500771Y870606D01*
G01X1508170Y872716D02*
Y870607D01*
X1508171Y870606D01*
G01X1497070Y872716D02*
Y870607D01*
X1497071Y870606D01*
G01X1498921Y875920D02*
Y873811D01*
X1498920Y873810D01*
G01X1504471Y870606D02*
Y872716D01*
G01X1506321Y875920D02*
Y873810D01*
G01X1495221Y882329D02*
Y880220D01*
X1495220Y880219D01*
G01X1497070Y885533D02*
Y883424D01*
X1497071Y883423D01*
G01X1502621Y882329D02*
Y880219D01*
G01X1504471Y885533D02*
Y883423D01*
G01X1493370Y885533D02*
Y883424D01*
X1493371Y883423D01*
G01X1500770Y885533D02*
Y883424D01*
X1500771Y883423D01*
G01X1498921Y888737D02*
Y886628D01*
X1498920Y886627D01*
G01X1506321Y888737D02*
Y886627D01*
G01X1503054Y1122541D02*
Y1124650D01*
X1503053Y1124651D01*
G01X1497503Y1119337D02*
X1497504Y1121447D01*
G01X1493803Y1125746D02*
Y1127855D01*
X1493804Y1127856D01*
G01X1501203Y1125746D02*
Y1127855D01*
X1501204Y1127856D01*
G01X1499354Y1122541D02*
Y1124650D01*
X1499353Y1124651D01*
G01X1495654Y1122541D02*
Y1124650D01*
X1495653Y1124651D01*
G01X1508603Y1132154D02*
Y1134263D01*
X1508604Y1134264D01*
G01X1501203Y1138563D02*
Y1140973D01*
G01X1499354Y1135359D02*
Y1137469D01*
G01X1493803Y1138563D02*
Y1140973D01*
G01X1503054Y1135359D02*
Y1137469D01*
G01X1497503Y1132154D02*
Y1134263D01*
X1497504Y1134264D01*
G01X1495654Y1135359D02*
Y1137469D01*
G01X1501875Y1578182D02*
X1500698Y1579359D01*
Y1581811D01*
X1501975Y1583088D01*
G01X1498475Y1578182D02*
X1499678Y1579385D01*
Y1581803D01*
X1498393Y1583088D01*
X1498375D01*
G01X1501875Y1590094D02*
X1500688Y1588907D01*
Y1586475D01*
X1501975Y1585188D01*
G01X1498475Y1590094D02*
X1499668Y1588901D01*
Y1586468D01*
X1498388Y1585188D01*
X1498375D01*
G01X1503775Y1614292D02*
X1504968Y1613099D01*
Y1610666D01*
X1503688Y1609386D01*
X1503675D01*
G01X1507175Y1614292D02*
X1505988Y1613105D01*
Y1610673D01*
X1507275Y1609386D01*
G01X1495115Y1614292D02*
X1493928Y1613105D01*
Y1610673D01*
X1495215Y1609386D01*
G01X1503775Y1602380D02*
X1504978Y1603583D01*
Y1606001D01*
X1503693Y1607286D01*
X1503675D01*
G01X1507175Y1602380D02*
X1505998Y1603557D01*
Y1606009D01*
X1507275Y1607286D01*
G01X1495115Y1602380D02*
X1493938Y1603557D01*
Y1606009D01*
X1495215Y1607286D01*
G01X1542704Y32756D02*
Y34991D01*
X1543409Y35696D01*
Y37728D01*
X1542755Y38382D01*
X1537113D01*
X1526220Y49275D01*
Y52974D01*
X1524654Y54540D01*
G01X1531429Y77832D02*
Y75670D01*
X1529147Y73388D01*
X1526144Y66137D01*
Y59180D01*
X1524654Y57690D01*
G01X1521554Y1109724D02*
X1521553Y1111834D01*
G01X1519703Y1106520D02*
Y1108630D01*
G01X1510453Y1135359D02*
Y1137468D01*
X1510454Y1137469D01*
G01X1525995Y1578182D02*
X1524818Y1579359D01*
Y1581811D01*
X1526095Y1583088D01*
G01X1513935Y1578182D02*
X1512758Y1579359D01*
Y1581811D01*
X1514035Y1583088D01*
G01X1522595Y1578182D02*
X1523798Y1579385D01*
Y1581803D01*
X1522513Y1583088D01*
X1522495D01*
G01X1510535Y1578182D02*
X1511738Y1579385D01*
Y1581803D01*
X1510453Y1583088D01*
X1510435D01*
G01X1525995Y1590094D02*
X1524808Y1588907D01*
Y1586475D01*
X1526095Y1585188D01*
G01X1513935Y1590094D02*
X1512748Y1588907D01*
Y1586475D01*
X1514035Y1585188D01*
G01X1522595Y1590094D02*
X1523788Y1588901D01*
Y1586468D01*
X1522508Y1585188D01*
X1522495D01*
G01X1510535Y1590094D02*
X1511728Y1588901D01*
Y1586468D01*
X1510448Y1585188D01*
X1510435D01*
G01X1515835Y1614292D02*
X1517028Y1613099D01*
Y1610666D01*
X1515748Y1609386D01*
X1515735D01*
G01X1519235Y1614292D02*
X1518048Y1613105D01*
Y1610673D01*
X1519335Y1609386D01*
G01X1515835Y1602380D02*
X1517038Y1603583D01*
Y1606001D01*
X1515753Y1607286D01*
X1515735D01*
G01X1519235Y1602380D02*
X1518058Y1603557D01*
Y1606009D01*
X1519335Y1607286D01*
G01X1545066Y32756D02*
Y35133D01*
X1544429Y35770D01*
Y38151D01*
X1543178Y39402D01*
X1537536D01*
X1527240Y49698D01*
Y53126D01*
X1528654Y54540D01*
G01X1552153Y44370D02*
Y46558D01*
X1551516Y47195D01*
Y49260D01*
X1547900Y53251D01*
X1538081Y59814D01*
X1537816Y60307D01*
Y61011D01*
X1539096Y62291D01*
G01X1549791Y44370D02*
Y46453D01*
X1550496Y47158D01*
Y48866D01*
X1547228Y52472D01*
X1537301Y59107D01*
X1536786Y60069D01*
Y61001D01*
X1535496Y62291D01*
G01X1538996Y69297D02*
X1537802Y68103D01*
Y65685D01*
X1539096Y64391D01*
G01X1535596Y69297D02*
X1536782Y68111D01*
Y65677D01*
X1535496Y64391D01*
G01X1528654Y57690D02*
X1527164Y59180D01*
Y65934D01*
X1530012Y72810D01*
X1532205Y75003D01*
X1534367D01*
G01D02*
Y77165D01*
X1536405Y79203D01*
Y84483D01*
X1532870Y88018D01*
Y98972D01*
X1534060Y100162D01*
G01X1531429Y77832D02*
X1533591D01*
X1535385Y79626D01*
Y84060D01*
X1531850Y87595D01*
Y98972D01*
X1530660Y100162D01*
G01X1538055Y1578182D02*
X1536878Y1579359D01*
Y1581811D01*
X1538155Y1583088D01*
G01X1534655Y1578182D02*
X1535858Y1579385D01*
Y1581803D01*
X1534573Y1583088D01*
X1534555D01*
G01X1538055Y1590094D02*
X1536868Y1588907D01*
Y1586475D01*
X1538155Y1585188D01*
G01X1534655Y1590094D02*
X1535848Y1588901D01*
Y1586468D01*
X1534568Y1585188D01*
X1534555D01*
G01X1527895Y1614292D02*
X1529088Y1613099D01*
Y1610666D01*
X1527808Y1609386D01*
X1527795D01*
G01X1539955Y1614292D02*
X1541148Y1613099D01*
Y1610666D01*
X1539868Y1609386D01*
X1539855D01*
G01X1531295Y1614292D02*
X1530108Y1613105D01*
Y1610673D01*
X1531395Y1609386D01*
G01X1527895Y1602380D02*
X1529098Y1603583D01*
Y1606001D01*
X1527813Y1607286D01*
X1527795D01*
G01X1539955Y1602380D02*
X1541158Y1603583D01*
Y1606001D01*
X1539873Y1607286D01*
X1539855D01*
G01X1531295Y1602380D02*
X1530118Y1603557D01*
Y1606009D01*
X1531395Y1607286D01*
G01X1556877Y32756D02*
Y30648D01*
X1557599Y29926D01*
Y20681D01*
X1556413Y19495D01*
G01X1549791Y32756D02*
Y30618D01*
X1550498Y29911D01*
Y27621D01*
X1549308Y26431D01*
G01X1552153Y32756D02*
Y30556D01*
X1551518Y29921D01*
Y27621D01*
X1552708Y26431D01*
G01X1556877Y44370D02*
Y46453D01*
X1557582Y47158D01*
Y50151D01*
X1547786Y59947D01*
Y67001D01*
X1546496Y68291D01*
G01X1559240Y44370D02*
Y46592D01*
X1558602Y47230D01*
Y50574D01*
X1548806Y60370D01*
Y67001D01*
X1550096Y68291D01*
G01X1563964Y44370D02*
Y46453D01*
X1564669Y47158D01*
Y51624D01*
X1558786Y57507D01*
Y61001D01*
X1557496Y62291D01*
G01X1546596Y75297D02*
X1547782Y74111D01*
Y71677D01*
X1546496Y70391D01*
G01X1557596Y69297D02*
X1558782Y68111D01*
Y65677D01*
X1557496Y64391D01*
G01X1549996Y75297D02*
X1548802Y74103D01*
Y71685D01*
X1550096Y70391D01*
G01X1550115Y1578182D02*
X1548938Y1579359D01*
Y1581811D01*
X1550215Y1583088D01*
G01X1546715Y1578182D02*
X1547918Y1579385D01*
Y1581803D01*
X1546633Y1583088D01*
X1546615D01*
G01X1550115Y1590094D02*
X1548928Y1588907D01*
Y1586475D01*
X1550215Y1585188D01*
G01X1546715Y1590094D02*
X1547908Y1588901D01*
Y1586468D01*
X1546628Y1585188D01*
X1546615D01*
G01X1552015Y1614292D02*
X1553208Y1613099D01*
Y1610666D01*
X1551928Y1609386D01*
X1551915D01*
G01X1555415Y1614292D02*
X1554228Y1613105D01*
Y1610673D01*
X1555515Y1609386D01*
G01X1543355Y1614292D02*
X1542168Y1613105D01*
Y1610673D01*
X1543455Y1609386D01*
G01X1552015Y1602380D02*
X1553218Y1603583D01*
Y1606001D01*
X1551933Y1607286D01*
X1551915D01*
G01X1555415Y1602380D02*
X1554238Y1603557D01*
Y1606009D01*
X1555515Y1607286D01*
G01X1543355Y1602380D02*
X1542178Y1603557D01*
Y1606009D01*
X1543455Y1607286D01*
G01X1571051Y32756D02*
Y30647D01*
X1571772Y29926D01*
Y20681D01*
X1570586Y19495D01*
G01X1573413Y32756D02*
Y30557D01*
X1572792Y29936D01*
Y20689D01*
X1573986Y19495D01*
G01X1559240Y32756D02*
Y30557D01*
X1558619Y29936D01*
Y20689D01*
X1559813Y19495D01*
G01X1563964Y32756D02*
Y30618D01*
X1564671Y29911D01*
Y27621D01*
X1563481Y26431D01*
G01X1566326Y32756D02*
Y30556D01*
X1565691Y29921D01*
Y27621D01*
X1566881Y26431D01*
G01X1571051Y44370D02*
Y46453D01*
X1571756Y47158D01*
Y53085D01*
X1569786Y55055D01*
Y67001D01*
X1568496Y68291D01*
G01X1566326Y44370D02*
Y46486D01*
X1565689Y47123D01*
Y52047D01*
X1559806Y57930D01*
Y60996D01*
X1559816Y61006D01*
Y61011D01*
X1561096Y62291D01*
G01X1573413Y44370D02*
Y46489D01*
X1572786Y47116D01*
Y47148D01*
X1572776Y47158D01*
Y53508D01*
X1570806Y55478D01*
Y67001D01*
X1572096Y68291D01*
G01X1568596Y75297D02*
X1569782Y74111D01*
Y71677D01*
X1568496Y70391D01*
G01X1560996Y69297D02*
X1559802Y68103D01*
Y65685D01*
X1561096Y64391D01*
G01X1571996Y75297D02*
X1570802Y74103D01*
Y71685D01*
X1572096Y70391D01*
G01X1574235Y1578182D02*
X1573058Y1579359D01*
Y1581811D01*
X1574335Y1583088D01*
G01X1562175Y1578182D02*
X1560998Y1579359D01*
Y1581811D01*
X1562275Y1583088D01*
G01X1570835Y1578182D02*
X1572038Y1579385D01*
Y1581803D01*
X1570753Y1583088D01*
X1570735D01*
G01X1558775Y1578182D02*
X1559978Y1579385D01*
Y1581803D01*
X1558693Y1583088D01*
X1558675D01*
G01X1574235Y1590094D02*
X1573048Y1588907D01*
Y1586475D01*
X1574335Y1585188D01*
G01X1562175Y1590094D02*
X1560988Y1588907D01*
Y1586475D01*
X1562275Y1585188D01*
G01X1570835Y1590094D02*
X1572028Y1588901D01*
Y1586468D01*
X1570748Y1585188D01*
X1570735D01*
G01X1558775Y1590094D02*
X1559968Y1588901D01*
Y1586468D01*
X1558688Y1585188D01*
X1558675D01*
G01X1564075Y1614292D02*
X1565268Y1613099D01*
Y1610666D01*
X1563988Y1609386D01*
X1563975D01*
G01X1567475Y1614292D02*
X1566288Y1613105D01*
Y1610673D01*
X1567575Y1609386D01*
G01X1564075Y1602380D02*
X1565278Y1603583D01*
Y1606001D01*
X1563993Y1607286D01*
X1563975D01*
G01X1567475Y1602380D02*
X1566298Y1603557D01*
Y1606009D01*
X1567575Y1607286D01*
G01X1585224Y32756D02*
Y30647D01*
X1585945Y29926D01*
Y20681D01*
X1584759Y19495D01*
G01X1587586Y32756D02*
Y30537D01*
X1586965Y29916D01*
Y20689D01*
X1588159Y19495D01*
G01X1578137Y32756D02*
Y30618D01*
X1578844Y29911D01*
Y27621D01*
X1577654Y26431D01*
G01X1580499Y32756D02*
Y30556D01*
X1579864Y29921D01*
Y27621D01*
X1581054Y26431D01*
G01X1585224Y44370D02*
Y46453D01*
X1585939Y47168D01*
Y54404D01*
X1591796Y60261D01*
Y66991D01*
X1590496Y68291D01*
G01X1580499Y44370D02*
Y46533D01*
X1579872Y47160D01*
Y54644D01*
X1581816Y56588D01*
Y61011D01*
X1583096Y62291D01*
G01X1587586Y44370D02*
Y46515D01*
X1586959Y47142D01*
Y53981D01*
X1592816Y59838D01*
Y67011D01*
X1594096Y68291D01*
G01X1578137Y44370D02*
Y46453D01*
X1578842Y47158D01*
Y47159D01*
X1578852Y47169D01*
Y55067D01*
X1580796Y57011D01*
Y60991D01*
X1579496Y62291D01*
G01X1590596Y75297D02*
X1591782Y74111D01*
Y71677D01*
X1590496Y70391D01*
G01X1582996Y69297D02*
X1581802Y68103D01*
Y65685D01*
X1583096Y64391D01*
G01X1579596Y69297D02*
X1580782Y68111D01*
Y65677D01*
X1579496Y64391D01*
G01X1586295Y1578182D02*
X1585118Y1579359D01*
Y1581811D01*
X1586395Y1583088D01*
G01X1582895Y1578182D02*
X1584098Y1579385D01*
Y1581803D01*
X1582813Y1583088D01*
X1582795D01*
G01X1586295Y1590094D02*
X1585108Y1588907D01*
Y1586475D01*
X1586395Y1585188D01*
G01X1582895Y1590094D02*
X1584088Y1588901D01*
Y1586468D01*
X1582808Y1585188D01*
X1582795D01*
G01X1588195Y1614292D02*
X1589388Y1613099D01*
Y1610666D01*
X1588108Y1609386D01*
X1588095D01*
G01X1576135Y1614292D02*
X1577328Y1613099D01*
Y1610666D01*
X1576048Y1609386D01*
X1576035D01*
G01X1591595Y1614292D02*
X1590408Y1613105D01*
Y1610673D01*
X1591695Y1609386D01*
G01X1579535Y1614292D02*
X1578348Y1613105D01*
Y1610673D01*
X1579635Y1609386D01*
G01X1588195Y1602380D02*
X1589398Y1603583D01*
Y1606001D01*
X1588113Y1607286D01*
X1588095D01*
G01X1576135Y1602380D02*
X1577338Y1603583D01*
Y1606001D01*
X1576053Y1607286D01*
X1576035D01*
G01X1591595Y1602380D02*
X1590418Y1603557D01*
Y1606009D01*
X1591695Y1607286D01*
G01X1579535Y1602380D02*
X1578358Y1603557D01*
Y1606009D01*
X1579635Y1607286D01*
G01X1599397Y32756D02*
Y30648D01*
X1600119Y29926D01*
Y20681D01*
X1598933Y19495D01*
G01X1601759Y32756D02*
Y30556D01*
X1601139Y29936D01*
Y20689D01*
X1602333Y19495D01*
G01X1592311Y32756D02*
Y30618D01*
X1593018Y29911D01*
Y27621D01*
X1591828Y26431D01*
G01X1594673Y32756D02*
Y30556D01*
X1594038Y29921D01*
Y27621D01*
X1595228Y26431D01*
G01X1599397Y44370D02*
Y46453D01*
X1600112Y47168D01*
Y49497D01*
X1613796Y63181D01*
Y66991D01*
X1612496Y68291D01*
G01X1594673Y44370D02*
Y46649D01*
X1594046Y47276D01*
Y50008D01*
X1603816Y59778D01*
Y61011D01*
X1605096Y62291D01*
G01X1601759Y44370D02*
Y46623D01*
X1601132Y47250D01*
Y49074D01*
X1614816Y62758D01*
Y67011D01*
X1616096Y68291D01*
G01X1592311Y44370D02*
Y46453D01*
X1593016Y47158D01*
Y47266D01*
X1593026Y47276D01*
Y50431D01*
X1602796Y60201D01*
Y60991D01*
X1601496Y62291D01*
G01X1604996Y69297D02*
X1603802Y68103D01*
Y65685D01*
X1605096Y64391D01*
G01X1593996Y75297D02*
X1592802Y74103D01*
Y71685D01*
X1594096Y70391D01*
G01X1601596Y69297D02*
X1602782Y68111D01*
Y65677D01*
X1601496Y64391D01*
G01X1598355Y1578182D02*
X1597178Y1579359D01*
Y1581811D01*
X1598455Y1583088D01*
G01X1607015Y1578182D02*
X1608218Y1579385D01*
Y1581803D01*
X1606933Y1583088D01*
X1606915D01*
G01X1594955Y1578182D02*
X1596158Y1579385D01*
Y1581803D01*
X1594873Y1583088D01*
X1594855D01*
G01X1598355Y1590094D02*
X1597168Y1588907D01*
Y1586475D01*
X1598455Y1585188D01*
G01X1607015Y1590094D02*
X1608208Y1588901D01*
Y1586468D01*
X1606928Y1585188D01*
X1606915D01*
G01X1594955Y1590094D02*
X1596148Y1588901D01*
Y1586468D01*
X1594868Y1585188D01*
X1594855D01*
G01X1600255Y1614292D02*
X1601448Y1613099D01*
Y1610666D01*
X1600168Y1609386D01*
X1600155D01*
G01X1603655Y1614292D02*
X1602468Y1613105D01*
Y1610673D01*
X1603755Y1609386D01*
G01X1600255Y1602380D02*
X1601458Y1603583D01*
Y1606001D01*
X1600173Y1607286D01*
X1600155D01*
G01X1603655Y1602380D02*
X1602478Y1603557D01*
Y1606009D01*
X1603755Y1607286D01*
G01X1612596Y75297D02*
X1613782Y74111D01*
Y71677D01*
X1612496Y70391D01*
G01X1615996Y75297D02*
X1614802Y74103D01*
Y71685D01*
X1616096Y70391D01*
G01X1622475Y1578182D02*
X1621298Y1579359D01*
Y1581811D01*
X1622575Y1583088D01*
G01X1610415Y1578182D02*
X1609238Y1579359D01*
Y1581811D01*
X1610515Y1583088D01*
G01X1619075Y1578182D02*
X1620278Y1579385D01*
Y1581803D01*
X1618993Y1583088D01*
X1618975D01*
G01X1622475Y1590094D02*
X1621288Y1588907D01*
Y1586475D01*
X1622575Y1585188D01*
G01X1610415Y1590094D02*
X1609228Y1588907D01*
Y1586475D01*
X1610515Y1585188D01*
G01X1619075Y1590094D02*
X1620268Y1588901D01*
Y1586468D01*
X1618988Y1585188D01*
X1618975D01*
G01X1612315Y1614292D02*
X1613508Y1613099D01*
Y1610666D01*
X1612228Y1609386D01*
X1612215D01*
G01X1615715Y1614292D02*
X1614528Y1613105D01*
Y1610673D01*
X1615815Y1609386D01*
G01X1612315Y1602380D02*
X1613518Y1603583D01*
Y1606001D01*
X1612233Y1607286D01*
X1612215D01*
G01X1615715Y1602380D02*
X1614538Y1603557D01*
Y1606009D01*
X1615815Y1607286D01*
G01X1635263Y32756D02*
Y30648D01*
X1635985Y29926D01*
Y20681D01*
X1634799Y19495D01*
G01X1637625Y32756D02*
Y30556D01*
X1637005Y29936D01*
Y20689D01*
X1638199Y19495D01*
G01X1628177Y32756D02*
Y30618D01*
X1628884Y29911D01*
Y27621D01*
X1627694Y26431D01*
G01X1630539Y32756D02*
Y30556D01*
X1629904Y29921D01*
Y27621D01*
X1631094Y26431D01*
G01X1635263Y44370D02*
Y46453D01*
X1635968Y47158D01*
Y55791D01*
X1636990Y56813D01*
Y67001D01*
X1635700Y68291D01*
G01X1630539Y44370D02*
Y46473D01*
X1629912Y47100D01*
Y53310D01*
X1625816Y57406D01*
Y61011D01*
X1627096Y62291D01*
G01X1637625Y44370D02*
Y46547D01*
X1636988Y47184D01*
Y55368D01*
X1638010Y56390D01*
Y67001D01*
X1639300Y68291D01*
G01X1628177Y44370D02*
Y46453D01*
X1628892Y47168D01*
Y52887D01*
X1624796Y56983D01*
Y60991D01*
X1623496Y62291D01*
G01X1635800Y75297D02*
X1636986Y74111D01*
Y71677D01*
X1635700Y70391D01*
G01X1626996Y69297D02*
X1625802Y68103D01*
Y65685D01*
X1627096Y64391D01*
G01X1639200Y75297D02*
X1638006Y74103D01*
Y71685D01*
X1639300Y70391D01*
G01X1623596Y69297D02*
X1624782Y68111D01*
Y65677D01*
X1623496Y64391D01*
G01X1634535Y1578182D02*
X1633358Y1579359D01*
Y1581811D01*
X1634635Y1583088D01*
G01X1631135Y1578182D02*
X1632338Y1579385D01*
Y1581803D01*
X1631053Y1583088D01*
X1631035D01*
G01X1634535Y1590094D02*
X1633348Y1588907D01*
Y1586475D01*
X1634635Y1585188D01*
G01X1631135Y1590094D02*
X1632328Y1588901D01*
Y1586468D01*
X1631048Y1585188D01*
X1631035D01*
G01X1636435Y1614292D02*
X1637628Y1613099D01*
Y1610666D01*
X1636348Y1609386D01*
X1636335D01*
G01X1624375Y1614292D02*
X1625568Y1613099D01*
Y1610666D01*
X1624288Y1609386D01*
X1624275D01*
G01X1639835Y1614292D02*
X1638648Y1613105D01*
Y1610673D01*
X1639935Y1609386D01*
G01X1627775Y1614292D02*
X1626588Y1613105D01*
Y1610673D01*
X1627875Y1609386D01*
G01X1636435Y1602380D02*
X1637638Y1603583D01*
Y1606001D01*
X1636353Y1607286D01*
X1636335D01*
G01X1624375Y1602380D02*
X1625578Y1603583D01*
Y1606001D01*
X1624293Y1607286D01*
X1624275D01*
G01X1639835Y1602380D02*
X1638658Y1603557D01*
Y1606009D01*
X1639935Y1607286D01*
G01X1627775Y1602380D02*
X1626598Y1603557D01*
Y1606009D01*
X1627875Y1607286D01*
G01X1649437Y32756D02*
Y30647D01*
X1650158Y29926D01*
Y20681D01*
X1648972Y19495D01*
G01X1651799Y32756D02*
Y30557D01*
X1651178Y29936D01*
Y20689D01*
X1652372Y19495D01*
G01X1642350Y32756D02*
Y30618D01*
X1643057Y29911D01*
Y27621D01*
X1641867Y26431D01*
G01X1644712Y32756D02*
Y30556D01*
X1644077Y29921D01*
Y27621D01*
X1645267Y26431D01*
G01X1649437Y44370D02*
Y46453D01*
X1650152Y47168D01*
Y50647D01*
X1659000Y59495D01*
Y66991D01*
X1657700Y68291D01*
G01X1644712Y44370D02*
Y46529D01*
X1644085Y47156D01*
Y53677D01*
X1649020Y58612D01*
Y61011D01*
X1650300Y62291D01*
G01X1651799Y44370D02*
Y46524D01*
X1651172Y47151D01*
Y50224D01*
X1660020Y59072D01*
Y67011D01*
X1661300Y68291D01*
G01X1642350Y44370D02*
Y46453D01*
X1643065Y47168D01*
Y54100D01*
X1648000Y59035D01*
Y60991D01*
X1646700Y62291D01*
G01X1650200Y69297D02*
X1649006Y68103D01*
Y65685D01*
X1650300Y64391D01*
G01X1646800Y69297D02*
X1647986Y68111D01*
Y65677D01*
X1646700Y64391D01*
G01X1646595Y1578182D02*
X1645418Y1579359D01*
Y1581811D01*
X1646695Y1583088D01*
G01X1643195Y1578182D02*
X1644398Y1579385D01*
Y1581803D01*
X1643113Y1583088D01*
X1643095D01*
G01X1646595Y1590094D02*
X1645408Y1588907D01*
Y1586475D01*
X1646695Y1585188D01*
G01X1643195Y1590094D02*
X1644388Y1588901D01*
Y1586468D01*
X1643108Y1585188D01*
X1643095D01*
G01X1651895Y1614292D02*
X1650708Y1613105D01*
Y1610673D01*
X1651995Y1609386D01*
G01X1648495Y1614292D02*
X1649688Y1613099D01*
Y1610666D01*
X1648408Y1609386D01*
X1648395D01*
G01X1651895Y1602380D02*
X1650718Y1603557D01*
Y1606009D01*
X1651995Y1607286D01*
G01X1648495Y1602380D02*
X1649698Y1603583D01*
Y1606001D01*
X1648413Y1607286D01*
X1648395D01*
G01X1672311Y32756D02*
Y30618D01*
X1673018Y29911D01*
Y27621D01*
X1671828Y26431D01*
G01X1672311Y44370D02*
Y46453D01*
X1673016Y47158D01*
Y53637D01*
X1669990Y56663D01*
Y61001D01*
X1668700Y62291D01*
G01X1674673Y44370D02*
Y46509D01*
X1674036Y47146D01*
Y54060D01*
X1671010Y57086D01*
Y60996D01*
X1671020Y61006D01*
Y61011D01*
X1672300Y62291D01*
G01X1672200Y69297D02*
X1671006Y68103D01*
Y65685D01*
X1672300Y64391D01*
G01X1657800Y75297D02*
X1658986Y74111D01*
Y71677D01*
X1657700Y70391D01*
G01X1668800Y69297D02*
X1669986Y68111D01*
Y65677D01*
X1668700Y64391D01*
G01X1661200Y75297D02*
X1660006Y74103D01*
Y71685D01*
X1661300Y70391D01*
G01X1679397Y32756D02*
Y30648D01*
X1680119Y29926D01*
Y20681D01*
X1678933Y19495D01*
G01X1681759Y32756D02*
Y30556D01*
X1681139Y29936D01*
Y20689D01*
X1682333Y19495D01*
G01X1686484Y32756D02*
Y30618D01*
X1687191Y29911D01*
Y27621D01*
X1686001Y26431D01*
G01X1688846Y32756D02*
Y30556D01*
X1688211Y29921D01*
Y27621D01*
X1689401Y26431D01*
G01X1674673Y32756D02*
Y30556D01*
X1674038Y29921D01*
Y27621D01*
X1675228Y26431D01*
G01X1688846Y44370D02*
Y46475D01*
X1688219Y47102D01*
Y53811D01*
X1693154Y58746D01*
Y61011D01*
X1694434Y62291D01*
G01X1679397Y44370D02*
Y46453D01*
X1680102Y47158D01*
Y55685D01*
X1681124Y56707D01*
Y67001D01*
X1679834Y68291D01*
G01X1686484Y44370D02*
Y46453D01*
X1687199Y47168D01*
Y54234D01*
X1692134Y59169D01*
Y60991D01*
X1690834Y62291D01*
G01X1681759Y44370D02*
Y46530D01*
X1681122Y47167D01*
Y55262D01*
X1682144Y56284D01*
Y67001D01*
X1683434Y68291D01*
G01X1679934Y75297D02*
X1681120Y74111D01*
Y71677D01*
X1679834Y70391D01*
G01X1683334Y75297D02*
X1682140Y74103D01*
Y71685D01*
X1683434Y70391D01*
G01X1695933Y32756D02*
Y30557D01*
X1695312Y29936D01*
Y20689D01*
X1696506Y19495D01*
G01X1693570Y32756D02*
Y30648D01*
X1694292Y29926D01*
Y20681D01*
X1693106Y19495D01*
G01X1703019Y32756D02*
Y30541D01*
X1702410Y29932D01*
Y27666D01*
X1703617Y26459D01*
G01X1700217D02*
X1701390Y27632D01*
Y30016D01*
X1700657Y30749D01*
Y32756D01*
G01X1703019Y44370D02*
Y46424D01*
X1702380Y47063D01*
Y49459D01*
X1703570Y50649D01*
G01X1700657Y44370D02*
Y46410D01*
X1701360Y47113D01*
Y49459D01*
X1700170Y50649D01*
G01X1695933Y44370D02*
Y46490D01*
X1695305Y47118D01*
Y52757D01*
X1704180Y61632D01*
Y67037D01*
X1705434Y68291D01*
G01X1693570Y44370D02*
Y46453D01*
X1694285Y47168D01*
Y53180D01*
X1703160Y62055D01*
Y66965D01*
X1701834Y68291D01*
G01X1694334Y69297D02*
X1693140Y68103D01*
Y65685D01*
X1694434Y64391D01*
G01X1701934Y75297D02*
X1703120Y74111D01*
Y71677D01*
X1701834Y70391D01*
G01X1690934Y69297D02*
X1692120Y68111D01*
Y65677D01*
X1690834Y64391D01*
G01X1705334Y75297D02*
X1704140Y74103D01*
Y71685D01*
X1705434Y70391D01*
G01X1758118Y32756D02*
Y30557D01*
X1757482Y29921D01*
Y27621D01*
X1758672Y26431D01*
G01X1755272D02*
X1756462Y27621D01*
Y29971D01*
X1755755Y30678D01*
Y32756D01*
G01X1758118Y44370D02*
Y46424D01*
X1757479Y47063D01*
Y49459D01*
X1758669Y50649D01*
G01X1755755Y44370D02*
Y46409D01*
X1756459Y47113D01*
Y49459D01*
X1755269Y50649D01*
G01X2078539Y1195372D02*
X2074713D01*
X2074046Y1194705D01*
Y603695D01*
X2074569Y603172D01*
X2078539D01*
G01X2068539D02*
X2072509D01*
X2073026Y603689D01*
Y1194695D01*
X2072349Y1195372D01*
X2068539D01*
G54D329*
G01X44773Y778511D02*
X52919D01*
G01X43765Y771783D02*
X43800Y771818D01*
X51617D01*
G01X52919Y788550D02*
X43810D01*
G01X44773Y801936D02*
X52919D01*
G01X43765Y795208D02*
X43800Y795243D01*
X51617D01*
G01X51646Y791897D02*
X44735D01*
G01X44773Y815322D02*
X52919D01*
G01X43765Y808594D02*
X43800Y808629D01*
X51617D01*
G01X43765Y832019D02*
X43800Y832054D01*
X51617D01*
G01X52919Y825361D02*
X43810D01*
G01X51646Y828708D02*
X44735D01*
G01X44773Y852133D02*
X52919D01*
G01X43765Y845405D02*
X43800Y845440D01*
X51617D01*
G01X44773Y838747D02*
X52919D01*
G01Y862172D02*
X43810D01*
G01X51646Y865519D02*
X44735D01*
G01X43765Y882216D02*
X43800Y882251D01*
X51617D01*
G01X44773Y875558D02*
X52919D01*
G01X43765Y868830D02*
X43800Y868865D01*
X51617D01*
G01X44773Y888944D02*
X52919D01*
G01Y898983D02*
X43810D01*
G01X51646Y902330D02*
X44735D01*
G01X44773Y912369D02*
X52919D01*
G01X43765Y905641D02*
X43800Y905676D01*
X51617D01*
G01X44773Y925755D02*
X52919D01*
G01X43765Y919027D02*
X43800Y919062D01*
X51617D01*
G01X44773Y949180D02*
X52919D01*
G01X43765Y942452D02*
X43800Y942487D01*
X51617D01*
G01X52919Y935794D02*
X43810D01*
G01X51646Y939141D02*
X44735D01*
G01X43765Y979263D02*
X43800Y979298D01*
X51617D01*
G01X43765Y972570D02*
X43800Y972605D01*
X51617D01*
G01X43765Y992649D02*
X43800Y992684D01*
X51617D01*
G01X43765Y985956D02*
X43800Y985991D01*
X51617D01*
G01X43765Y1026114D02*
X43800Y1026149D01*
X51617D01*
G01X43853Y1019456D02*
X51617D01*
G01X43765Y1046192D02*
X43800Y1046227D01*
X51617D01*
G01X43765Y1039499D02*
X43800Y1039534D01*
X51617D01*
G01X43765Y1032807D02*
X43800Y1032842D01*
X51617D01*
G01X43765Y1059578D02*
X43800Y1059613D01*
X52796D01*
G01X44773Y1072999D02*
X52919D01*
G01X43765Y1066271D02*
X43800Y1066306D01*
X51617D01*
G01X43765Y1089696D02*
X43800Y1089731D01*
X51617D01*
G01X52919Y1083038D02*
X43810D01*
G01X51646Y1086385D02*
X44735D01*
G01X44773Y1096424D02*
X52919D01*
G01X44773Y1109810D02*
X52919D01*
G01X43765Y1103082D02*
X43800Y1103117D01*
X51617D01*
G01X43765Y1126507D02*
X43800Y1126542D01*
X51617D01*
G01X52919Y1119849D02*
X43810D01*
G01X51646Y1123196D02*
X44735D01*
G01X43765Y1139893D02*
X43800Y1139928D01*
X51617D01*
G01X44773Y1133235D02*
X52919D01*
G01X44773Y1146621D02*
X52919D01*
G01Y1156660D02*
X43810D01*
G01X51646Y1160007D02*
X44735D01*
G01X43765Y1176704D02*
X43800Y1176739D01*
X51617D01*
G01X44773Y1170046D02*
X52919D01*
G01X43765Y1163318D02*
X43800Y1163353D01*
X51617D01*
G01X44773Y1183432D02*
X52919D01*
G01Y1193471D02*
X43810D01*
G01X44773Y1206857D02*
X52919D01*
G01X43765Y1200129D02*
X43800Y1200164D01*
X51617D01*
G01X51646Y1196818D02*
X44735D01*
G01X44773Y1220243D02*
X52919D01*
G01X43765Y1213515D02*
X43800Y1213550D01*
X51617D01*
G01X43765Y1236940D02*
X43800Y1236975D01*
X51617D01*
G01X52919Y1230282D02*
X43810D01*
G01X51646Y1233629D02*
X44735D01*
G01X51394Y1250343D02*
X45039D01*
G01X44773Y1243668D02*
X52919D01*
G01X58316Y771817D02*
X66477D01*
G01X58367Y775164D02*
X66477D01*
G01Y785204D02*
X58298D01*
G01X66477Y781858D02*
X66476Y781857D01*
X58295D01*
G01X58367Y798590D02*
X66477D01*
G01X58316Y795243D02*
X66477D01*
G01X58367Y811975D02*
X66477D01*
G01X58316Y808628D02*
X66477D01*
G01Y818669D02*
X66476Y818668D01*
X58295D01*
G01X58367Y835401D02*
X66477D01*
G01X58316Y832054D02*
X66477D01*
G01Y822015D02*
X58298D01*
G01X58367Y848786D02*
X66477D01*
G01X58316Y845439D02*
X66477D01*
G01X58316Y868865D02*
X66477D01*
G01Y858826D02*
X58298D01*
G01X66477Y855480D02*
X66476Y855479D01*
X58295D01*
G01X58367Y872212D02*
X66477D01*
G01X58316Y882250D02*
X66477D01*
G01X58367Y885597D02*
X66477D01*
G01Y895637D02*
X58298D01*
G01X66477Y892291D02*
X66476Y892290D01*
X58295D01*
G01X58367Y909023D02*
X66477D01*
G01X58316Y905676D02*
X66477D01*
G01X58367Y922408D02*
X66477D01*
G01X58316Y919062D02*
X66477D01*
G01Y932448D02*
X58298D01*
G01X66477Y929102D02*
X66476Y929101D01*
X58295D01*
G01X58367Y945834D02*
X66477D01*
G01X58316Y942487D02*
X66477D01*
G01X58316Y979298D02*
X66477D01*
G01X58316Y972605D02*
X66477D01*
G01X58316Y992684D02*
X66477D01*
G01X58316Y985991D02*
X66477D01*
G01X58316Y1032841D02*
X66477D01*
G01X58316Y1046227D02*
X66477D01*
G01X58316Y1039534D02*
X66477D01*
G01X58316Y1059613D02*
X66521D01*
G01X58367Y1069653D02*
X66477D01*
G01X58316Y1066306D02*
X66477D01*
G01X66478Y1079692D02*
X58298D01*
G01X66477Y1076346D02*
X66476Y1076345D01*
X58295D01*
G01X58367Y1093078D02*
X66477D01*
G01X58316Y1089731D02*
X66477D01*
G01X58367Y1106464D02*
X66477D01*
G01X58316Y1103117D02*
X66477D01*
G01X58316Y1126542D02*
X66477D01*
G01Y1116503D02*
X58298D01*
G01X66477Y1113157D02*
X66476Y1113156D01*
X58295D01*
G01X58367Y1143275D02*
X66477D01*
G01X58316Y1139928D02*
X66477D01*
G01X58367Y1129889D02*
X66477D01*
G01Y1153314D02*
X58298D01*
G01X66477Y1149968D02*
X58294D01*
G01X58316Y1176739D02*
X66477D01*
G01X58367Y1166700D02*
X66477D01*
G01X58316Y1163353D02*
X66477D01*
G01X58367Y1180086D02*
X66477D01*
G01Y1190125D02*
X58298D01*
G01X66477Y1186779D02*
X58294D01*
G01X58367Y1203511D02*
X66477D01*
G01X58316Y1200164D02*
X66477D01*
G01X58367Y1216897D02*
X66477D01*
G01X58316Y1213550D02*
X66477D01*
G01Y1226936D02*
X58298D01*
G01X66477Y1223590D02*
X58294D01*
G01X58367Y1240322D02*
X66477D01*
G01X58316Y1236975D02*
X66477D01*
G01X94807Y1056266D02*
X88030D01*
G01X81094Y1250343D02*
X74739D01*
G01X104173Y778511D02*
X112319D01*
G01X103165Y771783D02*
X103200Y771818D01*
X111017D01*
G01X103210Y788550D02*
X112319D01*
G01X103165Y795208D02*
X103200Y795243D01*
X111017D01*
G01X104135Y791897D02*
X111046D01*
G01X104173Y815322D02*
X112319D01*
G01X103165Y808594D02*
X103200Y808629D01*
X111017D01*
G01X104173Y801936D02*
X112319D01*
G01X103165Y832019D02*
X103200Y832054D01*
X111017D01*
G01X103210Y825361D02*
X112319D01*
G01X104135Y828708D02*
X111046D01*
G01X103165Y845405D02*
X103200Y845440D01*
X111017D01*
G01X104173Y838747D02*
X112319D01*
G01X104173Y852133D02*
X112319D01*
G01X103210Y862172D02*
X112319D01*
G01X104135Y865519D02*
X111046D01*
G01X103165Y882216D02*
X103200Y882251D01*
X111017D01*
G01X104173Y875558D02*
X112319D01*
G01X103165Y868830D02*
X103200Y868865D01*
X111017D01*
G01X104173Y888944D02*
X112319D01*
G01X103210Y898983D02*
X112319D01*
G01X104135Y902330D02*
X111046D01*
G01X104173Y912369D02*
X112319D01*
G01X103165Y905641D02*
X103200Y905676D01*
X111017D01*
G01X104173Y925755D02*
X112319D01*
G01X103200Y919062D02*
X111017D01*
G01X103200Y942487D02*
X111017D01*
G01X103210Y935794D02*
X112319D01*
G01X104135Y939141D02*
X112320D01*
G01X104173Y949180D02*
X112319D01*
G01X103165Y979263D02*
X103200Y979298D01*
X111017D01*
G01X103165Y972570D02*
X103200Y972605D01*
X111017D01*
G01X103165Y992649D02*
X103200Y992684D01*
X111017D01*
G01X103165Y985956D02*
X103200Y985991D01*
X111017D01*
G01X103165Y1026114D02*
X103200Y1026149D01*
X111017D01*
G01X103253Y1019456D02*
X111017D01*
G01X103165Y1039499D02*
X103200Y1039534D01*
X111017D01*
G01X103165Y1032807D02*
X103200Y1032842D01*
X111017D01*
G01X103165Y1059578D02*
X103200Y1059613D01*
X111017D01*
G01X103165Y1046192D02*
X103200Y1046227D01*
X111017D01*
G01X104173Y1072999D02*
X112319D01*
G01X103200Y1066306D02*
X111017D01*
G01X103200Y1089731D02*
X111017D01*
G01X103210Y1083038D02*
X112319D01*
G01X104135Y1086385D02*
X111046D01*
G01X104173Y1096424D02*
X112319D01*
G01X104173Y1109810D02*
X112319D01*
G01X103165Y1103082D02*
X103200Y1103117D01*
X111017D01*
G01X103165Y1126507D02*
X103200Y1126542D01*
X111017D01*
G01X103210Y1119849D02*
X112319D01*
G01X104135Y1123196D02*
X111046D01*
G01X103165Y1139893D02*
X103200Y1139928D01*
X111017D01*
G01X104173Y1133235D02*
X112319D01*
G01X104173Y1146621D02*
X112319D01*
G01X103210Y1156660D02*
X112319D01*
G01X104135Y1160007D02*
X111046D01*
G01X104173Y1170046D02*
X112319D01*
G01X103165Y1163318D02*
X103200Y1163353D01*
X111017D01*
G01X104173Y1183432D02*
X112319D01*
G01X103165Y1176704D02*
X103200Y1176739D01*
X111017D01*
G01X103210Y1193471D02*
X112319D01*
G01X104173Y1206857D02*
X112319D01*
G01X103165Y1200129D02*
X103200Y1200164D01*
X111017D01*
G01X104135Y1196818D02*
X111046D01*
G01X104173Y1220243D02*
X112319D01*
G01X103165Y1213515D02*
X103200Y1213550D01*
X111017D01*
G01X103165Y1236940D02*
X103200Y1236975D01*
X111017D01*
G01X103210Y1230282D02*
X112319D01*
G01X104135Y1233629D02*
X111046D01*
G01X110794Y1250343D02*
X104439D01*
G01X104173Y1243668D02*
X112319D01*
G01X117716Y771817D02*
X125877D01*
G01X117767Y775164D02*
X125877D01*
G01X117698Y785204D02*
X125877D01*
G01X117695Y781857D02*
X125876D01*
X125877Y781858D01*
G01X117767Y798590D02*
X125877D01*
G01X117716Y795243D02*
X125877D01*
G01X117767Y811975D02*
X125877D01*
G01X117716Y808628D02*
X125877D01*
G01X117716Y832054D02*
X125877D01*
G01X117698Y822015D02*
X125877D01*
G01X117695Y818668D02*
X125876D01*
X125877Y818669D01*
G01X117767Y848786D02*
X125877D01*
G01X117716Y845439D02*
X125877D01*
G01X117767Y835401D02*
X125877D01*
G01X117716Y868865D02*
X125877D01*
G01X117698Y858826D02*
X125877D01*
G01X117695Y855479D02*
X125876D01*
X125877Y855480D01*
G01X117767Y872212D02*
X125877D01*
G01X117716Y882250D02*
X125877D01*
G01X117767Y885597D02*
X125877D01*
G01X117698Y895637D02*
X125877D01*
G01X117695Y892290D02*
X125876D01*
X125877Y892291D01*
G01X117767Y909023D02*
X125877D01*
G01X117716Y905676D02*
X125877D01*
G01X117767Y922408D02*
X125877D01*
G01X117716Y919062D02*
X125877D01*
G01X117698Y932448D02*
X125877D01*
G01X117695Y929101D02*
X125876D01*
G01X117767Y945834D02*
X125877D01*
G01X117716Y942487D02*
X125877D01*
G01X117716Y979298D02*
X125877D01*
G01X117716Y972605D02*
X125877D01*
G01X117716Y992684D02*
X125877D01*
G01X117716Y985991D02*
X125877D01*
G01X117716Y1046227D02*
X125877D01*
G01X117716Y1039534D02*
X125877D01*
G01X117716Y1032841D02*
X125877D01*
G01X124567Y1056266D02*
X117863D01*
G01X117767Y1069653D02*
X125877D01*
G01X116779Y1066306D02*
X125877D01*
G01X117695Y1076345D02*
X125876D01*
G01X117767Y1093078D02*
X126026D01*
G01X117716Y1089731D02*
X125877D01*
G01X117698Y1079692D02*
X125877D01*
G01X117767Y1106464D02*
X125877D01*
G01X117716Y1103117D02*
X125877D01*
G01X117716Y1126542D02*
X125877D01*
G01X117698Y1116503D02*
X125877D01*
G01X117695Y1113156D02*
X125876D01*
X125877Y1113157D01*
G01X117716Y1139928D02*
X125877D01*
G01X117767Y1129889D02*
X125877D01*
G01X117767Y1143275D02*
X125877D01*
G01X117698Y1153314D02*
X125877D01*
G01X117694Y1149968D02*
X125877D01*
G01X117716Y1176739D02*
X125877D01*
G01X117767Y1166700D02*
X125877D01*
G01X117716Y1163353D02*
X125877D01*
G01X117767Y1180086D02*
X125877D01*
G01X117698Y1190125D02*
X125877D01*
G01X117694Y1186779D02*
X125877D01*
G01X117767Y1203511D02*
X125877D01*
G01X117716Y1200164D02*
X125877D01*
G01X117767Y1216897D02*
X125877D01*
G01X117716Y1213550D02*
X125877D01*
G01X117694Y1223590D02*
X125877D01*
G01X117767Y1240322D02*
X125877D01*
G01X117716Y1236975D02*
X125877D01*
G01X117698Y1226936D02*
X125877D01*
G01X140494Y1250343D02*
X134139D01*
G01X171719Y778511D02*
X163573D01*
G01X170417Y771818D02*
X162600D01*
X162565Y771783D01*
G01X171719Y788550D02*
X162610D01*
G01X170417Y795243D02*
X162600D01*
X162565Y795208D01*
G01X170446Y791897D02*
X163535D01*
G01X171719Y815322D02*
X163573D01*
G01X170417Y808629D02*
X162600D01*
X162565Y808594D01*
G01X171719Y801936D02*
X163573D01*
G01X170417Y832054D02*
X162600D01*
X162565Y832019D01*
G01X171719Y825361D02*
X162610D01*
G01X170446Y828708D02*
X163535D01*
G01X170417Y845440D02*
X162600D01*
X162565Y845405D01*
G01X171719Y838747D02*
X163573D01*
G01X171719Y852133D02*
X163573D01*
G01X171719Y862172D02*
X162610D01*
G01X170446Y865519D02*
X163535D01*
G01X170417Y882251D02*
X162600D01*
X162565Y882216D01*
G01X171719Y875558D02*
X163573D01*
G01X170417Y868865D02*
X162600D01*
X162565Y868830D01*
G01X171719Y888944D02*
X163573D01*
G01X171719Y898983D02*
X162610D01*
G01X170446Y902330D02*
X163535D01*
G01X171719Y912369D02*
X163573D01*
G01X170417Y905676D02*
X162600D01*
X162565Y905641D01*
G01X171719Y925755D02*
X163573D01*
G01X170417Y919062D02*
X162600D01*
X162565Y919027D01*
G01X170417Y942487D02*
X162600D01*
X162565Y942452D01*
G01X171719Y935794D02*
X162610D01*
G01X170446Y939141D02*
X163535D01*
G01X171719Y949180D02*
X163573D01*
G01X170417Y979298D02*
X162600D01*
X162565Y979263D01*
G01X170417Y972605D02*
X162600D01*
X162565Y972570D01*
G01X170417Y992684D02*
X162600D01*
X162565Y992649D01*
G01X170417Y985991D02*
X162600D01*
X162565Y985956D01*
G01X170417Y1026149D02*
X162600D01*
X162565Y1026114D01*
G01X170417Y1019456D02*
X162653D01*
G01X170417Y1039534D02*
X162600D01*
X162565Y1039499D01*
G01X170417Y1032842D02*
X162600D01*
X162565Y1032807D01*
G01X170417Y1059613D02*
X162600D01*
G01X170417Y1046227D02*
X162600D01*
X162565Y1046192D01*
G01X171719Y1072999D02*
X163573D01*
G01X170417Y1066306D02*
X162600D01*
X162565Y1066271D01*
G01X170417Y1089731D02*
X162600D01*
X162565Y1089696D01*
G01X171719Y1083038D02*
X162610D01*
G01X170446Y1086385D02*
X163535D01*
G01X171719Y1096424D02*
X163573D01*
G01X171719Y1109810D02*
X163573D01*
G01X170417Y1103117D02*
X162600D01*
X162565Y1103082D01*
G01X170417Y1126542D02*
X162600D01*
X162565Y1126507D01*
G01X171719Y1119849D02*
X162610D01*
G01X170446Y1123196D02*
X163535D01*
G01X170417Y1139928D02*
X162600D01*
X162565Y1139893D01*
G01X171719Y1133235D02*
X163573D01*
G01X171719Y1146621D02*
X163573D01*
G01X171719Y1156660D02*
X162610D01*
G01X170446Y1160007D02*
X163535D01*
G01X171719Y1170046D02*
X163573D01*
G01X170417Y1163353D02*
X162600D01*
X162565Y1163318D01*
G01X171719Y1183432D02*
X163573D01*
G01X170417Y1176739D02*
X162600D01*
X162565Y1176704D01*
G01X171719Y1193471D02*
X162610D01*
G01X171719Y1206857D02*
X163573D01*
G01X170417Y1200164D02*
X162600D01*
X162565Y1200129D01*
G01X170446Y1196818D02*
X163535D01*
G01X171719Y1220243D02*
X163573D01*
G01X170417Y1213550D02*
X162600D01*
X162565Y1213515D01*
G01X170417Y1236975D02*
X162600D01*
X162565Y1236940D01*
G01X171719Y1230282D02*
X162610D01*
G01X170446Y1233629D02*
X163535D01*
G01X163839Y1250343D02*
X170194D01*
G01X171719Y1243668D02*
X163573D01*
G01X185277Y771817D02*
X177116D01*
G01X185277Y775164D02*
X177167D01*
G01X185277Y785204D02*
X177098D01*
G01X185277Y781858D02*
X185276Y781857D01*
X177095D01*
G01X185277Y798590D02*
X177167D01*
G01X185277Y795243D02*
X177116D01*
G01X185277Y811975D02*
X177167D01*
G01X185277Y808628D02*
X177116D01*
G01X185277Y818669D02*
X185276Y818668D01*
X177095D01*
G01X185277Y835401D02*
X177167D01*
G01X185277Y832054D02*
X177116D01*
G01X185277Y822015D02*
X177098D01*
G01X185277Y848786D02*
X177167D01*
G01X185277Y845439D02*
X177116D01*
G01X185277Y868865D02*
X177116D01*
G01X185277Y858826D02*
X177098D01*
G01X185277Y855480D02*
X185276Y855479D01*
X177095D01*
G01X185277Y872212D02*
X177167D01*
G01X185277Y882250D02*
X177116D01*
G01X185277Y885597D02*
X177167D01*
G01X185277Y895637D02*
X177098D01*
G01X185277Y892291D02*
X185276Y892290D01*
X177095D01*
G01X185277Y909023D02*
X177167D01*
G01X185277Y905676D02*
X177116D01*
G01X185277Y922408D02*
X177167D01*
G01X185277Y919062D02*
X177116D01*
G01X185277Y932448D02*
X177098D01*
G01X185277Y929102D02*
X185276Y929101D01*
X177095D01*
G01X185277Y945834D02*
X177167D01*
G01X185277Y942487D02*
X177116D01*
G01X185277Y979298D02*
X177116D01*
G01X185277Y972605D02*
X177116D01*
G01X185277Y992684D02*
X177116D01*
G01X185277Y985991D02*
X177116D01*
G01X185277Y1032841D02*
X177116D01*
G01X185277Y1046227D02*
X177116D01*
G01X185277Y1039534D02*
X177116D01*
G01X183875Y1059613D02*
X177234D01*
G01X185277Y1069653D02*
X177167D01*
G01X185277Y1066306D02*
X177116D01*
G01X177098Y1079692D02*
X185277D01*
G01Y1076346D02*
X185276Y1076345D01*
X177095D01*
G01X177167Y1093078D02*
X185277D01*
G01X177116Y1089731D02*
X185277D01*
G01Y1106464D02*
X177167D01*
G01X185277Y1103117D02*
X177116D01*
G01X185277Y1126542D02*
X177116D01*
G01X177098Y1116503D02*
X185277D01*
G01X177095Y1113156D02*
X185276D01*
X185277Y1113157D01*
G01Y1143275D02*
X177167D01*
G01X185277Y1139928D02*
X177116D01*
G01X185277Y1129889D02*
X177167D01*
G01X177098Y1153314D02*
X185277D01*
G01Y1149968D02*
X177094D01*
G01X185277Y1176739D02*
X177116D01*
G01X185277Y1166700D02*
X177167D01*
G01X185277Y1163353D02*
X177116D01*
G01X185277Y1180086D02*
X177167D01*
G01X177098Y1190125D02*
X185277D01*
G01Y1186779D02*
X177094D01*
G01X185277Y1203511D02*
X177167D01*
G01X185277Y1200164D02*
X177116D01*
G01X185277Y1216897D02*
X177167D01*
G01X185277Y1213550D02*
X177116D01*
G01X185277Y1226936D02*
X177098D01*
G01X185277Y1223590D02*
X177094D01*
G01X185277Y1240322D02*
X177167D01*
G01X185277Y1236975D02*
X177116D01*
G01X199894Y1250343D02*
X193539D01*
G01X213612Y1059613D02*
X206876D01*
G01X221965Y778482D02*
X222060Y778511D01*
X229817D01*
G01X221965Y771776D02*
X222099Y771817D01*
X229721D01*
G01X221965Y788530D02*
X221985Y788550D01*
X231095D01*
X231119Y788526D01*
G01X221965Y801890D02*
X222115Y801936D01*
X229721D01*
G01X222135Y795208D02*
X222249Y795243D01*
X230893D01*
G01X221990Y791897D02*
X231080D01*
G01X221965Y815289D02*
X221997Y815321D01*
X229721D01*
G01X221965Y808583D02*
X222115Y808629D01*
X229721D01*
G01X221965Y832030D02*
X222043Y832054D01*
X229721D01*
G01X221965Y825311D02*
X222015Y825361D01*
X231095D01*
X231119Y825337D01*
G01X221990Y828708D02*
X231080D01*
G01X221997Y852087D02*
X222043Y852133D01*
X229817D01*
G01X221965Y845384D02*
X222021Y845440D01*
X229817D01*
G01X222078Y838584D02*
X222344D01*
X222877Y838747D01*
X229721D01*
X229979Y838673D01*
G01X221985Y862172D02*
X229847D01*
G01X221965Y865544D02*
X221990Y865519D01*
X231080D01*
X231119Y865558D01*
G01X229721Y882250D02*
X222877D01*
G01Y875558D02*
X229721D01*
G01X222877Y868865D02*
X229546D01*
G01X229648Y888943D02*
X222877D01*
G01X229847Y898983D02*
X222035D01*
G01X229846Y902330D02*
X222935D01*
G01X229944Y912305D02*
X229721Y912369D01*
X222877D01*
X222344Y912206D01*
X222178D01*
G01X229923Y905618D02*
X229721Y905676D01*
X222877D01*
X222344Y905513D01*
X222078D01*
G01X222877Y925754D02*
X229721D01*
G01X222877Y919062D02*
X229721D01*
G01Y949180D02*
X222877D01*
G01Y942487D02*
X229721D01*
G01X220599Y935794D02*
X232157D01*
G01X220599Y939141D02*
X232157D01*
G01X222508Y965912D02*
X230568D01*
G01X236106D02*
X244070D01*
G01X252130D02*
X260438D01*
G01X287973Y967870D02*
X288019Y967889D01*
X288465Y968074D01*
X291258D01*
X293962Y970778D01*
X318910D01*
X326934Y962754D01*
X330224D01*
G01X222349Y982644D02*
X230878D01*
G01X222279Y975951D02*
X230878D01*
G01X222178Y992684D02*
X230878D01*
G01X222178Y989337D02*
X230978D01*
G01X222178Y1029495D02*
X230878D01*
G01X222178Y1026148D02*
X230778D01*
G01X222329Y1046227D02*
X230978D01*
G01X222178Y1042880D02*
X230978D01*
G01X222178Y1036188D02*
X230978D01*
G01X231118Y1059613D02*
X223176D01*
G01X222372Y1052920D02*
X230686D01*
G01X235684Y1056266D02*
X244258D01*
G01X251810D02*
X261240D01*
G01X316557Y1023286D02*
X317524Y1022319D01*
X329957D01*
G01X222281Y1072999D02*
X230878D01*
G01X222966Y1066306D02*
X230978D01*
G01X221965Y1096424D02*
X230978D01*
G01X224077Y1089731D02*
X230978D01*
G01X220616Y1083038D02*
X231278D01*
G01X220616Y1086385D02*
X231278D01*
G01X223091Y1109810D02*
X230878D01*
G01X222040Y1103117D02*
X230978D01*
G01X222245Y1126542D02*
X231078D01*
G01X221965Y1119807D02*
X221968D01*
X222010Y1119849D01*
X231082D01*
G01X221965Y1123233D02*
X222002Y1123196D01*
X231090D01*
G01X222237Y1139928D02*
X230978D01*
G01X222301Y1133235D02*
X230983D01*
G01X222295Y1146621D02*
X230843D01*
G01X221965Y1156618D02*
X221968D01*
X222010Y1156660D01*
X231082D01*
X231119Y1156623D01*
G01X221965Y1160044D02*
X222002Y1160007D01*
X231090D01*
X231119Y1160036D01*
G01X230878Y1176739D02*
X222178D01*
G01Y1170046D02*
X230978D01*
G01X222161Y1163353D02*
X230878D01*
G01X230978Y1183432D02*
X222178D01*
G01X231119Y1193471D02*
X222010D01*
G01X230778Y1206857D02*
X222178D01*
G01X230878Y1200164D02*
X222178D01*
G01X229846Y1196818D02*
X222935D01*
G01X222278Y1220243D02*
X230778D01*
G01X222178Y1213550D02*
X230878D01*
G01X222099Y1236975D02*
X230878D01*
G01X221965Y1230240D02*
X221968D01*
X222010Y1230282D01*
X231082D01*
X231119Y1230245D01*
G01X221965Y1233666D02*
X222002Y1233629D01*
X231090D01*
X231119Y1233658D01*
G01X229594Y1250343D02*
X223239D01*
G01X230778Y1243668D02*
X222278D01*
G01X236567Y771817D02*
X243605D01*
G01X332204Y863371D02*
X330076Y861243D01*
Y850065D01*
X336093Y844048D01*
Y842652D01*
G01X260767Y778510D02*
X252698D01*
G01X333908Y861667D02*
X332476Y860235D01*
Y851065D01*
X336913Y846628D01*
X337824D01*
X341131Y843321D01*
Y842652D01*
G01X260778Y771817D02*
X251703D01*
X251678Y771792D01*
G01X236552Y778515D02*
X236567Y778510D01*
X243604D01*
X243629Y778535D01*
G01X260778Y788550D02*
X251994D01*
X251927Y788483D01*
X251878D01*
G01X235523Y785232D02*
X235551Y785204D01*
X244677D01*
G01X235548Y781857D02*
X244676D01*
X244677Y781858D01*
G01X330549Y871926D02*
X322876Y864253D01*
Y844127D01*
X323433Y843570D01*
Y842652D01*
G01X260518Y798589D02*
X252662D01*
X252439Y798658D01*
G01X235778Y801936D02*
X244478D01*
G01X235678Y795243D02*
X244541D01*
X244677Y795379D01*
G01X260678Y791922D02*
X260652D01*
X260626Y791896D01*
X252035D01*
X251978Y791953D01*
G01X328652Y902823D02*
X318016Y892187D01*
Y883765D01*
X311696Y877445D01*
Y846787D01*
X309285Y844376D01*
G01X260778Y815174D02*
X259817D01*
X259462Y815321D01*
X252698D01*
X252223Y815157D01*
X251578D01*
G01X331523Y899565D02*
X328791D01*
X320416Y891190D01*
Y882769D01*
X314096Y876449D01*
Y842064D01*
X312003Y839971D01*
G01X259846Y808628D02*
X252698D01*
X252529Y808569D01*
G01X235678Y815321D02*
X243559D01*
G01X235778Y808628D02*
X244478D01*
G01X328851Y873624D02*
X320476Y865249D01*
Y850418D01*
X319610Y849552D01*
Y847432D01*
X320476Y846566D01*
Y845775D01*
X318465Y843764D01*
Y843763D01*
X318397Y843695D01*
Y842653D01*
G01X260318Y801936D02*
X252698D01*
X252523Y801875D01*
G01X235523Y818606D02*
X235585Y818668D01*
X244636D01*
X244677Y818627D01*
G01X252218Y832054D02*
X259462D01*
G01X303768Y858208D02*
X304496Y858936D01*
Y880431D01*
X310816Y886751D01*
Y895175D01*
X327446Y911805D01*
X328823D01*
G01X235759Y832054D02*
X244456D01*
G01X260678Y825330D02*
X260647D01*
X260616Y825361D01*
X251915D01*
X251878Y825324D01*
G01X235523Y822073D02*
X235794Y822015D01*
X244619D01*
X244677Y822073D01*
G01X260578Y828785D02*
X260500D01*
X260422Y828707D01*
X252187D01*
X251878Y828743D01*
G01X330524Y919419D02*
X326627D01*
X303774Y896566D01*
G01X303206Y895998D02*
Y893459D01*
X300945Y891198D01*
G01X260422Y845439D02*
X252698D01*
G01X236567Y852132D02*
X243605D01*
G01X235678Y845439D02*
X243559D01*
G01X328824Y914404D02*
X326649D01*
X308416Y896171D01*
Y887747D01*
X302096Y881427D01*
Y865420D01*
X300797Y864121D01*
X297521D01*
G01X260412Y838747D02*
X252698D01*
G01X235811D02*
X244586D01*
G01X235778Y869201D02*
X236265D01*
X236601Y868865D01*
X243559D01*
X243659Y868965D01*
G01X328824Y923131D02*
X326942D01*
X301629Y897818D01*
X301405D01*
X300605Y897018D01*
X300523D01*
G01X260542Y852132D02*
X252698D01*
G01X260778Y862138D02*
X260268D01*
X260234Y862172D01*
X251604D01*
X251578Y862146D01*
G01X235523Y858854D02*
X235551Y858826D01*
X244609D01*
X244642Y858859D01*
X244677D01*
G01X260819Y865548D02*
X260789Y865518D01*
X251703D01*
X251678Y865543D01*
G01X235523Y855458D02*
X235544Y855479D01*
X244602D01*
X244631Y855450D01*
X244677D01*
G01X236609Y875598D02*
X236743Y875558D01*
X243560D01*
G01X244378Y882253D02*
X243463D01*
X243460Y882250D01*
X235878D01*
G01X328824Y933009D02*
X323236D01*
X307983Y917756D01*
X306324D01*
G01X260354Y875558D02*
X252698D01*
G01X251878Y872256D02*
X251923Y872211D01*
X259273D01*
G01X300523Y911394D02*
X305017D01*
X324232Y930609D01*
X328824D01*
G01X244378Y888944D02*
X235878D01*
G01X244677Y895637D02*
X236867D01*
G01X244677Y892291D02*
X244676Y892290D01*
X235801D01*
X235609Y892245D01*
G01X235778Y919062D02*
X244378D01*
G01X244278Y912369D02*
X235778D01*
G01X244378Y905676D02*
X235878D01*
G01X327526Y939804D02*
X320882D01*
X319070Y937992D01*
X317146D01*
G01X259462Y925754D02*
X252698D01*
G01X331524Y937813D02*
X329407D01*
X328998Y937404D01*
X321879D01*
X317257Y932782D01*
X316486D01*
G01X260538Y919062D02*
X251945D01*
G01X235878Y925754D02*
X244378D01*
G01X235035Y932448D02*
X245688D01*
G01X235035Y929101D02*
X245688D01*
G01X323487Y953659D02*
X321624D01*
G01X259462Y942487D02*
X251911D01*
G01X235453Y949180D02*
X244378D01*
G01X235678Y942487D02*
X244378D01*
G01X261880Y935794D02*
X250324D01*
G01Y939140D02*
X261880D01*
G01X328808Y951736D02*
X323586Y956958D01*
Y959734D01*
X322473Y960847D01*
X321624D01*
G01X260490Y949180D02*
X252698D01*
G01X330224Y960245D02*
X326046D01*
X317913Y968378D01*
X295398D01*
X290167Y963147D01*
X288733Y962553D01*
G01X260778Y959219D02*
X251678D01*
G01X244378Y962565D02*
X235986D01*
G01X330224Y969174D02*
X329006D01*
X321402Y976778D01*
X292790D01*
X291921Y977647D01*
G01X259404Y982644D02*
X252439D01*
G01X235878Y979298D02*
X244378D01*
G01X331224Y966610D02*
X328174D01*
X320406Y974378D01*
X287921D01*
X287337Y974962D01*
G01X260306Y975951D02*
X251942D01*
G01X331224Y964026D02*
X327361D01*
X319409Y971978D01*
X292975D01*
X291571Y970574D01*
X287673D01*
X287453Y970483D01*
X287406Y970464D01*
G01X260390Y969258D02*
X252002D01*
G01X235878Y972605D02*
X244278D01*
G01X330325Y981579D02*
X302665D01*
X301508Y982736D01*
G01X235678Y992684D02*
X244478D01*
G01X330461Y975689D02*
X326972Y979178D01*
X297726D01*
X296838Y980066D01*
G01X260778Y989337D02*
X251814D01*
G01X235778Y985991D02*
X244378D01*
G01X235813Y1029495D02*
X244378D01*
G01X328305Y1004831D02*
X322817Y1010319D01*
X294516D01*
X293820Y1010457D01*
X291218Y1011535D01*
X290974Y1011636D01*
X290926Y1011753D01*
G01X260610Y1029495D02*
X251974D01*
G01X327456Y1003982D02*
X322319Y1009119D01*
X293924D01*
X293614Y1008809D01*
X292125D01*
G01X260567Y1025741D02*
X259585Y1026148D01*
X252086D01*
G01X235727Y1042880D02*
X244631D01*
G01X252030Y1039534D02*
X260540D01*
G01X302267Y1015794D02*
X302942Y1015119D01*
X324809D01*
X329037Y1010891D01*
X332225D01*
G01X235778Y1036188D02*
X244478D01*
G01X329853Y1006679D02*
X323813Y1012719D01*
X297120D01*
X295891Y1013948D01*
Y1014047D01*
X295879Y1014059D01*
G01X260256Y1032841D02*
X252046D01*
G01X252068Y1046227D02*
X260526D01*
G01X307374Y1018202D02*
X308057Y1017519D01*
X325805D01*
X329729Y1013595D01*
X334512D01*
G01X329171Y1015851D02*
X326303Y1018719D01*
X310431D01*
X309461Y1019689D01*
G01X260484Y1049573D02*
X252166D01*
G01X244677D02*
X235879D01*
G01X329796Y1018622D02*
X327299Y1021119D01*
X315342D01*
X315025Y1021250D01*
G01X260258Y1052920D02*
X252096D01*
G01X235379Y1059668D02*
X235545Y1059613D01*
X243736D01*
X243739Y1059616D01*
X244677D01*
G01X251891Y1072999D02*
X260631D01*
G01X295596Y1052049D02*
X300979D01*
X323230Y1029798D01*
X325626D01*
G01X328325Y1027396D02*
X322234D01*
X300051Y1049579D01*
X298688D01*
X295894Y1046785D01*
G01X260323Y1069652D02*
X252266D01*
G01X236308Y1069587D02*
X236521Y1069652D01*
X244578D01*
G01X235594Y1066306D02*
X244578D01*
G01X234217Y1079692D02*
X245695D01*
G01X234217Y1076346D02*
X236494D01*
X236495Y1076345D01*
X245695D01*
G01X252698Y1093077D02*
X260648D01*
G01X299586Y1065171D02*
X300229Y1064528D01*
Y1063494D01*
X300864Y1062859D01*
Y1062352D01*
X325144Y1038072D01*
G01X235778Y1093077D02*
X244578D01*
G01X235663Y1089731D02*
X244411D01*
G01X261056Y1083038D02*
X251243D01*
G01X261056Y1086384D02*
X251243D01*
G01X325513Y1041100D02*
X303444Y1063169D01*
X299695Y1072220D01*
X297678Y1074237D01*
G01X259486Y1096424D02*
X252822D01*
G01X252576Y1109783D02*
X252662Y1109810D01*
X259273D01*
X259442Y1109772D01*
G01X290679Y1103175D02*
X291138Y1102716D01*
X291705D01*
X292350Y1103361D01*
X292981D01*
X293678Y1102664D01*
Y1101356D01*
X293348Y1101026D01*
Y1100594D01*
X294835Y1099107D01*
X296852Y1088966D01*
X302447Y1078503D01*
X328312Y1052638D01*
G01X330326Y1045474D02*
X329572D01*
X329095Y1045951D01*
Y1048456D01*
X300491Y1077060D01*
X294566Y1088145D01*
X292839Y1096824D01*
X290757Y1098906D01*
X287819D01*
X287115Y1099610D01*
G01X259569Y1106508D02*
X259462Y1106463D01*
X252698D01*
X252465Y1106544D01*
G01X236367Y1106463D02*
X243559D01*
X243563Y1106459D01*
G01X236642Y1103117D02*
X243654D01*
X243762Y1103139D01*
G01X251981Y1129888D02*
X260819D01*
G01X297443Y1115869D02*
X299603Y1113709D01*
X300219Y1112221D01*
Y1109596D01*
X303868Y1091258D01*
X308439Y1082705D01*
X329709Y1061435D01*
G01X236280Y1126605D02*
X236470Y1126542D01*
X243264D01*
X243627Y1126615D01*
G01X260778Y1119780D02*
X260709Y1119849D01*
X251844D01*
X251778Y1119783D01*
G01X235523Y1116541D02*
X235529D01*
X235567Y1116503D01*
X244597D01*
X244635Y1116541D01*
X244677D01*
G01X260578Y1123223D02*
X260550D01*
X260522Y1123195D01*
X251724D01*
X251653Y1123266D01*
X251578D01*
G01X235546Y1113115D02*
X235588Y1113157D01*
X244609D01*
X244652Y1113114D01*
X244677D01*
G01X333204Y1066530D02*
X331743Y1067991D01*
X313091Y1086639D01*
X309635Y1093097D01*
X306628Y1108159D01*
Y1128685D01*
X306150Y1129163D01*
G01X259512Y1143295D02*
X259462Y1143274D01*
X252698D01*
X252546Y1143327D01*
G01X235881Y1143274D02*
X244631D01*
G01X235727Y1139928D02*
X244478D01*
G01X331407Y1063133D02*
X310387Y1084153D01*
X306155Y1092072D01*
X302619Y1109845D01*
Y1117861D01*
X301027Y1119453D01*
G01X260778Y1133235D02*
X252470D01*
G01X236424Y1129858D02*
X236521Y1129888D01*
X244553D01*
G01X252098Y1149967D02*
X259782D01*
G01X308627Y1138583D02*
X309028Y1138182D01*
Y1108402D01*
X311922Y1093915D01*
X315034Y1088099D01*
X327954Y1075180D01*
G01X260778Y1156660D02*
X252590D01*
X251999Y1156523D01*
X251778D01*
G01X235523Y1153352D02*
X235529D01*
X235567Y1153314D01*
X244597D01*
X244635Y1153352D01*
X244677D01*
G01X260778Y1160006D02*
X252589D01*
X251902Y1160152D01*
X251578D01*
G01X235523Y1149945D02*
X235546Y1149968D01*
X244609D01*
X244652Y1149925D01*
X244677D01*
G01X244478Y1176739D02*
X235678D01*
G01X333055Y1083681D02*
X322836Y1093900D01*
X321068Y1097198D01*
X318628Y1109401D01*
Y1155305D01*
X317304Y1156629D01*
G01X260234Y1170046D02*
X252084D01*
G01X331357Y1081982D02*
X320883Y1092456D01*
X318784Y1096370D01*
X316228Y1109158D01*
Y1150571D01*
X315387Y1151412D01*
G01X260406Y1166699D02*
X252220D01*
G01X235678D02*
X244478D01*
G01X235678Y1163353D02*
X244478D01*
G01X244631Y1180085D02*
X235778D01*
G01X244677Y1190125D02*
X236498D01*
G01X244677Y1186779D02*
X236494D01*
G01X244631Y1203510D02*
X235778D01*
G01X244478Y1200164D02*
X235678D01*
G01X252128Y1220243D02*
X260254D01*
G01X321366Y1168193D02*
X323440Y1166119D01*
X324428Y1163733D01*
Y1110401D01*
X326658Y1099265D01*
X329099Y1096824D01*
G01X327360Y1095086D02*
X324466Y1097980D01*
X322028Y1110150D01*
Y1160404D01*
X319753Y1162679D01*
G01X260422Y1216896D02*
X252108D01*
G01X235578D02*
X244378D01*
G01X235778Y1213550D02*
X244378D01*
G01X235523Y1226974D02*
X235529D01*
X235567Y1226936D01*
X244597D01*
X244635Y1226974D01*
X244677D01*
G01X235523Y1223567D02*
X235546Y1223590D01*
X244609D01*
X244652Y1223547D01*
X244677D01*
G01X335795Y1101427D02*
X335482Y1101740D01*
X334596D01*
X333488Y1102848D01*
X333372Y1103429D01*
X333787Y1104052D01*
X333584Y1105067D01*
X332961Y1105482D01*
X331628Y1112151D01*
Y1170233D01*
X331320Y1171462D01*
X330762Y1171795D01*
X330508Y1172814D01*
X331095Y1173798D01*
X330830Y1174859D01*
X330340Y1175151D01*
X329833Y1175023D01*
X329347Y1175313D01*
X329196Y1175921D01*
X329900Y1177093D01*
X329831Y1177655D01*
X329331Y1178155D01*
G01X260282Y1240321D02*
X252142D01*
G01X244378D02*
X235678D01*
G01X235778Y1236975D02*
X244378D01*
G01X260578Y1230249D02*
X260517D01*
X260484Y1230282D01*
X252162D01*
X252139Y1230259D01*
X251978D01*
G01Y1233686D02*
X252132D01*
X252190Y1233628D01*
X260404D01*
X260426Y1233650D01*
X260478D01*
G01X336361Y1106520D02*
X334962Y1107919D01*
X334028Y1112572D01*
Y1176110D01*
X332880Y1177258D01*
Y1178282D01*
X334057Y1179459D01*
Y1180569D01*
X332901Y1181725D01*
G01X260358Y1243668D02*
X252182D01*
G01X334757Y860818D02*
X333676Y859737D01*
Y851567D01*
X337324Y847919D01*
X339056D01*
X343651Y843324D01*
Y842652D01*
G01X333053Y862522D02*
X331276Y860745D01*
Y850565D01*
X338611Y843230D01*
Y842652D01*
G01X329700Y872775D02*
X321676Y864751D01*
Y844045D01*
X320915Y843284D01*
Y842653D01*
G01X331398Y871077D02*
X324076Y863755D01*
Y847553D01*
X325952Y845677D01*
Y842652D01*
G01X329502Y901974D02*
X319216Y891688D01*
Y883267D01*
X312896Y876947D01*
Y844425D01*
X310223Y841752D01*
G01X331523Y898325D02*
X329249D01*
X321616Y890692D01*
Y882271D01*
X315296Y875951D01*
Y839703D01*
X313784Y838191D01*
G01X328823Y910604D02*
X327943D01*
X312016Y894677D01*
Y886253D01*
X305696Y879933D01*
Y856511D01*
X303457Y854272D01*
G01X303454D02*
X303079Y853897D01*
G01X328824Y921931D02*
X327441D01*
X301926Y896416D01*
Y895760D01*
X300523Y894357D01*
G01X330924Y917819D02*
X326725D01*
X304974Y896068D01*
Y891661D01*
X301853Y888540D01*
G01X328823Y913029D02*
X326972D01*
X309616Y895673D01*
Y887249D01*
X303296Y880929D01*
Y861385D01*
X301423Y859512D01*
G01X328824Y929409D02*
X324730D01*
X304105Y908784D01*
X300523D01*
G01X328824Y931809D02*
X323734D01*
X305835Y913910D01*
X304126D01*
G01X328030Y938604D02*
X321381D01*
X318079Y935302D01*
X317146D01*
G01X316486Y930263D02*
X317241D01*
X318463Y931485D01*
Y932289D01*
X322378Y936204D01*
X329677D01*
X330085Y936612D01*
X331524D01*
G01X328109Y950736D02*
X322668Y956177D01*
Y956183D01*
X321624Y957227D01*
G01X326703Y948745D02*
X324446Y951002D01*
X321724D01*
G01X330224Y961548D02*
X326442D01*
X318412Y969578D01*
X294580D01*
X291420Y966418D01*
X288072Y965029D01*
X288022Y965008D01*
G01X331224Y967821D02*
X328661D01*
X320904Y975578D01*
X290424D01*
X289602Y976400D01*
G01X331224Y965354D02*
X327731D01*
X319907Y973178D01*
X292425D01*
X291898Y972651D01*
X286025D01*
G01X329725Y980378D02*
X300292D01*
X299471Y981199D01*
G01X330349Y970777D02*
X330157Y970969D01*
X328909D01*
X321900Y977978D01*
X295326D01*
X294088Y979216D01*
G01X333477Y1012121D02*
X329505D01*
X325307Y1016319D01*
X305686D01*
X304539Y1017466D01*
G01X331925Y1009671D02*
X328559D01*
X324311Y1013919D01*
X300628D01*
X299117Y1014545D01*
X298235Y1015427D01*
G01X329154Y1005680D02*
X323315Y1011519D01*
X295136D01*
X294547Y1011763D01*
X293540Y1012770D01*
G01X329597Y1017123D02*
X326801Y1019919D01*
X313079D01*
X312589Y1020122D01*
G01X330492Y1029087D02*
X330002Y1028597D01*
X322732D01*
X300510Y1050819D01*
X297172D01*
X296995Y1050642D01*
Y1049912D01*
X296594Y1049511D01*
X295596D01*
G01X328325Y1026195D02*
X321736D01*
X299946Y1047985D01*
X298860D01*
X297834Y1046959D01*
Y1045137D01*
X297688Y1044991D01*
G01X325305Y1039610D02*
X302354Y1062561D01*
X299941Y1068388D01*
X299586Y1068743D01*
G01X330226Y1036518D02*
X329720Y1036619D01*
X324899D01*
X303065Y1058453D01*
X302466D01*
X301929Y1058990D01*
Y1059258D01*
X299586Y1061601D01*
G01X331208Y1047234D02*
X330608D01*
X330322Y1047520D01*
Y1048930D01*
X301465Y1077787D01*
X295709Y1088555D01*
X293841Y1097952D01*
X291557Y1100236D01*
X290057D01*
X288899Y1101394D01*
G01X330426Y1042921D02*
X330072Y1043275D01*
X327071D01*
X326493Y1043853D01*
Y1045221D01*
X326920Y1045648D01*
X327472D01*
X327872Y1046048D01*
Y1047598D01*
X327472Y1047998D01*
X326920D01*
X326184Y1048734D01*
Y1049668D01*
X299516Y1076336D01*
X293423Y1087734D01*
X291828Y1095748D01*
X290152Y1097125D01*
X289223D01*
X288763Y1096665D01*
Y1095262D01*
X288226Y1094725D01*
X287310D01*
X286456Y1095579D01*
Y1096693D01*
X285327Y1097822D01*
G01X330559Y1058885D02*
X307466Y1081978D01*
X302725Y1090847D01*
X299094Y1109094D01*
X298634Y1109554D01*
Y1110799D01*
X299019Y1111184D01*
Y1111954D01*
X298535Y1112438D01*
X297312D01*
G01X332505Y1065530D02*
X331072Y1066963D01*
X312117Y1085915D01*
X308492Y1092687D01*
X305428Y1108040D01*
Y1124958D01*
X305030Y1125356D01*
G01X330558Y1062284D02*
X309413Y1083429D01*
X305010Y1091668D01*
X301419Y1109716D01*
Y1115497D01*
X299245Y1117671D01*
G01X332104Y1069329D02*
X331190Y1070243D01*
X314064Y1087365D01*
X310780Y1093504D01*
X307828Y1108281D01*
Y1133144D01*
X307090Y1133882D01*
Y1134512D01*
G01X332206Y1082831D02*
X321858Y1093179D01*
X319925Y1096789D01*
X317428Y1109277D01*
Y1152933D01*
X316818Y1153543D01*
G01X330501Y1081127D02*
X319918Y1091710D01*
X317637Y1095969D01*
X315028Y1109030D01*
Y1148186D01*
X313595Y1149619D01*
G01X328220Y1095945D02*
X325567Y1098598D01*
X323228Y1110274D01*
Y1162767D01*
X319835Y1166160D01*
G01X326491Y1094216D02*
X323507Y1097200D01*
X323322Y1097547D01*
X320828Y1110028D01*
Y1158043D01*
X317973Y1160898D01*
G01X336733Y1102158D02*
X335956Y1103205D01*
X334120Y1106635D01*
X333774Y1107598D01*
X332828Y1112319D01*
Y1170342D01*
X332256Y1174191D01*
X331177Y1179606D01*
Y1179872D01*
X330875Y1180174D01*
G01X327550Y1176375D02*
X327982Y1175943D01*
Y1175333D01*
X330428Y1169426D01*
Y1112022D01*
X332384Y1102246D01*
X333603Y1101027D01*
G01X537466Y995095D02*
X537854Y995157D01*
X538317Y995230D01*
X540404Y995435D01*
X543935Y995959D01*
X551644Y997494D01*
X552966Y997826D01*
X559724Y1000626D01*
X570231Y1011133D01*
X571817D01*
G01X532709Y991986D02*
X536223Y993446D01*
X539190Y994036D01*
X543687Y994478D01*
X553616Y996455D01*
X559821Y999025D01*
X569411Y1008615D01*
X571525D01*
G01X539725Y987566D02*
X545579D01*
X546056Y987089D01*
X552701D01*
X559402Y980388D01*
X578331D01*
X579181Y981238D01*
G01X546325Y985620D02*
X552370D01*
X558802Y979188D01*
X580710D01*
X581521Y979999D01*
G01X621387Y992886D02*
X621589Y992684D01*
X627967D01*
G01X548870Y886296D02*
X550028Y885138D01*
Y847587D01*
X548285Y845844D01*
G01X621403Y771817D02*
X629164D01*
X629227Y771880D01*
G01X552416Y892242D02*
X553628Y891030D01*
Y841665D01*
X552470Y838867D01*
X551587Y837984D01*
G01X550109Y887534D02*
X551228Y886415D01*
Y845170D01*
X550065Y844007D01*
G01X551411Y891237D02*
X552428Y890220D01*
Y842437D01*
X552031Y842040D01*
G01X622376Y778510D02*
X629164D01*
X629227Y778573D01*
G01X621246Y785286D02*
X621329Y785203D01*
X629158D01*
X629227Y785272D01*
G01X621247Y781802D02*
X621302Y781857D01*
X629098D01*
X629181Y781774D01*
G01X552124Y914518D02*
X569028Y897614D01*
Y847963D01*
X570333Y846658D01*
G01X554360Y908886D02*
X566628Y896618D01*
Y843022D01*
X567812Y841838D01*
G01X555209Y909735D02*
X567828Y897116D01*
Y845455D01*
X568822Y844461D01*
G01X621403Y815321D02*
X629164D01*
X629227Y815384D01*
G01X553511Y908037D02*
X565428Y896120D01*
Y840514D01*
X565958Y839984D01*
G01X621403Y808628D02*
X629164D01*
X629227Y808691D01*
G01X556969Y901393D02*
X563228Y895134D01*
Y839144D01*
G01X563670Y833105D02*
X564218Y832557D01*
G01X553620Y901346D02*
X560828Y894138D01*
Y828651D01*
X563537Y825942D01*
Y825348D01*
G01X556183Y900481D02*
X562028Y894636D01*
Y832442D01*
X563313Y829338D01*
X565060Y827591D01*
G01X621403Y801936D02*
X629164D01*
X629227Y801999D01*
G01X554422Y898846D02*
X559628Y893640D01*
Y827318D01*
X560815Y826131D01*
Y825348D01*
G01X621403Y795243D02*
X629164D01*
X629227Y795306D01*
G01X622750Y822014D02*
X629141D01*
X629198Y822071D01*
G01X622243Y818668D02*
X626480D01*
G01X628055D02*
X629190D01*
X629211Y818647D01*
X629227D01*
G01X555524Y927909D02*
X557337D01*
X582028Y903218D01*
Y888055D01*
X583475Y886608D01*
Y886607D01*
X584179Y885903D01*
G01X555524Y926709D02*
X556839D01*
X580828Y902720D01*
Y881190D01*
X581704Y880314D01*
Y879248D01*
G01X621246Y845513D02*
X621320Y845439D01*
X629187D01*
X629227Y845479D01*
G01X552524Y924584D02*
X555644D01*
X578628Y901600D01*
Y871038D01*
X580070Y869596D01*
X580071D01*
G01X552524Y922087D02*
X554745D01*
X576228Y900604D01*
Y861240D01*
X577872Y859596D01*
G01X552524Y923321D02*
X555209D01*
X577428Y901102D01*
Y865701D01*
X578218Y864911D01*
X578923D01*
G01X621246Y838828D02*
X621327Y838747D01*
X629130D01*
X629153Y838770D01*
X629227D01*
G01X552524Y920887D02*
X554247D01*
X575028Y900106D01*
Y858758D01*
X578287Y855499D01*
G01X621255Y832054D02*
X629134D01*
X629193Y832113D01*
X629227D01*
G01X552517Y945343D02*
X555750Y942110D01*
X563437D01*
X582732Y922815D01*
X582999D01*
X583745Y922069D01*
G01X621312Y919062D02*
X629171D01*
G01X554924Y938709D02*
X561825D01*
X592104Y908430D01*
X595023D01*
G01X621246Y875612D02*
X621300Y875558D01*
X629193D01*
X629227Y875592D01*
G01X554924Y936309D02*
X560823D01*
X590829Y906303D01*
Y904624D01*
X592374Y903079D01*
X595423D01*
G01X621246Y868917D02*
X621298Y868865D01*
X629188D01*
X629227Y868904D01*
G01X555524Y930309D02*
X558333D01*
X584428Y904214D01*
Y893239D01*
X587971Y889696D01*
G01X555524Y929109D02*
X557835D01*
X583228Y903716D01*
Y890465D01*
X585984Y887709D01*
G01X621246Y852133D02*
X629227D01*
G01X556224Y939909D02*
X562324D01*
X590627Y911606D01*
X595024D01*
G01X554924Y937509D02*
X561321D01*
X592960Y905874D01*
X593169Y905665D01*
X595423D01*
G01X621306Y858825D02*
X629227D01*
G01X621246Y855415D02*
X621310Y855479D01*
X628700D01*
G01X553813Y949237D02*
X557340Y945710D01*
X564931D01*
X580907Y929734D01*
X582524D01*
G01X552108Y947534D02*
X556332Y943310D01*
X563935D01*
X582635Y924610D01*
X583724D01*
G01X552957Y948383D02*
X556830Y944510D01*
X564433D01*
X581800Y927143D01*
X583724D01*
G01X621281Y922408D02*
X629167D01*
G01X551762Y963544D02*
X552402D01*
X560632Y955314D01*
X568915D01*
X574654Y949575D01*
X576124D01*
G01X551824Y959500D02*
X553050D01*
X559636Y952914D01*
X567919D01*
X576470Y944363D01*
X580024D01*
G01X551824Y960700D02*
X553548D01*
X560134Y954114D01*
X568417D01*
X575592Y946939D01*
X578624D01*
G01X621345Y945833D02*
X629100D01*
G01X551824Y958300D02*
X552552D01*
X559138Y951714D01*
X567421D01*
X577380Y941755D01*
X580024D01*
G01X621246Y939140D02*
X629107D01*
X629170Y939077D01*
G01X621474Y932447D02*
X629156D01*
G01X621273Y929101D02*
X629115D01*
G01X557733Y978557D02*
X558302Y977988D01*
X583071D01*
X585121Y980038D01*
G01X557325Y977265D02*
X557802Y976788D01*
X585074D01*
G01X621321Y985991D02*
X629028D01*
X629070Y986033D01*
G01X556484Y976406D02*
X557302Y975588D01*
X578868D01*
X579189Y975267D01*
G01X555110Y975248D02*
X555970Y974388D01*
X576492D01*
X577001Y973879D01*
G01X621319Y979392D02*
X621413Y979298D01*
X628997D01*
X629070Y979371D01*
G01X554225Y974033D02*
X555070Y973188D01*
X574096D01*
X575203Y972081D01*
G01X643924Y969258D02*
X637485D01*
X637388Y969355D01*
G01X629015Y968913D02*
X628670Y969258D01*
X621549D01*
X621470Y969179D01*
G01X570577Y969457D02*
X569246Y970788D01*
X552425D01*
G01X658790Y962528D02*
X658753Y962565D01*
X650205D01*
G01X645369Y965815D02*
X645272Y965912D01*
X637455D01*
X637408Y965865D01*
G01X629151Y959219D02*
X620455D01*
G01X567099Y965199D02*
X563910Y968388D01*
X552424D01*
G01X568987Y967467D02*
X566866Y969588D01*
X552425D01*
G01X629051Y955975D02*
X628949Y955873D01*
X620497D01*
G01X563511Y965199D02*
X561522Y967188D01*
X552424D01*
G01X554225Y971988D02*
X571706D01*
X573008Y970686D01*
G01X621370Y972654D02*
X621419Y972605D01*
X628974D01*
X629051Y972682D01*
G01X585185Y1016383D02*
X584777Y1015975D01*
X571677D01*
X558564Y1002862D01*
X554961Y1001369D01*
X554625D01*
G01X552825Y999131D02*
X559153Y1001753D01*
X571051Y1013651D01*
X571817D01*
G01X621295Y1029454D02*
X621336Y1029495D01*
X628813D01*
X629227Y1029081D01*
G01X550825Y1006228D02*
X551247D01*
X552054Y1007035D01*
X552909D01*
X553486Y1006458D01*
X554052D01*
X554652Y1007058D01*
X555200D01*
X556511Y1007601D01*
X570256Y1021346D01*
X572712D01*
X576151Y1022030D01*
X576493Y1022372D01*
G01X552325Y1005027D02*
X554024D01*
X556775Y1006167D01*
X570491Y1019883D01*
X578001D01*
X579334Y1021216D01*
G01X621246Y1042813D02*
X621313Y1042880D01*
X628970D01*
X629027Y1042823D01*
G01X552325Y1003827D02*
X554507D01*
X557283Y1004977D01*
X570989Y1018683D01*
X580362D01*
X581898Y1020219D01*
G01X552325Y1002627D02*
X554749D01*
X557963Y1003959D01*
X571487Y1017483D01*
X582724D01*
X583576Y1018335D01*
G01X621227Y1036124D02*
X621291Y1036188D01*
X629143D01*
X629227Y1036104D01*
G01X645151Y1056313D02*
X645104Y1056266D01*
X637609D01*
X637570Y1056305D01*
G01X629221Y1056194D02*
X629149Y1056266D01*
X621285D01*
X621246Y1056227D01*
G01X570146Y1030613D02*
X569621Y1030088D01*
X567794Y1025677D01*
X555100Y1012983D01*
X551125D01*
G01X657042Y1052920D02*
X651098D01*
X651070Y1052948D01*
G01X644957Y1052821D02*
X644858Y1052920D01*
X637723D01*
X637670Y1052867D01*
G01X627585Y1052920D02*
X621305D01*
X621246Y1052979D01*
G01X572834Y1026082D02*
X572470Y1025718D01*
X570356Y1024842D01*
X555905Y1010391D01*
X551125D01*
G01X571976Y1028846D02*
X570853Y1027723D01*
X570367Y1026551D01*
X555545Y1011729D01*
X551125D01*
G01X629227Y1049501D02*
X629155Y1049573D01*
X621297D01*
X621246Y1049522D01*
G01X574958Y1024509D02*
X574389Y1023940D01*
X570348Y1023136D01*
X555971Y1008759D01*
X551125D01*
G01X552109Y1034869D02*
X588541Y1071301D01*
X592510Y1091142D01*
X594842Y1093474D01*
X595728D01*
G01X553819Y1033183D02*
X590758Y1070122D01*
X593777Y1085226D01*
X595402Y1086308D01*
X595753Y1088059D01*
X596757Y1088728D01*
X598508Y1088377D01*
X599828D01*
G01X552955Y1034017D02*
X589650Y1070712D01*
X593039Y1087663D01*
X594345Y1089621D01*
X596596Y1090997D01*
X599828D01*
G01X621357Y1093077D02*
X629097D01*
G01X554704Y1032370D02*
X591751Y1069417D01*
X591895Y1069687D01*
X594527Y1082851D01*
X597472Y1085796D01*
X599827D01*
G01X621333Y1086384D02*
X629162D01*
G01X555971Y1025144D02*
X597497Y1066670D01*
X598639Y1072390D01*
X599311Y1073062D01*
G01X557698Y1023475D02*
X592858Y1058635D01*
X594926D01*
G01X556849Y1024324D02*
X599726Y1067201D01*
G01X620864Y1069652D02*
X629159D01*
G01X558497Y1022576D02*
X591419Y1055498D01*
X594776D01*
G01X621217Y1066306D02*
X629204D01*
G01X621246Y1079691D02*
X629145D01*
G01X621246Y1076344D02*
X621247Y1076345D01*
X629141D01*
G01X550899Y1052075D02*
X576196Y1077372D01*
X582573Y1109237D01*
Y1111054D01*
X584335Y1115750D01*
X585280Y1116695D01*
G01X553098Y1052576D02*
X577304Y1076782D01*
X584236Y1111429D01*
X585550Y1113403D01*
X587061Y1114914D01*
G01X621246Y1126676D02*
X621380Y1126542D01*
X629158D01*
X629227Y1126611D01*
G01X550917Y1041759D02*
X582866Y1073708D01*
X588376Y1101243D01*
X590185Y1102726D01*
X592627Y1105168D01*
G01X554865Y1042310D02*
X585079Y1072524D01*
X589406Y1094153D01*
X590875Y1095622D01*
Y1097122D01*
X591395Y1097642D01*
X592331D01*
X593282Y1098593D01*
G01X554015Y1043159D02*
X583973Y1073117D01*
X589129Y1098885D01*
X591365Y1101121D01*
X592163D01*
X592628Y1101586D01*
G01X621278Y1109845D02*
X621298D01*
X621333Y1109810D01*
X629178D01*
X629227Y1109859D01*
G01X555714Y1041460D02*
X586186Y1071932D01*
X590352Y1092762D01*
X594169Y1095890D01*
X595677Y1097398D01*
G01X621297Y1103117D02*
X629040D01*
X629167Y1103244D01*
X629227D01*
G01X621227Y1116609D02*
X621334Y1116502D01*
X629156D01*
X629227Y1116573D01*
G01X621253Y1113129D02*
X621280Y1113156D01*
X629137D01*
X629218Y1113075D01*
G01X553440Y1066434D02*
X568655Y1081643D01*
X572940Y1103086D01*
Y1133482D01*
X573527Y1134069D01*
G01X554341Y1063933D02*
X570868Y1080460D01*
X575340Y1102813D01*
Y1122579D01*
X577518Y1124757D01*
G01X554292Y1065582D02*
X569761Y1081051D01*
X574140Y1102947D01*
Y1127685D01*
X574272Y1127817D01*
Y1131253D01*
X574727Y1131708D01*
G01X621996Y1146621D02*
X629148D01*
X629227Y1146700D01*
G01X555191Y1063084D02*
X571975Y1079868D01*
X576540Y1102691D01*
Y1120122D01*
X579346Y1122928D01*
G01X621246Y1140075D02*
X621393Y1139928D01*
X629117D01*
X629227Y1140038D01*
G01X549201Y1053773D02*
X573984Y1078556D01*
X580128Y1109272D01*
Y1118773D01*
X581665Y1120310D01*
G01X550050Y1052924D02*
X575090Y1077964D01*
X581373Y1109374D01*
Y1111657D01*
X582535Y1117618D01*
X583446Y1118529D01*
G01X621246Y1133336D02*
X621347Y1133235D01*
X629174D01*
X629227Y1133288D01*
G01X621252Y1153364D02*
X621302Y1153314D01*
X629019D01*
G01X621247Y1149914D02*
X621300Y1149967D01*
X629134D01*
X629217Y1149884D01*
G01X553836Y1080438D02*
X559727Y1086329D01*
X563325Y1104347D01*
Y1143228D01*
X564836Y1150820D01*
X565697Y1151679D01*
G01X551985Y1075191D02*
X561942Y1085148D01*
X565725Y1104072D01*
Y1140549D01*
X568457Y1147147D01*
X569443Y1148133D01*
G01X554685Y1079589D02*
X560833Y1085737D01*
X564525Y1104193D01*
Y1140935D01*
X564784Y1142235D01*
X566920Y1149280D01*
X567608Y1149968D01*
G01X621246Y1170046D02*
X628596D01*
X629010Y1170189D01*
X629227D01*
G01X556384Y1077890D02*
X563051Y1084557D01*
X566925Y1103949D01*
Y1139732D01*
X568456Y1143428D01*
X571302Y1146274D01*
G01X621380Y1163353D02*
X629227D01*
G01X551641Y1083333D02*
X556580Y1088272D01*
X559764Y1104177D01*
Y1143793D01*
X562137Y1155727D01*
G01X562765Y1157243D02*
X564312Y1158790D01*
G01X552492Y1082482D02*
X557687Y1087677D01*
X560964Y1104049D01*
Y1143059D01*
X562973Y1153150D01*
X563823Y1154740D01*
X564679Y1155596D01*
G01X621246Y1213576D02*
X621272Y1213550D01*
X629201D01*
X629227Y1213576D01*
G01X550144Y1106549D02*
Y1167166D01*
X551671Y1168693D01*
Y1170582D01*
G01X551344Y1106549D02*
Y1166232D01*
X554193Y1169081D01*
Y1170582D01*
G01X621246Y1237040D02*
X621311Y1236975D01*
X628439D01*
G01X550884Y1085992D02*
X554370Y1089478D01*
X557364Y1104436D01*
Y1145747D01*
X557454Y1146789D01*
X559369Y1157764D01*
X560785Y1161957D01*
X561317Y1162982D01*
X561959Y1163624D01*
G01X551737Y1085139D02*
X555476Y1088878D01*
X558564Y1104308D01*
Y1144500D01*
X561469Y1159118D01*
X561921Y1159963D01*
X562530Y1160572D01*
G01X621470Y1216873D02*
X621493Y1216896D01*
X629031D01*
X629051Y1216876D01*
G01X621246Y1226962D02*
X621272Y1226936D01*
X629207D01*
X629227Y1226956D01*
G01X621247Y1223569D02*
X621267Y1223589D01*
X626480D01*
G01X628055D02*
X629190D01*
X629211Y1223568D01*
X629227D01*
G01X547744Y1106549D02*
Y1166371D01*
X547379Y1166736D01*
Y1168572D01*
X546558Y1169393D01*
G01X548944Y1106549D02*
Y1168026D01*
G01X549145Y1168227D02*
Y1170582D01*
G01X622271Y1243668D02*
X628687D01*
G01X645369Y778448D02*
X645306Y778511D01*
X637545D01*
G01X645369Y771755D02*
X645306Y771818D01*
X637545D01*
G01X645369Y788518D02*
X645337Y788550D01*
X637440D01*
X637388Y788498D01*
G01X645369Y795180D02*
X645306Y795243D01*
X637545D01*
G01X645369Y791937D02*
X645329Y791897D01*
X637457D01*
X637382Y791972D01*
G01X645369Y815258D02*
X645306Y815321D01*
X637545D01*
G01X645369Y808565D02*
X645306Y808628D01*
X637545D01*
G01X645369Y801873D02*
X645306Y801936D01*
X637545D01*
G01X645369Y831996D02*
X645311Y832054D01*
X637649D01*
X637588Y831993D01*
X637388D01*
G01X645346Y825320D02*
X645305Y825361D01*
X637503D01*
X637388Y825246D01*
G01X645350Y828783D02*
X645275Y828708D01*
X637457D01*
X637395Y828770D01*
G01X645266Y845420D02*
X645246Y845440D01*
X637499D01*
G01X645369Y838689D02*
X645311Y838747D01*
X637440D01*
X637388Y838695D01*
G01X645301Y852133D02*
X637552D01*
X637498Y852079D01*
G01X645369Y862106D02*
X645303Y862172D01*
X637475D01*
X637369Y862066D01*
G01X645369Y865583D02*
X645305Y865519D01*
X637482D01*
X637431Y865570D01*
X637411D01*
G01X645369Y882226D02*
X645344Y882251D01*
X636727D01*
G01X645249Y875558D02*
X637426D01*
X637388Y875520D01*
G01X645249Y868865D02*
X637422D01*
X637388Y868831D01*
G01X645369Y888919D02*
X645344Y888944D01*
X636833D01*
G01X645295Y898888D02*
X645200Y898983D01*
X636641D01*
G01X645369Y902404D02*
X645295Y902330D01*
X636646D01*
G01X645344Y912369D02*
X636833D01*
G01X645369Y905651D02*
X645344Y905676D01*
X636727D01*
G01X645325Y925755D02*
X637509D01*
G01X645186Y919062D02*
X637440D01*
G01X645296Y942487D02*
X637482D01*
G01X645287Y935794D02*
X637454D01*
G01X645297Y939141D02*
X637464D01*
G01X644588Y949180D02*
X637452D01*
G01X645369Y982720D02*
X645293Y982644D01*
X637472D01*
X637388Y982728D01*
G01X645369Y975989D02*
X645331Y975951D01*
X637444D01*
X637388Y976007D01*
G01X644955Y992684D02*
X638126D01*
X637388Y993422D01*
G01X645369Y989391D02*
X645315Y989337D01*
X637440D01*
X637388Y989389D01*
G01X645369Y1029560D02*
X645304Y1029495D01*
X637652D01*
X637499Y1029648D01*
X637388D01*
G01X645228Y1025694D02*
X644774Y1026148D01*
X638007D01*
X637553Y1025694D01*
G01X645366Y1049619D02*
X645320Y1049573D01*
X637451D01*
X637388Y1049636D01*
G01X645369Y1042919D02*
X645330Y1042880D01*
X637436D01*
X637369Y1042947D01*
G01X645369Y1036304D02*
X645253Y1036188D01*
X637456D01*
X637369Y1036275D01*
G01X644653Y1059613D02*
X637492D01*
G01X644684Y1072999D02*
X637424D01*
G01X645289Y1066306D02*
X637699D01*
G01X645320Y1089731D02*
X637417D01*
G01X645243Y1083038D02*
X637450D01*
G01X645136Y1086385D02*
X637432D01*
G01X645069Y1096022D02*
X644667Y1096424D01*
X637433D01*
G01X645369Y1109734D02*
X645293Y1109810D01*
X637425D01*
X637388Y1109773D01*
G01X645369Y1106502D02*
X645330Y1106463D01*
X637446D01*
X637375Y1106534D01*
G01X645369Y1126475D02*
X645302Y1126542D01*
X637432D01*
X637388Y1126498D01*
G01X645369Y1119823D02*
X645343Y1119849D01*
X637450D01*
X637388Y1119787D01*
G01X645369Y1123269D02*
X645296Y1123196D01*
X637434D01*
X637388Y1123242D01*
G01X645334Y1139928D02*
X640599D01*
G01X645330Y1133264D02*
X645301Y1133235D01*
X640599D01*
G01X645353Y1146621D02*
X640599D01*
G01X645369Y1156634D02*
X645343Y1156660D01*
X637450D01*
X637388Y1156598D01*
G01X645369Y1160080D02*
X645296Y1160007D01*
X637434D01*
X637388Y1160053D01*
G01X642183Y1170046D02*
X637467D01*
X637438Y1170017D01*
G01X642183Y1163353D02*
X637467D01*
X637438Y1163324D01*
G01X645369Y1183407D02*
X645344Y1183432D01*
X636833D01*
G01X645369Y1176714D02*
X645344Y1176739D01*
X636727D01*
G01X645369Y1193406D02*
X645304Y1193471D01*
X637388D01*
G01X645369Y1206819D02*
X645331Y1206857D01*
X637388D01*
G01X645369Y1200129D02*
X645334Y1200164D01*
X637388D01*
G01X645322Y1196863D02*
X645277Y1196818D01*
X637388D01*
G01X645369Y1220205D02*
X645331Y1220243D01*
X637431D01*
X637388Y1220200D01*
G01X645369Y1213528D02*
X645347Y1213550D01*
X637410D01*
X637388Y1213528D01*
G01X645369Y1236936D02*
X645330Y1236975D01*
X637423D01*
X637388Y1236940D01*
G01X645369Y1230259D02*
X645346Y1230282D01*
X637503D01*
X637388Y1230167D01*
G01X645369Y1233648D02*
X645350Y1233629D01*
X637388D01*
G01X638157Y1250358D02*
X644617D01*
G01X644341Y1243668D02*
X637735D01*
X637588Y1243521D01*
X637388D01*
G01X658927Y771880D02*
X658864Y771817D01*
X651103D01*
G01X658927Y778573D02*
X658864Y778510D01*
X651103D01*
G01X658927Y785247D02*
X658884Y785204D01*
X650970D01*
X650946Y785228D01*
G01X658927Y781828D02*
X658898Y781857D01*
X650974D01*
X650946Y781829D01*
G01X658927Y801999D02*
X658864Y801936D01*
X651103D01*
G01X658927Y795306D02*
X658864Y795243D01*
X651103D01*
G01X658927Y815384D02*
X658864Y815321D01*
X651103D01*
G01X658927Y808691D02*
X658864Y808628D01*
X651103D01*
G01X658927Y818642D02*
X658901Y818668D01*
X651109D01*
X651029Y818588D01*
X651009D01*
G01X658927Y832117D02*
X658864Y832054D01*
X651103D01*
G01X658927Y822053D02*
X658888Y822014D01*
X657678D01*
G01X656106D02*
X651448D01*
G01X658837Y852186D02*
X658783Y852132D01*
X651008D01*
X650943Y852197D01*
G01X658927Y845502D02*
X658864Y845439D01*
X651103D01*
G01X658927Y838810D02*
X658864Y838747D01*
X651103D01*
G01X658724Y868865D02*
X651024D01*
X650967Y868922D01*
G01X658927Y858869D02*
X658884Y858826D01*
X650970D01*
X650946Y858850D01*
G01X658927Y855450D02*
X658898Y855479D01*
X650974D01*
X650946Y855451D01*
G01X658724Y875558D02*
X651024D01*
X650967Y875615D01*
G01X658724Y882250D02*
X651024D01*
X650967Y882307D01*
G01X658724Y888943D02*
X651024D01*
X650967Y889000D01*
G01X658927Y895680D02*
X658884Y895637D01*
X650970D01*
X650946Y895661D01*
G01X658927Y892261D02*
X658898Y892290D01*
X650974D01*
X650946Y892262D01*
G01X658823Y919062D02*
X651082D01*
G01X658927Y912420D02*
X658876Y912369D01*
X651051D01*
X650992Y912428D01*
G01X658927Y905767D02*
X658836Y905676D01*
X651051D01*
X650996Y905731D01*
G01X658883Y925755D02*
X651051D01*
G01X658884Y932448D02*
X650970D01*
G01X658898Y929101D02*
X650974D01*
G01X658927Y945762D02*
X658855Y945834D01*
X651056D01*
G01X658847Y942487D02*
X651034D01*
G01X658927Y979391D02*
X658834Y979298D01*
X651035D01*
X651003Y979330D01*
G01X658927Y972655D02*
X658877Y972605D01*
X651058D01*
X650996Y972667D01*
G01X658927Y992736D02*
X658875Y992684D01*
X651056D01*
X650979Y992761D01*
G01X658927Y986041D02*
X658877Y985991D01*
X651033D01*
X650996Y986028D01*
G01X658927Y1032905D02*
X658863Y1032841D01*
X651009D01*
X650947Y1032903D01*
G01X658927Y1046312D02*
X658842Y1046227D01*
X651530D01*
G01X658927Y1039611D02*
X658850Y1039534D01*
X651051D01*
X650996Y1039589D01*
G01X650797Y1059613D02*
X658867D01*
G01X658878Y1072999D02*
X651056D01*
G01X658629Y1066306D02*
X651111D01*
G01X658884Y1079692D02*
X650970D01*
G01X658898Y1076345D02*
X650974D01*
G01X658765Y1093078D02*
X651032D01*
G01X658512Y1089731D02*
X651064D01*
G01X658927Y1109839D02*
X658898Y1109810D01*
X651031D01*
X650996Y1109845D01*
G01X658927Y1103149D02*
X658895Y1103117D01*
X651028D01*
X650996Y1103149D01*
G01X655741Y1126542D02*
X651025D01*
X650996Y1126571D01*
G01X658927Y1116546D02*
X658884Y1116503D01*
X650970D01*
X650946Y1116527D01*
G01X658927Y1113127D02*
X658898Y1113156D01*
X650974D01*
X650946Y1113128D01*
G01X655741Y1146621D02*
X651025D01*
X650996Y1146650D01*
G01X655741Y1139928D02*
X651025D01*
X650996Y1139957D01*
G01X655741Y1133235D02*
X651025D01*
X650996Y1133264D01*
G01X658927Y1153357D02*
X658884Y1153314D01*
X650970D01*
X650946Y1153338D01*
G01X658927Y1149939D02*
X658898Y1149968D01*
X650974D01*
X650946Y1149940D01*
G01X655741Y1176739D02*
X651025D01*
X650996Y1176768D01*
G01X655741Y1170046D02*
X651025D01*
X650996Y1170075D01*
G01X655741Y1163353D02*
X651025D01*
X650996Y1163382D01*
G01X656500Y1183432D02*
X651018D01*
X650996Y1183454D01*
G01X658927Y1190145D02*
X658907Y1190125D01*
X650966D01*
X650946Y1190145D01*
G01X658927Y1186759D02*
X658907Y1186779D01*
X650966D01*
X650946Y1186759D01*
G01X656376Y1206857D02*
X651032D01*
X650996Y1206893D01*
G01X655731Y1200164D02*
X651038D01*
X650996Y1200206D01*
G01X656077Y1220243D02*
X651182D01*
X651091Y1220269D01*
X651030D01*
G01X656754Y1213550D02*
X651016D01*
X650996Y1213570D01*
G01X658927Y1226975D02*
X658888Y1226936D01*
X657678D01*
G01X656106D02*
X651057D01*
G01X658927Y1223564D02*
X658901Y1223590D01*
X651108D01*
X651065Y1223547D01*
X651045D01*
G01X658489Y1243668D02*
X651239D01*
G01X658813Y1236975D02*
X651035D01*
X650996Y1237014D01*
G01X667857Y1253705D02*
X674137D01*
G01X680747Y1059613D02*
X688627D01*
G01X704769Y778486D02*
X704744Y778511D01*
X696233D01*
G01X704769Y771793D02*
X704744Y771818D01*
X696127D01*
G01X696167Y788550D02*
X704748D01*
X704769Y788529D01*
G01Y801911D02*
X704744Y801936D01*
X696233D01*
G01X704769Y795218D02*
X704744Y795243D01*
X696127D01*
G01X696252Y791897D02*
X704745D01*
X704769Y791921D01*
G01Y815297D02*
X704744Y815322D01*
X696233D01*
G01X704769Y808604D02*
X704744Y808629D01*
X696127D01*
G01X704769Y832029D02*
X704744Y832054D01*
X696127D01*
G01X696167Y825361D02*
X704748D01*
X704769Y825340D01*
G01X696252Y828708D02*
X704745D01*
X704769Y828732D01*
G01Y852108D02*
X704744Y852133D01*
X696233D01*
G01X704769Y845415D02*
X704744Y845440D01*
X696127D01*
G01X704769Y838722D02*
X704744Y838747D01*
X696233D01*
G01X696167Y862172D02*
X704748D01*
X704769Y862151D01*
G01X696252Y865519D02*
X704745D01*
X704769Y865543D01*
G01Y882226D02*
X704744Y882251D01*
X696127D01*
G01X704769Y875533D02*
X704744Y875558D01*
X696233D01*
G01X704769Y868840D02*
X704744Y868865D01*
X696127D01*
G01X704769Y888919D02*
X704744Y888944D01*
X696233D01*
G01X696167Y898983D02*
X704748D01*
X704769Y898962D01*
G01X696252Y902330D02*
X704745D01*
X704769Y902354D01*
G01Y912344D02*
X704744Y912369D01*
X696233D01*
G01X704769Y905651D02*
X704744Y905676D01*
X696127D01*
G01X704769Y925730D02*
X704744Y925755D01*
X696233D01*
G01X704769Y919037D02*
X704744Y919062D01*
X696127D01*
G01X704769Y949155D02*
X704744Y949180D01*
X696233D01*
G01X704769Y942462D02*
X704744Y942487D01*
X696127D01*
G01X696167Y935794D02*
X704748D01*
X704769Y935773D01*
G01X696252Y939141D02*
X704745D01*
X704769Y939165D01*
G01X696167Y982644D02*
X704720D01*
X704769Y982693D01*
G01X696167Y975951D02*
X704720D01*
X704769Y976000D01*
G01X696167Y989337D02*
X704720D01*
X704769Y989386D01*
G01X696167Y1029495D02*
X704720D01*
X704769Y1029544D01*
G01X696157Y1019456D02*
X704720D01*
X704769Y1019505D01*
G01X696167Y1049573D02*
X704720D01*
X704769Y1049622D01*
G01X695801Y1042880D02*
X704720D01*
X704769Y1042929D01*
G01Y1036237D02*
X704720Y1036188D01*
X695844D01*
G01X696788Y1059556D02*
X696845Y1059613D01*
X704744D01*
X704769Y1059588D01*
G01Y1072974D02*
X704744Y1072999D01*
X696233D01*
G01X704769Y1066281D02*
X704744Y1066306D01*
X696127D01*
G01X704769Y1089706D02*
X704744Y1089731D01*
X696127D01*
G01X696167Y1083038D02*
X704748D01*
X704769Y1083017D01*
G01X696252Y1086385D02*
X704745D01*
X704769Y1086409D01*
G01Y1096399D02*
X704744Y1096424D01*
X696233D01*
G01X704769Y1109785D02*
X704744Y1109810D01*
X696233D01*
G01X704769Y1103092D02*
X704744Y1103117D01*
X696127D01*
G01X704769Y1126517D02*
X704744Y1126542D01*
X696127D01*
G01X696167Y1119849D02*
X704748D01*
X704769Y1119828D01*
G01X696252Y1123196D02*
X704745D01*
X704769Y1123220D01*
G01Y1139903D02*
X704744Y1139928D01*
X696127D01*
G01X704769Y1133210D02*
X704744Y1133235D01*
X696233D01*
G01X704769Y1146596D02*
X704744Y1146621D01*
X696233D01*
G01X696167Y1156660D02*
X704748D01*
X704769Y1156639D01*
G01X696252Y1160007D02*
X704745D01*
X704769Y1160031D01*
G01Y1176714D02*
X704744Y1176739D01*
X696127D01*
G01X704769Y1170021D02*
X704744Y1170046D01*
X696233D01*
G01X704769Y1163328D02*
X704744Y1163353D01*
X696127D01*
G01X704769Y1183407D02*
X704744Y1183432D01*
X696233D01*
G01X696167Y1193471D02*
X704748D01*
X704769Y1193450D01*
G01Y1206832D02*
X704744Y1206857D01*
X696233D01*
G01X704769Y1200139D02*
X704744Y1200164D01*
X696127D01*
G01X696252Y1196818D02*
X704745D01*
X704769Y1196842D01*
G01Y1220218D02*
X704744Y1220243D01*
X696233D01*
G01X704769Y1213525D02*
X704744Y1213550D01*
X696127D01*
G01X704769Y1236950D02*
X704744Y1236975D01*
X696127D01*
G01X696167Y1230282D02*
X704748D01*
X704769Y1230261D01*
G01X696252Y1233629D02*
X704745D01*
X704769Y1233653D01*
G01X696687Y1250358D02*
X704147D01*
G01X704769Y1243643D02*
X704744Y1243668D01*
X696233D01*
G01X710346Y771845D02*
X710374Y771817D01*
X718279D01*
X718327Y771865D01*
G01X710346Y778538D02*
X710374Y778510D01*
X718279D01*
X718327Y778558D01*
G01X710346Y785228D02*
X710370Y785204D01*
X718284D01*
X718327Y785247D01*
G01X710346Y781829D02*
X710374Y781857D01*
X718298D01*
X718327Y781828D01*
G01X710346Y801964D02*
X710374Y801936D01*
X718279D01*
X718327Y801984D01*
G01X710346Y795271D02*
X710374Y795243D01*
X718279D01*
X718327Y795291D01*
G01X710346Y815349D02*
X710374Y815321D01*
X718279D01*
X718327Y815369D01*
G01X710346Y808656D02*
X710374Y808628D01*
X718279D01*
X718327Y808676D01*
G01X710346Y818640D02*
X710374Y818668D01*
X718298D01*
X718327Y818639D01*
G01X710346Y832082D02*
X710374Y832054D01*
X718279D01*
X718327Y832102D01*
G01X710346Y822039D02*
X710370Y822015D01*
X718284D01*
X718327Y822058D01*
G01X710346Y852160D02*
X710374Y852132D01*
X718279D01*
X718327Y852180D01*
G01X710346Y845467D02*
X710374Y845439D01*
X718279D01*
X718327Y845487D01*
G01X710346Y838775D02*
X710374Y838747D01*
X718279D01*
X718327Y838795D01*
G01X710346Y868893D02*
X710374Y868865D01*
X718279D01*
X718327Y868913D01*
G01X710346Y858850D02*
X710370Y858826D01*
X718284D01*
X718327Y858869D01*
G01X710346Y855451D02*
X710374Y855479D01*
X718298D01*
X718327Y855450D01*
G01X710346Y875586D02*
X710374Y875558D01*
X718279D01*
X718327Y875606D01*
G01X710346Y882278D02*
X710374Y882250D01*
X718279D01*
X718327Y882298D01*
G01X710346Y888971D02*
X710374Y888943D01*
X718279D01*
X718327Y888991D01*
G01X710346Y895661D02*
X710370Y895637D01*
X718284D01*
X718327Y895680D01*
G01X710346Y892262D02*
X710374Y892290D01*
X718298D01*
X718327Y892261D01*
G01X710346Y912397D02*
X710374Y912369D01*
X718279D01*
X718327Y912417D01*
G01X710346Y905704D02*
X710374Y905676D01*
X718279D01*
X718327Y905724D01*
G01X710346Y925782D02*
X710374Y925754D01*
X718279D01*
X718327Y925802D01*
G01X710346Y919090D02*
X710374Y919062D01*
X718279D01*
X718327Y919110D01*
G01X710346Y932472D02*
X710370Y932448D01*
X718284D01*
X718327Y932491D01*
G01X710346Y929073D02*
X710374Y929101D01*
X718298D01*
X718327Y929072D01*
G01X710346Y949208D02*
X710374Y949180D01*
X718279D01*
X718327Y949228D01*
G01X710346Y942515D02*
X710374Y942487D01*
X718279D01*
X718327Y942535D01*
G01X710346Y979340D02*
X710388Y979298D01*
X718298D01*
X718327Y979327D01*
G01X710346Y972647D02*
X710388Y972605D01*
X718298D01*
X718327Y972634D01*
G01X710346Y992726D02*
X710388Y992684D01*
X718298D01*
X718327Y992713D01*
G01X710346Y986033D02*
X710388Y985991D01*
X718298D01*
X718327Y986020D01*
G01X710346Y1032883D02*
X710388Y1032841D01*
X718298D01*
X718327Y1032870D01*
G01X710346Y1046269D02*
X710388Y1046227D01*
X718298D01*
X718327Y1046256D01*
G01X710346Y1039576D02*
X710388Y1039534D01*
X718298D01*
X718327Y1039563D01*
G01X710697Y1059613D02*
X718047D01*
G01X710346Y1073027D02*
X710374Y1072999D01*
X718279D01*
X718327Y1073047D01*
G01X710346Y1066334D02*
X710374Y1066306D01*
X718279D01*
X718327Y1066354D01*
G01X710346Y1079716D02*
X710370Y1079692D01*
X718284D01*
X718327Y1079735D01*
G01X710346Y1076317D02*
X710374Y1076345D01*
X718298D01*
X718327Y1076316D01*
G01X710346Y1096452D02*
X710374Y1096424D01*
X718279D01*
X718327Y1096472D01*
G01X710346Y1089759D02*
X710374Y1089731D01*
X718279D01*
X718327Y1089779D01*
G01X710346Y1109838D02*
X710374Y1109810D01*
X718279D01*
X718327Y1109858D01*
G01X710346Y1103145D02*
X710374Y1103117D01*
X718279D01*
X718327Y1103165D01*
G01X710346Y1126570D02*
X710374Y1126542D01*
X718279D01*
X718327Y1126590D01*
G01X710346Y1116527D02*
X710370Y1116503D01*
X718284D01*
X718327Y1116546D01*
G01X710346Y1113128D02*
X710374Y1113156D01*
X718298D01*
X718327Y1113127D01*
G01X710346Y1146649D02*
X710374Y1146621D01*
X718279D01*
X718327Y1146669D01*
G01X710346Y1139956D02*
X710374Y1139928D01*
X718279D01*
X718327Y1139976D01*
G01X710346Y1133263D02*
X710374Y1133235D01*
X718279D01*
X718327Y1133283D01*
G01X710346Y1153338D02*
X710370Y1153314D01*
X718284D01*
X718327Y1153357D01*
G01X710346Y1149940D02*
X710374Y1149968D01*
X718298D01*
X718327Y1149939D01*
G01X710346Y1176767D02*
X710374Y1176739D01*
X718279D01*
X718327Y1176787D01*
G01X710346Y1170074D02*
X710374Y1170046D01*
X718279D01*
X718327Y1170094D01*
G01X710346Y1163381D02*
X710374Y1163353D01*
X718279D01*
X718327Y1163401D01*
G01X710346Y1183460D02*
X710374Y1183432D01*
X718279D01*
X718327Y1183480D01*
G01X710346Y1190149D02*
X710370Y1190125D01*
X718284D01*
X718327Y1190168D01*
G01X710346Y1186751D02*
X710374Y1186779D01*
X718298D01*
X718327Y1186750D01*
G01X710346Y1206885D02*
X710374Y1206857D01*
X718279D01*
X718327Y1206905D01*
G01X710346Y1200192D02*
X710374Y1200164D01*
X718279D01*
X718327Y1200212D01*
G01X710346Y1220271D02*
X710374Y1220243D01*
X718279D01*
X718327Y1220291D01*
G01X710346Y1213578D02*
X710374Y1213550D01*
X718279D01*
X718327Y1213598D01*
G01X710346Y1226960D02*
X710370Y1226936D01*
X718284D01*
X718327Y1226979D01*
G01X710346Y1223562D02*
X710374Y1223590D01*
X718298D01*
X718327Y1223561D01*
G01X710346Y1243696D02*
X710374Y1243668D01*
X718279D01*
X718327Y1243716D01*
G01X710346Y1237003D02*
X710374Y1236975D01*
X718279D01*
X718327Y1237023D01*
G01X727257Y1250358D02*
X733747D01*
G01X764169Y778486D02*
X764144Y778511D01*
X755633D01*
G01X764169Y771793D02*
X764144Y771818D01*
X755527D01*
G01X755567Y788550D02*
X764148D01*
X764169Y788529D01*
G01Y795218D02*
X764144Y795243D01*
X755527D01*
G01X755652Y791897D02*
X764145D01*
X764169Y791921D01*
G01Y815297D02*
X764144Y815322D01*
X755633D01*
G01X764169Y808604D02*
X764144Y808629D01*
X755527D01*
G01X764169Y801911D02*
X764144Y801936D01*
X755633D01*
G01X764169Y832029D02*
X764144Y832054D01*
X755527D01*
G01X755567Y825361D02*
X764148D01*
X764169Y825340D01*
G01X755652Y828708D02*
X764145D01*
X764169Y828732D01*
G01Y845415D02*
X764144Y845440D01*
X755527D01*
G01X764169Y838722D02*
X764144Y838747D01*
X755633D01*
G01X764169Y852108D02*
X764144Y852133D01*
X755633D01*
G01X755567Y862172D02*
X764148D01*
X764169Y862151D01*
G01X755652Y865519D02*
X764145D01*
X764169Y865543D01*
G01Y882226D02*
X764144Y882251D01*
X755527D01*
G01X764169Y875533D02*
X764144Y875558D01*
X755633D01*
G01X764169Y868840D02*
X764144Y868865D01*
X755527D01*
G01X764169Y888919D02*
X764144Y888944D01*
X755633D01*
G01X755567Y898983D02*
X764148D01*
X764169Y898962D01*
G01X755652Y902330D02*
X764145D01*
X764169Y902354D01*
G01Y912344D02*
X764144Y912369D01*
X755633D01*
G01X764169Y905651D02*
X764144Y905676D01*
X755527D01*
G01X764729Y925755D02*
X755633D01*
G01X764729Y919062D02*
X755633D01*
G01X764729Y942487D02*
X755633D01*
G01X755567Y935794D02*
X764148D01*
G01X755652Y939141D02*
X764145D01*
G01X764729Y949180D02*
X755633D01*
G01X755567Y982644D02*
X764120D01*
X764169Y982693D01*
G01X755567Y975951D02*
X764120D01*
X764169Y976000D01*
G01X755567Y989337D02*
X764120D01*
X764169Y989386D01*
G01X755567Y1029495D02*
X764120D01*
X764169Y1029544D01*
G01X755557Y1019456D02*
X764120D01*
X764169Y1019505D01*
G01X755201Y1042880D02*
X764120D01*
X764169Y1042929D01*
G01X755244Y1036188D02*
X764120D01*
X764169Y1036237D01*
G01X764729Y1059613D02*
X755633D01*
G01X755567Y1049573D02*
X764120D01*
X764169Y1049622D01*
G01X764729Y1072999D02*
X755633D01*
G01X764729Y1066306D02*
X755633D01*
G01X764729Y1089731D02*
X755633D01*
G01X755567Y1083038D02*
X764148D01*
G01X755652Y1086385D02*
X764145D01*
G01X764729Y1096424D02*
X755633D01*
G01X764169Y1109785D02*
X764144Y1109810D01*
X755633D01*
G01X764169Y1103092D02*
X764144Y1103117D01*
X755527D01*
G01X764169Y1126517D02*
X764144Y1126542D01*
X755527D01*
G01X755567Y1119849D02*
X764148D01*
X764169Y1119828D01*
G01X755652Y1123196D02*
X764145D01*
X764169Y1123220D01*
G01Y1139903D02*
X764144Y1139928D01*
X755527D01*
G01X764169Y1133210D02*
X764144Y1133235D01*
X755633D01*
G01X764169Y1146596D02*
X764144Y1146621D01*
X755633D01*
G01X755567Y1156660D02*
X764148D01*
X764169Y1156639D01*
G01X755652Y1160007D02*
X764145D01*
X764169Y1160031D01*
G01Y1170021D02*
X764144Y1170046D01*
X755633D01*
G01X764169Y1163328D02*
X764144Y1163353D01*
X755527D01*
G01X764169Y1183407D02*
X764144Y1183432D01*
X755257D01*
G01X764169Y1176714D02*
X764144Y1176739D01*
X755527D01*
G01X755567Y1193471D02*
X764148D01*
X764169Y1193450D01*
G01Y1206832D02*
X764144Y1206857D01*
X755633D01*
G01X764169Y1200139D02*
X764144Y1200164D01*
X755527D01*
G01X755652Y1196818D02*
X764145D01*
X764169Y1196842D01*
G01Y1220218D02*
X764144Y1220243D01*
X755633D01*
G01X764169Y1213525D02*
X764144Y1213550D01*
X755527D01*
G01X764169Y1236950D02*
X764144Y1236975D01*
X755527D01*
G01X755567Y1230282D02*
X764148D01*
X764169Y1230261D01*
G01X755652Y1233629D02*
X764145D01*
X764169Y1233653D01*
G01X756957Y1250358D02*
X763457D01*
G01X764169Y1243643D02*
X764144Y1243668D01*
X755633D01*
G01X769746Y771845D02*
X769774Y771817D01*
X777679D01*
X777727Y771865D01*
G01X769746Y778538D02*
X769774Y778510D01*
X777679D01*
X777727Y778558D01*
G01X769746Y785228D02*
X769770Y785204D01*
X777684D01*
X777727Y785247D01*
G01X769746Y781829D02*
X769774Y781857D01*
X777698D01*
X777727Y781828D01*
G01X769746Y801964D02*
X769774Y801936D01*
X777679D01*
X777727Y801984D01*
G01X769746Y795271D02*
X769774Y795243D01*
X777679D01*
X777727Y795291D01*
G01X769746Y815349D02*
X769774Y815321D01*
X777679D01*
X777727Y815369D01*
G01X769746Y808656D02*
X769774Y808628D01*
X777679D01*
X777727Y808676D01*
G01X769746Y832082D02*
X769774Y832054D01*
X777679D01*
X777727Y832102D01*
G01X769746Y822039D02*
X769770Y822015D01*
X777684D01*
X777727Y822058D01*
G01X769746Y818640D02*
X769774Y818668D01*
X777698D01*
X777727Y818639D01*
G01X769746Y852160D02*
X769774Y852132D01*
X777679D01*
X777727Y852180D01*
G01X769746Y845467D02*
X769774Y845439D01*
X777679D01*
X777727Y845487D01*
G01X769746Y838775D02*
X769774Y838747D01*
X777679D01*
X777727Y838795D01*
G01X769746Y868893D02*
X769774Y868865D01*
X777679D01*
X777727Y868913D01*
G01X769746Y858850D02*
X769770Y858826D01*
X777684D01*
X777727Y858869D01*
G01X769746Y855451D02*
X769774Y855479D01*
X777698D01*
X777727Y855450D01*
G01X769746Y875586D02*
X769774Y875558D01*
X777679D01*
X777727Y875606D01*
G01X769746Y882278D02*
X769774Y882250D01*
X777679D01*
X777727Y882298D01*
G01X769746Y888971D02*
X769774Y888943D01*
X777679D01*
X777727Y888991D01*
G01X769746Y895661D02*
X769770Y895637D01*
X777684D01*
X777727Y895680D01*
G01X769746Y892262D02*
X769774Y892290D01*
X777698D01*
X777727Y892261D01*
G01X769746Y912397D02*
X769774Y912369D01*
X777679D01*
X777727Y912417D01*
G01X769746Y905704D02*
X769774Y905676D01*
X777679D01*
X777727Y905724D01*
G01X769774Y925754D02*
X777515D01*
G01X769774Y919062D02*
X777679D01*
G01X769774Y929101D02*
X777698D01*
G01X769774Y949180D02*
X777515D01*
G01X769774Y942487D02*
X777679D01*
G01X769770Y932448D02*
X777684D01*
G01X769746Y979340D02*
X769788Y979298D01*
X777698D01*
X777727Y979327D01*
G01X769746Y972647D02*
X769788Y972605D01*
X777698D01*
X777727Y972634D01*
G01X769746Y992726D02*
X769788Y992684D01*
X777698D01*
X777727Y992713D01*
G01X769746Y986033D02*
X769788Y985991D01*
X777698D01*
X777727Y986020D01*
G01X769746Y1046269D02*
X769788Y1046227D01*
X777698D01*
X777727Y1046256D01*
G01X769746Y1039576D02*
X769788Y1039534D01*
X777698D01*
X777727Y1039563D01*
G01X769746Y1032883D02*
X769788Y1032841D01*
X777698D01*
X777727Y1032870D01*
G01X777667Y1059613D02*
X769697D01*
G01X769774Y1072999D02*
X777515D01*
G01X769774Y1066306D02*
X777679D01*
G01X769774Y1076345D02*
X777698D01*
G01X769774Y1096424D02*
X777515D01*
G01X769774Y1089731D02*
X777679D01*
G01X769770Y1079692D02*
X777684D01*
G01X769746Y1109838D02*
X769774Y1109810D01*
X777679D01*
X777727Y1109858D01*
G01X769746Y1103145D02*
X769774Y1103117D01*
X777679D01*
X777727Y1103165D01*
G01X769746Y1126570D02*
X769774Y1126542D01*
X777679D01*
X777727Y1126590D01*
G01X769746Y1116527D02*
X769770Y1116503D01*
X777684D01*
X777727Y1116546D01*
G01X769746Y1113128D02*
X769774Y1113156D01*
X777698D01*
X777727Y1113127D01*
G01X769746Y1139956D02*
X769774Y1139928D01*
X777679D01*
X777727Y1139976D01*
G01X769746Y1133263D02*
X769774Y1133235D01*
X777679D01*
X777727Y1133283D01*
G01X769746Y1146649D02*
X769774Y1146621D01*
X777679D01*
X777727Y1146669D01*
G01X769746Y1153338D02*
X769770Y1153314D01*
X777684D01*
X777727Y1153357D01*
G01X769746Y1149940D02*
X769774Y1149968D01*
X777698D01*
X777727Y1149939D01*
G01X769746Y1176767D02*
X769774Y1176739D01*
X777679D01*
X777727Y1176787D01*
G01X769746Y1170074D02*
X769774Y1170046D01*
X777679D01*
X777727Y1170094D01*
G01X769746Y1163381D02*
X769774Y1163353D01*
X777679D01*
X777727Y1163401D01*
G01X769746Y1183460D02*
X769774Y1183432D01*
X777679D01*
X777727Y1183480D01*
G01X769746Y1190149D02*
X769770Y1190125D01*
X777684D01*
X777727Y1190168D01*
G01X769746Y1186751D02*
X769774Y1186779D01*
X777698D01*
X777727Y1186750D01*
G01X769746Y1206885D02*
X769774Y1206857D01*
X777679D01*
X777727Y1206905D01*
G01X769746Y1200192D02*
X769774Y1200164D01*
X777679D01*
X777727Y1200212D01*
G01X769746Y1220271D02*
X769774Y1220243D01*
X777679D01*
X777727Y1220291D01*
G01X769746Y1213578D02*
X769774Y1213550D01*
X777679D01*
X777727Y1213598D01*
G01X769746Y1223562D02*
X769774Y1223590D01*
X777698D01*
X777727Y1223561D01*
G01X769746Y1243696D02*
X769774Y1243668D01*
X777679D01*
X777727Y1243716D01*
G01X769746Y1237003D02*
X769774Y1236975D01*
X777679D01*
X777727Y1237023D01*
G01X769746Y1226960D02*
X769770Y1226936D01*
X777684D01*
X777727Y1226979D01*
G01X786657Y1250358D02*
X793187D01*
G01X807367Y1059613D02*
X799457D01*
G01X823569Y778486D02*
X823544Y778511D01*
X815033D01*
G01X823569Y771793D02*
X823544Y771818D01*
X814927D01*
G01X814967Y788550D02*
X823548D01*
X823569Y788529D01*
G01Y795218D02*
X823544Y795243D01*
X814927D01*
G01X815052Y791897D02*
X823545D01*
X823569Y791921D01*
G01Y815297D02*
X823544Y815322D01*
X815033D01*
G01X823569Y808604D02*
X823544Y808629D01*
X814927D01*
G01X823569Y801911D02*
X823544Y801936D01*
X815033D01*
G01X823569Y832029D02*
X823544Y832054D01*
X814927D01*
G01X814967Y825361D02*
X823548D01*
X823569Y825340D01*
G01X815052Y828708D02*
X823545D01*
X823569Y828732D01*
G01Y845415D02*
X823544Y845440D01*
X814927D01*
G01X823569Y838722D02*
X823544Y838747D01*
X815033D01*
G01X823569Y852108D02*
X823544Y852133D01*
X815033D01*
G01X814967Y862172D02*
X823548D01*
X823569Y862151D01*
G01X815052Y865519D02*
X823545D01*
X823569Y865543D01*
G01Y882226D02*
X823544Y882251D01*
X814927D01*
G01X823569Y875533D02*
X823544Y875558D01*
X815033D01*
G01X823569Y868840D02*
X823544Y868865D01*
X814927D01*
G01X823569Y888919D02*
X823544Y888944D01*
X815033D01*
G01X814967Y898983D02*
X823548D01*
X823569Y898962D01*
G01X815052Y902330D02*
X823545D01*
X823569Y902354D01*
G01Y912344D02*
X823544Y912369D01*
X815033D01*
G01X823569Y905651D02*
X823544Y905676D01*
X814927D01*
G01X823569Y925730D02*
X823544Y925755D01*
X815033D01*
G01X823569Y919037D02*
X823544Y919062D01*
X814927D01*
G01X823569Y942462D02*
X823544Y942487D01*
X814927D01*
G01X814967Y935794D02*
X823548D01*
X823569Y935773D01*
G01X815052Y939141D02*
X823545D01*
X823569Y939165D01*
G01Y949155D02*
X823544Y949180D01*
X815033D01*
G01X814967Y982644D02*
X823520D01*
X823569Y982693D01*
G01X814967Y975951D02*
X823520D01*
X823569Y976000D01*
G01X814967Y989337D02*
X823520D01*
X823569Y989386D01*
G01X814967Y1029495D02*
X823520D01*
X823569Y1029544D01*
G01X814957Y1019456D02*
X823520D01*
X823569Y1019505D01*
G01X814625Y1049573D02*
X823520D01*
X823569Y1049622D01*
G01X814967Y1042880D02*
X823520D01*
X823569Y1042929D01*
G01X814967Y1036188D02*
X823520D01*
X823569Y1036237D01*
G01Y1059450D02*
X823511D01*
X822973Y1059613D01*
X815588D01*
G01X823569Y1072974D02*
X823544Y1072999D01*
X815033D01*
G01X823569Y1066281D02*
X823544Y1066306D01*
X814927D01*
G01X823569Y1089706D02*
X823544Y1089731D01*
X814927D01*
G01X814967Y1083038D02*
X823548D01*
X823569Y1083017D01*
G01X815052Y1086385D02*
X823545D01*
X823569Y1086409D01*
G01Y1096399D02*
X823544Y1096424D01*
X815033D01*
G01X823569Y1109785D02*
X823544Y1109810D01*
X815033D01*
G01X823569Y1103092D02*
X823544Y1103117D01*
X814927D01*
G01X823569Y1126517D02*
X823544Y1126542D01*
X814927D01*
G01X814967Y1119849D02*
X823548D01*
X823569Y1119828D01*
G01X815052Y1123196D02*
X823545D01*
X823569Y1123220D01*
G01Y1139903D02*
X823544Y1139928D01*
X814927D01*
G01X823569Y1133210D02*
X823544Y1133235D01*
X815033D01*
G01X823569Y1146596D02*
X823544Y1146621D01*
X815033D01*
G01X814967Y1156660D02*
X823548D01*
X823569Y1156639D01*
G01X815052Y1160007D02*
X823545D01*
X823569Y1160031D01*
G01Y1170021D02*
X823544Y1170046D01*
X815033D01*
G01X823569Y1163328D02*
X823544Y1163353D01*
X814927D01*
G01X823569Y1183407D02*
X823544Y1183432D01*
X815033D01*
G01X823569Y1176714D02*
X823544Y1176739D01*
X814927D01*
G01X814967Y1193471D02*
X823548D01*
X823569Y1193450D01*
G01Y1206832D02*
X823544Y1206857D01*
X815033D01*
G01X823569Y1200139D02*
X823544Y1200164D01*
X814927D01*
G01X815052Y1196818D02*
X823545D01*
X823569Y1196842D01*
G01Y1220218D02*
X823544Y1220243D01*
X815033D01*
G01X823569Y1213525D02*
X823544Y1213550D01*
X814927D01*
G01X823569Y1236950D02*
X823544Y1236975D01*
X814927D01*
G01X814967Y1230282D02*
X823548D01*
X823569Y1230261D01*
G01X815052Y1233629D02*
X823545D01*
X823569Y1233653D01*
G01X822777Y1250358D02*
X816357D01*
G01X823569Y1243643D02*
X823544Y1243668D01*
X815033D01*
G01X829146Y771845D02*
X829174Y771817D01*
X837079D01*
X837127Y771865D01*
G01X829146Y778538D02*
X829174Y778510D01*
X837079D01*
X837127Y778558D01*
G01X829146Y785228D02*
X829170Y785204D01*
X837084D01*
X837127Y785247D01*
G01X829146Y781829D02*
X829174Y781857D01*
X837098D01*
X837127Y781828D01*
G01X829146Y801964D02*
X829174Y801936D01*
X837079D01*
X837127Y801984D01*
G01X829146Y795271D02*
X829174Y795243D01*
X837079D01*
X837127Y795291D01*
G01X829146Y815349D02*
X829174Y815321D01*
X837079D01*
X837127Y815369D01*
G01X829146Y808656D02*
X829174Y808628D01*
X837079D01*
X837127Y808676D01*
G01X829146Y818640D02*
X829174Y818668D01*
X837098D01*
X837127Y818639D01*
G01X829146Y832082D02*
X829174Y832054D01*
X837079D01*
X837127Y832102D01*
G01X829146Y822039D02*
X829170Y822015D01*
X837084D01*
X837127Y822058D01*
G01X829146Y852160D02*
X829174Y852132D01*
X837079D01*
X837127Y852180D01*
G01X829146Y845467D02*
X829174Y845439D01*
X837079D01*
X837127Y845487D01*
G01X829146Y838775D02*
X829174Y838747D01*
X837079D01*
X837127Y838795D01*
G01X829146Y868893D02*
X829174Y868865D01*
X837079D01*
X837127Y868913D01*
G01X829146Y858850D02*
X829170Y858826D01*
X837084D01*
X837127Y858869D01*
G01X829146Y855451D02*
X829174Y855479D01*
X837098D01*
X837127Y855450D01*
G01X829146Y875586D02*
X829174Y875558D01*
X837079D01*
X837127Y875606D01*
G01X829146Y882278D02*
X829174Y882250D01*
X837079D01*
X837127Y882298D01*
G01X829146Y888971D02*
X829174Y888943D01*
X837079D01*
X837127Y888991D01*
G01X829146Y895661D02*
X829170Y895637D01*
X837084D01*
X837127Y895680D01*
G01X829146Y892262D02*
X829174Y892290D01*
X837098D01*
X837127Y892261D01*
G01X829146Y912397D02*
X829174Y912369D01*
X837079D01*
X837127Y912417D01*
G01X829146Y905704D02*
X829174Y905676D01*
X837079D01*
X837127Y905724D01*
G01X829146Y925782D02*
X829174Y925754D01*
X837079D01*
X837127Y925802D01*
G01X829146Y919090D02*
X829174Y919062D01*
X837079D01*
X837127Y919110D01*
G01X829146Y932472D02*
X829170Y932448D01*
X837084D01*
X837127Y932491D01*
G01X829146Y929073D02*
X829174Y929101D01*
X837098D01*
X837127Y929072D01*
G01X829146Y949208D02*
X829174Y949180D01*
X837079D01*
X837127Y949228D01*
G01X829146Y942515D02*
X829174Y942487D01*
X837079D01*
X837127Y942535D01*
G01X829146Y979340D02*
X829188Y979298D01*
X837098D01*
X837127Y979327D01*
G01X829146Y972647D02*
X829188Y972605D01*
X837098D01*
X837127Y972634D01*
G01X829146Y992726D02*
X829188Y992684D01*
X837098D01*
X837127Y992713D01*
G01X829146Y986033D02*
X829188Y985991D01*
X837098D01*
X837127Y986020D01*
G01X829146Y1046269D02*
X829188Y1046227D01*
X837098D01*
X837127Y1046256D01*
G01X829146Y1039576D02*
X829188Y1039534D01*
X837098D01*
X837127Y1039563D01*
G01X829146Y1032883D02*
X829188Y1032841D01*
X837098D01*
X837127Y1032870D01*
G01X837097Y1059613D02*
X829227D01*
G01X829146Y1073027D02*
X829174Y1072999D01*
X837079D01*
X837127Y1073047D01*
G01X829146Y1066334D02*
X829174Y1066306D01*
X837079D01*
X837127Y1066354D01*
G01X829146Y1079716D02*
X829170Y1079692D01*
X837084D01*
X837127Y1079735D01*
G01X829146Y1076317D02*
X829174Y1076345D01*
X837098D01*
X837127Y1076316D01*
G01X829146Y1096452D02*
X829174Y1096424D01*
X837079D01*
X837127Y1096472D01*
G01X829146Y1089759D02*
X829174Y1089731D01*
X837079D01*
X837127Y1089779D01*
G01X829146Y1109838D02*
X829174Y1109810D01*
X837079D01*
X837127Y1109858D01*
G01X829146Y1103145D02*
X829174Y1103117D01*
X837079D01*
X837127Y1103165D01*
G01X829146Y1126570D02*
X829174Y1126542D01*
X837079D01*
X837127Y1126590D01*
G01X829146Y1116527D02*
X829170Y1116503D01*
X837084D01*
X837127Y1116546D01*
G01X829146Y1113128D02*
X829174Y1113156D01*
X837098D01*
X837127Y1113127D01*
G01X829146Y1139956D02*
X829174Y1139928D01*
X837079D01*
X837127Y1139976D01*
G01X829146Y1133263D02*
X829174Y1133235D01*
X837079D01*
X837127Y1133283D01*
G01X829146Y1146649D02*
X829174Y1146621D01*
X837079D01*
X837127Y1146669D01*
G01X829146Y1153338D02*
X829170Y1153314D01*
X837084D01*
X837127Y1153357D01*
G01X829146Y1149940D02*
X829174Y1149968D01*
X837098D01*
X837127Y1149939D01*
G01X829146Y1176767D02*
X829174Y1176739D01*
X837079D01*
X837127Y1176787D01*
G01X829146Y1170074D02*
X829174Y1170046D01*
X837079D01*
X837127Y1170094D01*
G01X829146Y1163381D02*
X829174Y1163353D01*
X837079D01*
X837127Y1163401D01*
G01X829146Y1183460D02*
X829174Y1183432D01*
X837079D01*
X837127Y1183480D01*
G01X829146Y1190149D02*
X829170Y1190125D01*
X837084D01*
X837127Y1190168D01*
G01X829146Y1186751D02*
X829174Y1186779D01*
X837098D01*
X837127Y1186750D01*
G01X829146Y1206885D02*
X829174Y1206857D01*
X837079D01*
X837127Y1206905D01*
G01X829146Y1200192D02*
X829174Y1200164D01*
X837079D01*
X837127Y1200212D01*
G01X829146Y1220271D02*
X829174Y1220243D01*
X837079D01*
X837127Y1220291D01*
G01X829146Y1213578D02*
X829174Y1213550D01*
X837079D01*
X837127Y1213598D01*
G01X829146Y1226960D02*
X829170Y1226936D01*
X837084D01*
X837127Y1226979D01*
G01X829146Y1223562D02*
X829174Y1223590D01*
X837098D01*
X837127Y1223561D01*
G01X829146Y1243696D02*
X829174Y1243668D01*
X837079D01*
X837127Y1243716D01*
G01X829146Y1237003D02*
X829174Y1236975D01*
X837079D01*
X837127Y1237023D01*
G01X852477Y1250358D02*
X846057D01*
G01X1029061Y778511D02*
X1020915D01*
G01X1027759Y771818D02*
X1019942D01*
X1019907Y771783D01*
G01X1029061Y788550D02*
X1019952D01*
G01X1029061Y801936D02*
X1020915D01*
G01X1027759Y795243D02*
X1019942D01*
X1019907Y795208D01*
G01X1027788Y791897D02*
X1020877D01*
G01X1029061Y815322D02*
X1020915D01*
G01X1027759Y808629D02*
X1019942D01*
X1019907Y808594D01*
G01X1027759Y832054D02*
X1019942D01*
X1019907Y832019D01*
G01X1029061Y825361D02*
X1019952D01*
G01X1027788Y828708D02*
X1020877D01*
G01X1029061Y852133D02*
X1020915D01*
G01X1027759Y845440D02*
X1019942D01*
X1019907Y845405D01*
G01X1029061Y838747D02*
X1020915D01*
G01X1029061Y862172D02*
X1019952D01*
G01X1027788Y865519D02*
X1020877D01*
G01X1027759Y882251D02*
X1019942D01*
X1019907Y882216D01*
G01X1029061Y875558D02*
X1020915D01*
G01X1027759Y868865D02*
X1019942D01*
X1019907Y868830D01*
G01X1029061Y888944D02*
X1020915D01*
G01X1029061Y898983D02*
X1019952D01*
G01X1027788Y902330D02*
X1020877D01*
G01X1029061Y912369D02*
X1020915D01*
G01X1027759Y905676D02*
X1019942D01*
X1019907Y905641D01*
G01X1029061Y925755D02*
X1020915D01*
G01X1027759Y919062D02*
X1019942D01*
X1019907Y919027D01*
G01X1029061Y949180D02*
X1020915D01*
G01X1027759Y942487D02*
X1019942D01*
X1019907Y942452D01*
G01X1029061Y935794D02*
X1019952D01*
G01X1027788Y939141D02*
X1020877D01*
G01X1027759Y979298D02*
X1019942D01*
X1019907Y979263D01*
G01X1027759Y972605D02*
X1019942D01*
X1019907Y972570D01*
G01X1027759Y992684D02*
X1019942D01*
X1019907Y992649D01*
G01X1027759Y985991D02*
X1019942D01*
X1019907Y985956D01*
G01X1027759Y1026149D02*
X1019942D01*
X1019907Y1026114D01*
G01X1027759Y1019456D02*
X1019995D01*
G01X1027759Y1046227D02*
X1019942D01*
X1019907Y1046192D01*
G01X1027759Y1039534D02*
X1019942D01*
X1019907Y1039499D01*
G01X1027759Y1032842D02*
X1019942D01*
X1019907Y1032807D01*
G01X1028938Y1059613D02*
X1019942D01*
X1019907Y1059578D01*
G01X1029061Y1072999D02*
X1020915D01*
G01X1027759Y1066306D02*
X1019942D01*
X1019907Y1066271D01*
G01X1027759Y1089731D02*
X1019942D01*
X1019907Y1089696D01*
G01X1029061Y1083038D02*
X1019952D01*
G01X1027788Y1086385D02*
X1020877D01*
G01X1029061Y1096424D02*
X1020915D01*
G01X1029061Y1109810D02*
X1020915D01*
G01X1027759Y1103117D02*
X1019942D01*
X1019907Y1103082D01*
G01X1027759Y1126542D02*
X1019942D01*
X1019907Y1126507D01*
G01X1029061Y1119849D02*
X1019952D01*
G01X1027788Y1123196D02*
X1020877D01*
G01X1027759Y1139928D02*
X1019942D01*
X1019907Y1139893D01*
G01X1029061Y1133235D02*
X1020915D01*
G01X1029061Y1146621D02*
X1020915D01*
G01X1029061Y1156660D02*
X1019952D01*
G01X1027788Y1160007D02*
X1020877D01*
G01X1027759Y1176739D02*
X1019942D01*
X1019907Y1176704D01*
G01X1029061Y1170046D02*
X1020915D01*
G01X1027759Y1163353D02*
X1019942D01*
X1019907Y1163318D01*
G01X1029061Y1183432D02*
X1020915D01*
G01X1029061Y1193471D02*
X1019952D01*
G01X1029061Y1206857D02*
X1020915D01*
G01X1027759Y1200164D02*
X1019942D01*
X1019907Y1200129D01*
G01X1027788Y1196818D02*
X1020877D01*
G01X1029061Y1220243D02*
X1020915D01*
G01X1027759Y1213550D02*
X1019942D01*
X1019907Y1213515D01*
G01X1027759Y1236975D02*
X1019942D01*
X1019907Y1236940D01*
G01X1029061Y1230282D02*
X1019952D01*
G01X1027788Y1233629D02*
X1020877D01*
G01X1027536Y1250343D02*
X1021181D01*
G01X1029061Y1243668D02*
X1020915D01*
G01X1042619Y771817D02*
X1034458D01*
G01X1042619Y775164D02*
X1034509D01*
G01X1042619Y785204D02*
X1034440D01*
G01X1042619Y781858D02*
X1042618Y781857D01*
X1034437D01*
G01X1042619Y798590D02*
X1034509D01*
G01X1042619Y795243D02*
X1034458D01*
G01X1042619Y811975D02*
X1034509D01*
G01X1042619Y808628D02*
X1034458D01*
G01X1042619Y818669D02*
X1042618Y818668D01*
X1034437D01*
G01X1042619Y835401D02*
X1034509D01*
G01X1042619Y832054D02*
X1034458D01*
G01X1042619Y822015D02*
X1034440D01*
G01X1042619Y848786D02*
X1034509D01*
G01X1042619Y845439D02*
X1034458D01*
G01X1042619Y868865D02*
X1034458D01*
G01X1042619Y858826D02*
X1034440D01*
G01X1042619Y855480D02*
X1042618Y855479D01*
X1034437D01*
G01X1042619Y872212D02*
X1034509D01*
G01X1042619Y882250D02*
X1034458D01*
G01X1042619Y885597D02*
X1034509D01*
G01X1042619Y895637D02*
X1034440D01*
G01X1042619Y892291D02*
X1042618Y892290D01*
X1034437D01*
G01X1042619Y909023D02*
X1034509D01*
G01X1042619Y905676D02*
X1034458D01*
G01X1042619Y922408D02*
X1034509D01*
G01X1042619Y919062D02*
X1034458D01*
G01X1042619Y932448D02*
X1034440D01*
G01X1042619Y929102D02*
X1042618Y929101D01*
X1034437D01*
G01X1042619Y945834D02*
X1034509D01*
G01X1042619Y942487D02*
X1034458D01*
G01X1042619Y979298D02*
X1034458D01*
G01X1042619Y972605D02*
X1034458D01*
G01X1042619Y992684D02*
X1034458D01*
G01X1042619Y985991D02*
X1034458D01*
G01X1042619Y1032841D02*
X1034458D01*
G01X1042619Y1046227D02*
X1034458D01*
G01X1042619Y1039534D02*
X1034458D01*
G01Y1059613D02*
X1042663D01*
G01X1042619Y1069653D02*
X1034509D01*
G01X1042619Y1066306D02*
X1034458D01*
G01X1042620Y1079692D02*
X1034440D01*
G01X1042619Y1076346D02*
X1042618Y1076345D01*
X1034437D01*
G01X1042619Y1093078D02*
X1034509D01*
G01X1042619Y1089731D02*
X1034458D01*
G01X1042619Y1106464D02*
X1034509D01*
G01X1042619Y1103117D02*
X1034458D01*
G01X1042619Y1126542D02*
X1034458D01*
G01X1042619Y1116503D02*
X1034440D01*
G01X1042619Y1113157D02*
X1042618Y1113156D01*
X1034437D01*
G01X1042619Y1143275D02*
X1034509D01*
G01X1042619Y1139928D02*
X1034458D01*
G01X1042619Y1129889D02*
X1034509D01*
G01X1042619Y1153314D02*
X1034440D01*
G01X1042619Y1149968D02*
X1034436D01*
G01X1042619Y1176739D02*
X1034458D01*
G01X1042619Y1166700D02*
X1034509D01*
G01X1042619Y1163353D02*
X1034458D01*
G01X1042619Y1180086D02*
X1034509D01*
G01X1042619Y1190125D02*
X1034440D01*
G01X1042619Y1186779D02*
X1034436D01*
G01X1042619Y1203511D02*
X1034509D01*
G01X1042619Y1200164D02*
X1034458D01*
G01X1042619Y1216897D02*
X1034509D01*
G01X1042619Y1213550D02*
X1034458D01*
G01X1042619Y1226936D02*
X1034440D01*
G01X1042619Y1223590D02*
X1034436D01*
G01X1042619Y1240322D02*
X1034509D01*
G01X1042619Y1236975D02*
X1034458D01*
G01X1064172Y1056266D02*
X1070949D01*
G01X1050881Y1250343D02*
X1057236D01*
G01X1088461Y778511D02*
X1080315D01*
G01X1087159Y771818D02*
X1079342D01*
X1079307Y771783D01*
G01X1088461Y788550D02*
X1079352D01*
G01X1087159Y795243D02*
X1079342D01*
X1079307Y795208D01*
G01X1087188Y791897D02*
X1080277D01*
G01X1088461Y815322D02*
X1080315D01*
G01X1087159Y808629D02*
X1079342D01*
X1079307Y808594D01*
G01X1088461Y801936D02*
X1080315D01*
G01X1087159Y832054D02*
X1079342D01*
X1079307Y832019D01*
G01X1088461Y825361D02*
X1079352D01*
G01X1087188Y828708D02*
X1080277D01*
G01X1087159Y845440D02*
X1079342D01*
X1079307Y845405D01*
G01X1088461Y838747D02*
X1080315D01*
G01X1088461Y852133D02*
X1080315D01*
G01X1088461Y862172D02*
X1079352D01*
G01X1087188Y865519D02*
X1080277D01*
G01X1087159Y882251D02*
X1079342D01*
X1079307Y882216D01*
G01X1088461Y875558D02*
X1080315D01*
G01X1087159Y868865D02*
X1079342D01*
X1079307Y868830D01*
G01X1088461Y888944D02*
X1080315D01*
G01X1088461Y898983D02*
X1079352D01*
G01X1087188Y902330D02*
X1080277D01*
G01X1088461Y912369D02*
X1080315D01*
G01X1087159Y905676D02*
X1079342D01*
X1079307Y905641D01*
G01X1088461Y925755D02*
X1080315D01*
G01X1087159Y919062D02*
X1079342D01*
G01X1087159Y942487D02*
X1079342D01*
G01X1088461Y935794D02*
X1079352D01*
G01X1088462Y939141D02*
X1080277D01*
G01X1088461Y949180D02*
X1080315D01*
G01X1087159Y979298D02*
X1079342D01*
X1079307Y979263D01*
G01X1087159Y972605D02*
X1079342D01*
X1079307Y972570D01*
G01X1087159Y992684D02*
X1079342D01*
X1079307Y992649D01*
G01X1087159Y985991D02*
X1079342D01*
X1079307Y985956D01*
G01X1087159Y1026149D02*
X1079342D01*
X1079307Y1026114D01*
G01X1087159Y1019456D02*
X1079395D01*
G01X1087159Y1039534D02*
X1079342D01*
X1079307Y1039499D01*
G01X1087159Y1032842D02*
X1079342D01*
X1079307Y1032807D01*
G01X1087159Y1059613D02*
X1079342D01*
X1079307Y1059578D01*
G01X1087159Y1046227D02*
X1079342D01*
X1079307Y1046192D01*
G01X1088461Y1072999D02*
X1080315D01*
G01X1087159Y1066306D02*
X1079342D01*
G01X1087159Y1089731D02*
X1079342D01*
G01X1088461Y1083038D02*
X1079352D01*
G01X1087188Y1086385D02*
X1080277D01*
G01X1088461Y1096424D02*
X1080315D01*
G01X1088461Y1109810D02*
X1080315D01*
G01X1087159Y1103117D02*
X1079342D01*
X1079307Y1103082D01*
G01X1087159Y1126542D02*
X1079342D01*
X1079307Y1126507D01*
G01X1088461Y1119849D02*
X1079352D01*
G01X1087188Y1123196D02*
X1080277D01*
G01X1087159Y1139928D02*
X1079342D01*
X1079307Y1139893D01*
G01X1088461Y1133235D02*
X1080315D01*
G01X1088461Y1146621D02*
X1080315D01*
G01X1088461Y1156660D02*
X1079352D01*
G01X1087188Y1160007D02*
X1080277D01*
G01X1088461Y1170046D02*
X1080315D01*
G01X1087159Y1163353D02*
X1079342D01*
X1079307Y1163318D01*
G01X1088461Y1183432D02*
X1080315D01*
G01X1087159Y1176739D02*
X1079342D01*
X1079307Y1176704D01*
G01X1088461Y1193471D02*
X1079352D01*
G01X1088461Y1206857D02*
X1080315D01*
G01X1087159Y1200164D02*
X1079342D01*
X1079307Y1200129D01*
G01X1087188Y1196818D02*
X1080277D01*
G01X1088461Y1220243D02*
X1080315D01*
G01X1087159Y1213550D02*
X1079342D01*
X1079307Y1213515D01*
G01X1087159Y1236975D02*
X1079342D01*
X1079307Y1236940D01*
G01X1088461Y1230282D02*
X1079352D01*
G01X1087188Y1233629D02*
X1080277D01*
G01X1086936Y1250343D02*
X1080581D01*
G01X1088461Y1243668D02*
X1080315D01*
G01X1102019Y771817D02*
X1093858D01*
G01X1102019Y775164D02*
X1093909D01*
G01X1102019Y785204D02*
X1093840D01*
G01X1102019Y781858D02*
X1102018Y781857D01*
X1093837D01*
G01X1102019Y798590D02*
X1093909D01*
G01X1102019Y795243D02*
X1093858D01*
G01X1102019Y811975D02*
X1093909D01*
G01X1102019Y808628D02*
X1093858D01*
G01X1102019Y832054D02*
X1093858D01*
G01X1102019Y822015D02*
X1093840D01*
G01X1102019Y818669D02*
X1102018Y818668D01*
X1093837D01*
G01X1102019Y848786D02*
X1093909D01*
G01X1102019Y845439D02*
X1093858D01*
G01X1102019Y835401D02*
X1093909D01*
G01X1102019Y868865D02*
X1093858D01*
G01X1102019Y858826D02*
X1093840D01*
G01X1102019Y855480D02*
X1102018Y855479D01*
X1093837D01*
G01X1102019Y872212D02*
X1093909D01*
G01X1102019Y882250D02*
X1093858D01*
G01X1102019Y885597D02*
X1093909D01*
G01X1102019Y895637D02*
X1093840D01*
G01X1102019Y892291D02*
X1102018Y892290D01*
X1093837D01*
G01X1102019Y909023D02*
X1093909D01*
G01X1102019Y905676D02*
X1093858D01*
G01X1102019Y922408D02*
X1093909D01*
G01X1102019Y919062D02*
X1093858D01*
G01X1102019Y932448D02*
X1093840D01*
G01X1102018Y929101D02*
X1093837D01*
G01X1102019Y945834D02*
X1093909D01*
G01X1102019Y942487D02*
X1093858D01*
G01X1102019Y979298D02*
X1093858D01*
G01X1102019Y972605D02*
X1093858D01*
G01X1102019Y992684D02*
X1093858D01*
G01X1102019Y985991D02*
X1093858D01*
G01X1102019Y1046227D02*
X1093858D01*
G01X1102019Y1039534D02*
X1093858D01*
G01X1102019Y1032841D02*
X1093858D01*
G01X1094005Y1056266D02*
X1100709D01*
G01X1102019Y1069653D02*
X1093909D01*
G01X1102019Y1066306D02*
X1092921D01*
G01X1102018Y1076345D02*
X1093837D01*
G01X1102168Y1093078D02*
X1093909D01*
G01X1102019Y1089731D02*
X1093858D01*
G01X1102019Y1079692D02*
X1093840D01*
G01X1102019Y1106464D02*
X1093909D01*
G01X1102019Y1103117D02*
X1093858D01*
G01X1102019Y1126542D02*
X1093858D01*
G01X1102019Y1116503D02*
X1093840D01*
G01X1102019Y1113157D02*
X1102018Y1113156D01*
X1093837D01*
G01X1102019Y1139928D02*
X1093858D01*
G01X1102019Y1129889D02*
X1093909D01*
G01X1102019Y1143275D02*
X1093909D01*
G01X1102019Y1153314D02*
X1093840D01*
G01X1102019Y1149968D02*
X1093836D01*
G01X1102019Y1176739D02*
X1093858D01*
G01X1102019Y1166700D02*
X1093909D01*
G01X1102019Y1163353D02*
X1093858D01*
G01X1102019Y1180086D02*
X1093909D01*
G01X1102019Y1190125D02*
X1093840D01*
G01X1102019Y1186779D02*
X1093836D01*
G01X1102019Y1203511D02*
X1093909D01*
G01X1102019Y1200164D02*
X1093858D01*
G01X1102019Y1216897D02*
X1093909D01*
G01X1102019Y1213550D02*
X1093858D01*
G01X1102019Y1223590D02*
X1093836D01*
G01X1102019Y1240322D02*
X1093909D01*
G01X1102019Y1236975D02*
X1093858D01*
G01X1102019Y1226936D02*
X1093840D01*
G01X1116636Y1250343D02*
X1110131D01*
G01X1147861Y778511D02*
X1139715D01*
G01X1146559Y771818D02*
X1138742D01*
X1138707Y771783D01*
G01X1147861Y788550D02*
X1138752D01*
G01X1146559Y795243D02*
X1138742D01*
X1138707Y795208D01*
G01X1146588Y791897D02*
X1139677D01*
G01X1147861Y815322D02*
X1139715D01*
G01X1146559Y808629D02*
X1138742D01*
X1138707Y808594D01*
G01X1147861Y801936D02*
X1139715D01*
G01X1146559Y832054D02*
X1138742D01*
X1138707Y832019D01*
G01X1147861Y825361D02*
X1138752D01*
G01X1146588Y828708D02*
X1139677D01*
G01X1146559Y845440D02*
X1138742D01*
X1138707Y845405D01*
G01X1147861Y838747D02*
X1139715D01*
G01X1147861Y852133D02*
X1139715D01*
G01X1147861Y862172D02*
X1138752D01*
G01X1146588Y865519D02*
X1139677D01*
G01X1146559Y882251D02*
X1138742D01*
X1138707Y882216D01*
G01X1147861Y875558D02*
X1139715D01*
G01X1146559Y868865D02*
X1138742D01*
X1138707Y868830D01*
G01X1147861Y888944D02*
X1139715D01*
G01X1147861Y898983D02*
X1138752D01*
G01X1146588Y902330D02*
X1139677D01*
G01X1147861Y912369D02*
X1139715D01*
G01X1146559Y905676D02*
X1138742D01*
X1138707Y905641D01*
G01X1147861Y925755D02*
X1139715D01*
G01X1146559Y919062D02*
X1138742D01*
X1138707Y919027D01*
G01X1146559Y942487D02*
X1138742D01*
X1138707Y942452D01*
G01X1147861Y935794D02*
X1138752D01*
G01X1146588Y939141D02*
X1139677D01*
G01X1147861Y949180D02*
X1139715D01*
G01X1146559Y979298D02*
X1138742D01*
X1138707Y979263D01*
G01X1146559Y972605D02*
X1138742D01*
X1138707Y972570D01*
G01X1146559Y992684D02*
X1138742D01*
X1138707Y992649D01*
G01X1146559Y985991D02*
X1138742D01*
X1138707Y985956D01*
G01X1146559Y1026149D02*
X1138742D01*
X1138707Y1026114D01*
G01X1146559Y1019456D02*
X1138795D01*
G01X1146559Y1039534D02*
X1138742D01*
X1138707Y1039499D01*
G01X1146559Y1032842D02*
X1138742D01*
X1138707Y1032807D01*
G01X1146559Y1059613D02*
X1138742D01*
G01X1146559Y1046227D02*
X1138742D01*
X1138707Y1046192D01*
G01X1147861Y1072999D02*
X1139715D01*
G01X1146559Y1066306D02*
X1138742D01*
X1138707Y1066271D01*
G01X1146559Y1089731D02*
X1138742D01*
X1138707Y1089696D01*
G01X1147861Y1083038D02*
X1138752D01*
G01X1146588Y1086385D02*
X1139677D01*
G01X1147861Y1096424D02*
X1139715D01*
G01X1147861Y1109810D02*
X1139715D01*
G01X1146559Y1103117D02*
X1138742D01*
X1138707Y1103082D01*
G01X1146559Y1126542D02*
X1138742D01*
X1138707Y1126507D01*
G01X1147861Y1119849D02*
X1138752D01*
G01X1146588Y1123196D02*
X1139677D01*
G01X1146559Y1139928D02*
X1138742D01*
X1138707Y1139893D01*
G01X1147861Y1133235D02*
X1139715D01*
G01X1147861Y1146621D02*
X1139715D01*
G01X1147861Y1156660D02*
X1138752D01*
G01X1146588Y1160007D02*
X1139677D01*
G01X1147861Y1170046D02*
X1139715D01*
G01X1146559Y1163353D02*
X1138742D01*
X1138707Y1163318D01*
G01X1147861Y1183432D02*
X1139715D01*
G01X1146559Y1176739D02*
X1138742D01*
X1138707Y1176704D01*
G01X1147861Y1193471D02*
X1138752D01*
G01X1147861Y1206857D02*
X1139715D01*
G01X1146559Y1200164D02*
X1138742D01*
X1138707Y1200129D01*
G01X1146588Y1196818D02*
X1139677D01*
G01X1147861Y1220243D02*
X1139715D01*
G01X1146559Y1213550D02*
X1138742D01*
X1138707Y1213515D01*
G01X1146559Y1236975D02*
X1138742D01*
X1138707Y1236940D01*
G01X1147861Y1230282D02*
X1138752D01*
G01X1146588Y1233629D02*
X1139677D01*
G01X1146336Y1250343D02*
X1139981D01*
G01X1147861Y1243668D02*
X1139715D01*
G01X1161419Y771817D02*
X1153258D01*
G01X1161419Y775164D02*
X1153309D01*
G01X1161419Y785204D02*
X1153240D01*
G01X1161419Y781858D02*
X1161418Y781857D01*
X1153237D01*
G01X1161419Y798590D02*
X1153309D01*
G01X1161419Y795243D02*
X1153258D01*
G01X1161419Y811975D02*
X1153309D01*
G01X1161419Y808628D02*
X1153258D01*
G01X1161419Y818669D02*
X1161418Y818668D01*
X1153237D01*
G01X1161419Y835401D02*
X1153309D01*
G01X1161419Y832054D02*
X1153258D01*
G01X1161419Y822015D02*
X1153240D01*
G01X1161419Y848786D02*
X1153309D01*
G01X1161419Y845439D02*
X1153258D01*
G01X1161419Y868865D02*
X1153258D01*
G01X1161419Y858826D02*
X1153240D01*
G01X1161419Y855480D02*
X1161418Y855479D01*
X1153237D01*
G01X1161419Y872212D02*
X1153309D01*
G01X1161419Y882250D02*
X1153258D01*
G01X1161419Y885597D02*
X1153309D01*
G01X1161419Y895637D02*
X1153240D01*
G01X1161419Y892291D02*
X1161418Y892290D01*
X1153237D01*
G01X1161419Y909023D02*
X1153309D01*
G01X1161419Y905676D02*
X1153258D01*
G01X1161419Y922408D02*
X1153309D01*
G01X1161419Y919062D02*
X1153258D01*
G01X1161419Y932448D02*
X1153240D01*
G01X1161419Y929102D02*
X1161418Y929101D01*
X1153237D01*
G01X1161419Y945834D02*
X1153309D01*
G01X1161419Y942487D02*
X1153258D01*
G01X1161419Y979298D02*
X1153258D01*
G01X1161419Y972605D02*
X1153258D01*
G01X1161419Y992684D02*
X1153258D01*
G01X1161419Y985991D02*
X1153258D01*
G01X1161419Y1032841D02*
X1153258D01*
G01X1161419Y1046227D02*
X1153258D01*
G01X1161419Y1039534D02*
X1153258D01*
G01X1153376Y1059613D02*
X1160017D01*
G01X1161419Y1069653D02*
X1153309D01*
G01X1161419Y1066306D02*
X1153258D01*
G01X1153240Y1079692D02*
X1161419D01*
G01Y1076346D02*
X1161418Y1076345D01*
X1153237D01*
G01X1153309Y1093078D02*
X1161419D01*
G01X1153258Y1089731D02*
X1161419D01*
G01Y1106464D02*
X1153309D01*
G01X1161419Y1103117D02*
X1153258D01*
G01X1161419Y1126542D02*
X1153258D01*
G01X1153240Y1116503D02*
X1161419D01*
G01X1153237Y1113156D02*
X1161418D01*
X1161419Y1113157D01*
G01Y1143275D02*
X1153309D01*
G01X1161419Y1139928D02*
X1153258D01*
G01X1161419Y1129889D02*
X1153309D01*
G01X1153240Y1153314D02*
X1161419D01*
G01Y1149968D02*
X1153236D01*
G01X1161419Y1176739D02*
X1153258D01*
G01X1161419Y1166700D02*
X1153309D01*
G01X1161419Y1163353D02*
X1153258D01*
G01X1161419Y1180086D02*
X1153309D01*
G01X1153240Y1190125D02*
X1161419D01*
G01Y1186779D02*
X1153236D01*
G01X1161419Y1203511D02*
X1153309D01*
G01X1161419Y1200164D02*
X1153258D01*
G01X1161419Y1216897D02*
X1153309D01*
G01X1161419Y1213550D02*
X1153258D01*
G01X1161419Y1226936D02*
X1153240D01*
G01X1161419Y1223590D02*
X1153236D01*
G01X1153309Y1240322D02*
X1161419D01*
G01Y1236975D02*
X1153258D01*
G01X1169681Y1250343D02*
X1176036D01*
G01X1183018Y1059613D02*
X1189754D01*
G01X1198107Y778482D02*
X1198202Y778511D01*
X1205959D01*
G01X1198107Y771776D02*
X1198241Y771817D01*
X1205863D01*
G01X1198107Y788530D02*
X1198127Y788550D01*
X1207237D01*
X1207261Y788526D01*
G01X1198107Y801890D02*
X1198257Y801936D01*
X1205863D01*
G01X1198277Y795208D02*
X1198391Y795243D01*
X1207035D01*
G01X1198132Y791897D02*
X1207222D01*
G01X1198107Y815289D02*
X1198139Y815321D01*
X1205863D01*
G01X1198107Y808583D02*
X1198257Y808629D01*
X1205863D01*
G01X1198107Y832030D02*
X1198185Y832054D01*
X1205863D01*
G01X1198107Y825311D02*
X1198157Y825361D01*
X1207237D01*
X1207261Y825337D01*
G01X1198132Y828708D02*
X1207222D01*
G01X1198139Y852087D02*
X1198185Y852133D01*
X1205959D01*
G01X1198107Y845384D02*
X1198163Y845440D01*
X1205959D01*
G01X1198220Y838584D02*
X1198486D01*
X1199019Y838747D01*
X1205863D01*
X1206121Y838673D01*
G01X1198127Y862172D02*
X1205989D01*
G01X1198107Y865544D02*
X1198132Y865519D01*
X1207222D01*
X1207261Y865558D01*
G01X1205863Y882250D02*
X1199019D01*
G01Y875558D02*
X1205863D01*
G01X1199019Y868865D02*
X1205688D01*
G01X1205790Y888943D02*
X1199019D01*
G01X1205989Y898983D02*
X1198177D01*
G01X1205988Y902330D02*
X1199077D01*
G01X1206086Y912305D02*
X1205863Y912369D01*
X1199019D01*
X1198486Y912206D01*
X1198320D01*
G01X1206065Y905618D02*
X1205863Y905676D01*
X1199019D01*
X1198486Y905513D01*
X1198220D01*
G01X1199019Y925754D02*
X1205863D01*
G01X1199019Y919062D02*
X1205863D01*
G01X1199019Y949180D02*
X1205863D01*
G01X1199019Y942487D02*
X1205863D01*
G01X1196741Y935794D02*
X1208299D01*
G01X1196741Y939141D02*
X1208299D01*
G01X1198650Y965912D02*
X1206710D01*
G01X1212248D02*
X1220212D01*
G01X1228272D02*
X1236580D01*
G01X1264115Y967870D02*
X1264161Y967889D01*
X1264607Y968074D01*
X1267400D01*
X1270104Y970778D01*
X1295052D01*
X1303076Y962754D01*
X1306366D01*
G01X1198491Y982644D02*
X1207020D01*
G01X1198421Y975951D02*
X1207020D01*
G01X1198320Y992684D02*
X1207020D01*
G01X1198320Y989337D02*
X1207120D01*
G01X1198320Y1029495D02*
X1207020D01*
G01X1198320Y1026148D02*
X1206920D01*
G01X1198471Y1046227D02*
X1207120D01*
G01X1198320Y1042880D02*
X1207120D01*
G01X1198320Y1036188D02*
X1207120D01*
G01X1207260Y1059613D02*
X1199318D01*
G01X1198514Y1052920D02*
X1206828D01*
G01X1211826Y1056266D02*
X1220400D01*
G01X1227952D02*
X1237382D01*
G01X1292699Y1023286D02*
X1293666Y1022319D01*
X1306099D01*
G01X1198423Y1072999D02*
X1207020D01*
G01X1199108Y1066306D02*
X1207120D01*
G01X1198107Y1096424D02*
X1207120D01*
G01X1200219Y1089731D02*
X1207120D01*
G01X1196758Y1083038D02*
X1207420D01*
G01X1196758Y1086385D02*
X1207420D01*
G01X1199233Y1109810D02*
X1207020D01*
G01X1198182Y1103117D02*
X1207120D01*
G01X1198387Y1126542D02*
X1207220D01*
G01X1198107Y1119807D02*
X1198110D01*
X1198152Y1119849D01*
X1207224D01*
G01X1198107Y1123233D02*
X1198144Y1123196D01*
X1207232D01*
G01X1198379Y1139928D02*
X1207120D01*
G01X1198443Y1133235D02*
X1207125D01*
G01X1198437Y1146621D02*
X1206985D01*
G01X1198107Y1156618D02*
X1198110D01*
X1198152Y1156660D01*
X1207224D01*
X1207261Y1156623D01*
G01X1198107Y1160044D02*
X1198144Y1160007D01*
X1207232D01*
X1207261Y1160036D01*
G01X1207020Y1176739D02*
X1198320D01*
G01Y1170046D02*
X1207120D01*
G01X1198303Y1163353D02*
X1207020D01*
G01X1207120Y1183432D02*
X1198320D01*
G01X1207261Y1193471D02*
X1198152D01*
G01X1206920Y1206857D02*
X1198320D01*
G01X1207020Y1200164D02*
X1198320D01*
G01X1205988Y1196818D02*
X1199077D01*
G01X1198420Y1220243D02*
X1206920D01*
G01X1198320Y1213550D02*
X1207020D01*
G01X1198241Y1236975D02*
X1207020D01*
G01X1198107Y1230240D02*
X1198110D01*
X1198152Y1230282D01*
X1207224D01*
X1207261Y1230245D01*
G01X1198107Y1233666D02*
X1198144Y1233629D01*
X1207232D01*
X1207261Y1233658D01*
G01X1199381Y1250343D02*
X1205736D01*
G01X1198420Y1243668D02*
X1206920D01*
G01X1212709Y771817D02*
X1219747D01*
G01X1308346Y863371D02*
X1306218Y861243D01*
Y850065D01*
X1312235Y844048D01*
Y842652D01*
G01X1236909Y778510D02*
X1228840D01*
G01X1310050Y861667D02*
X1308618Y860235D01*
Y851065D01*
X1313055Y846628D01*
X1313966D01*
X1317273Y843321D01*
Y842652D01*
G01X1236920Y771817D02*
X1227845D01*
X1227820Y771792D01*
G01X1212694Y778515D02*
X1212709Y778510D01*
X1219746D01*
X1219771Y778535D01*
G01X1236920Y788550D02*
X1228136D01*
X1228069Y788483D01*
X1228020D01*
G01X1211665Y785232D02*
X1211693Y785204D01*
X1220819D01*
G01X1211690Y781857D02*
X1220818D01*
X1220819Y781858D01*
G01X1306691Y871926D02*
X1299018Y864253D01*
Y844127D01*
X1299575Y843570D01*
Y842652D01*
G01X1236660Y798589D02*
X1228804D01*
X1228581Y798658D01*
G01X1211920Y801936D02*
X1220620D01*
G01X1211820Y795243D02*
X1220683D01*
X1220819Y795379D01*
G01X1236820Y791922D02*
X1236794D01*
X1236768Y791896D01*
X1228177D01*
X1228120Y791953D01*
G01X1304794Y902823D02*
X1294158Y892187D01*
Y883765D01*
X1287838Y877445D01*
Y846787D01*
X1285427Y844376D01*
G01X1236920Y815174D02*
X1235959D01*
X1235604Y815321D01*
X1228840D01*
X1228365Y815157D01*
X1227720D01*
G01X1307665Y899565D02*
X1304933D01*
X1296558Y891190D01*
Y882769D01*
X1290238Y876449D01*
Y842064D01*
X1288145Y839971D01*
G01X1235988Y808628D02*
X1228840D01*
X1228671Y808569D01*
G01X1211820Y815321D02*
X1219701D01*
G01X1211920Y808628D02*
X1220620D01*
G01X1304993Y873624D02*
X1296618Y865249D01*
Y850418D01*
X1295752Y849552D01*
Y847432D01*
X1296618Y846566D01*
Y845775D01*
X1294607Y843764D01*
Y843763D01*
X1294539Y843695D01*
Y842653D01*
G01X1236460Y801936D02*
X1228840D01*
X1228665Y801875D01*
G01X1211665Y818606D02*
X1211727Y818668D01*
X1220778D01*
X1220819Y818627D01*
G01X1228360Y832054D02*
X1235604D01*
G01X1279910Y858208D02*
X1280638Y858936D01*
Y880431D01*
X1286958Y886751D01*
Y895175D01*
X1303588Y911805D01*
X1304965D01*
G01X1211901Y832054D02*
X1220598D01*
G01X1236820Y825330D02*
X1236789D01*
X1236758Y825361D01*
X1228057D01*
X1228020Y825324D01*
G01X1211665Y822073D02*
X1211936Y822015D01*
X1220761D01*
X1220819Y822073D01*
G01X1236720Y828785D02*
X1236642D01*
X1236564Y828707D01*
X1228329D01*
X1228020Y828743D01*
G01X1306666Y919419D02*
X1302769D01*
X1279916Y896566D01*
G01X1279348Y895998D02*
Y893459D01*
X1277087Y891198D01*
G01X1236564Y845439D02*
X1228840D01*
G01X1212709Y852132D02*
X1219747D01*
G01X1211820Y845439D02*
X1219701D01*
G01X1304966Y914404D02*
X1302791D01*
X1284558Y896171D01*
Y887747D01*
X1278238Y881427D01*
Y865420D01*
X1276939Y864121D01*
X1273663D01*
G01X1236554Y838747D02*
X1228840D01*
G01X1211953D02*
X1220728D01*
G01X1211920Y869201D02*
X1212407D01*
X1212743Y868865D01*
X1219701D01*
X1219801Y868965D01*
G01X1304966Y923131D02*
X1303084D01*
X1277771Y897818D01*
X1277547D01*
X1276747Y897018D01*
X1276665D01*
G01X1236684Y852132D02*
X1228840D01*
G01X1236920Y862138D02*
X1236410D01*
X1236376Y862172D01*
X1227746D01*
X1227720Y862146D01*
G01X1211665Y858854D02*
X1211693Y858826D01*
X1220751D01*
X1220784Y858859D01*
X1220819D01*
G01X1236961Y865548D02*
X1236931Y865518D01*
X1227845D01*
X1227820Y865543D01*
G01X1211665Y855458D02*
X1211686Y855479D01*
X1220744D01*
X1220773Y855450D01*
X1220819D01*
G01X1212751Y875598D02*
X1212885Y875558D01*
X1219702D01*
G01X1220520Y882253D02*
X1219605D01*
X1219602Y882250D01*
X1212020D01*
G01X1304966Y933009D02*
X1299378D01*
X1284125Y917756D01*
X1282466D01*
G01X1236496Y875558D02*
X1228840D01*
G01X1228020Y872256D02*
X1228065Y872211D01*
X1235415D01*
G01X1276665Y911394D02*
X1281159D01*
X1300374Y930609D01*
X1304966D01*
G01X1220520Y888944D02*
X1212020D01*
G01X1220819Y895637D02*
X1213009D01*
G01X1220819Y892291D02*
X1220818Y892290D01*
X1211943D01*
X1211751Y892245D01*
G01X1211920Y919062D02*
X1220520D01*
G01X1220420Y912369D02*
X1211920D01*
G01X1220520Y905676D02*
X1212020D01*
G01X1303668Y939804D02*
X1297024D01*
X1295212Y937992D01*
X1293288D01*
G01X1235604Y925754D02*
X1228840D01*
G01X1307666Y937813D02*
X1305549D01*
X1305140Y937404D01*
X1298021D01*
X1293399Y932782D01*
X1292628D01*
G01X1236680Y919062D02*
X1228087D01*
G01X1212020Y925754D02*
X1220520D01*
G01X1211177Y932448D02*
X1221830D01*
G01X1211177Y929101D02*
X1221830D01*
G01X1299629Y953659D02*
X1297766D01*
G01X1235604Y942487D02*
X1228053D01*
G01X1211595Y949180D02*
X1220520D01*
G01X1211820Y942487D02*
X1220520D01*
G01X1238022Y935794D02*
X1226466D01*
G01Y939140D02*
X1238022D01*
G01X1304950Y951736D02*
X1299728Y956958D01*
Y959734D01*
X1298615Y960847D01*
X1297766D01*
G01X1236632Y949180D02*
X1228840D01*
G01X1306366Y960245D02*
X1302188D01*
X1294055Y968378D01*
X1271540D01*
X1266309Y963147D01*
X1264875Y962553D01*
G01X1236920Y959219D02*
X1227820D01*
G01X1220520Y962565D02*
X1212128D01*
G01X1306366Y969174D02*
X1305148D01*
X1297544Y976778D01*
X1268932D01*
X1268063Y977647D01*
G01X1235546Y982644D02*
X1228581D01*
G01X1212020Y979298D02*
X1220520D01*
G01X1307366Y966610D02*
X1304316D01*
X1296548Y974378D01*
X1264063D01*
X1263479Y974962D01*
G01X1236448Y975951D02*
X1228084D01*
G01X1307366Y964026D02*
X1303503D01*
X1295551Y971978D01*
X1269117D01*
X1267713Y970574D01*
X1263815D01*
X1263595Y970483D01*
X1263548Y970464D01*
G01X1236532Y969258D02*
X1228144D01*
G01X1212020Y972605D02*
X1220420D01*
G01X1306467Y981579D02*
X1278807D01*
X1277650Y982736D01*
G01X1211820Y992684D02*
X1220620D01*
G01X1306603Y975689D02*
X1303114Y979178D01*
X1273868D01*
X1272980Y980066D01*
G01X1236920Y989337D02*
X1227956D01*
G01X1211920Y985991D02*
X1220520D01*
G01X1211955Y1029495D02*
X1220520D01*
G01X1304447Y1004831D02*
X1298959Y1010319D01*
X1270658D01*
X1269962Y1010457D01*
X1267360Y1011535D01*
X1267116Y1011636D01*
X1267068Y1011753D01*
G01X1236752Y1029495D02*
X1228116D01*
G01X1303598Y1003982D02*
X1298461Y1009119D01*
X1270066D01*
X1269756Y1008809D01*
X1268267D01*
G01X1236709Y1025741D02*
X1235727Y1026148D01*
X1228228D01*
G01X1211869Y1042880D02*
X1220773D01*
G01X1228172Y1039534D02*
X1236682D01*
G01X1278409Y1015794D02*
X1279084Y1015119D01*
X1300951D01*
X1305179Y1010891D01*
X1308367D01*
G01X1211920Y1036188D02*
X1220620D01*
G01X1305995Y1006679D02*
X1299955Y1012719D01*
X1273262D01*
X1272033Y1013948D01*
Y1014047D01*
X1272021Y1014059D01*
G01X1236398Y1032841D02*
X1228188D01*
G01X1228210Y1046227D02*
X1236668D01*
G01X1283516Y1018202D02*
X1284199Y1017519D01*
X1301947D01*
X1305871Y1013595D01*
X1310654D01*
G01X1305313Y1015851D02*
X1302445Y1018719D01*
X1286573D01*
X1285603Y1019689D01*
G01X1236626Y1049573D02*
X1228308D01*
G01X1220819D02*
X1212021D01*
G01X1305938Y1018622D02*
X1303441Y1021119D01*
X1291484D01*
X1291167Y1021250D01*
G01X1236400Y1052920D02*
X1228238D01*
G01X1211521Y1059668D02*
X1211687Y1059613D01*
X1219878D01*
X1219881Y1059616D01*
X1220819D01*
G01X1228033Y1072999D02*
X1236773D01*
G01X1271738Y1052049D02*
X1277121D01*
X1299372Y1029798D01*
X1301768D01*
G01X1304467Y1027396D02*
X1298376D01*
X1276193Y1049579D01*
X1274830D01*
X1272036Y1046785D01*
G01X1236465Y1069652D02*
X1228408D01*
G01X1212450Y1069587D02*
X1212663Y1069652D01*
X1220720D01*
G01X1211736Y1066306D02*
X1220720D01*
G01X1210359Y1079692D02*
X1221837D01*
G01X1210359Y1076346D02*
X1212636D01*
X1212637Y1076345D01*
X1221837D01*
G01X1228840Y1093077D02*
X1236790D01*
G01X1275728Y1065171D02*
X1276371Y1064528D01*
Y1063494D01*
X1277006Y1062859D01*
Y1062352D01*
X1301286Y1038072D01*
G01X1211920Y1093077D02*
X1220720D01*
G01X1211805Y1089731D02*
X1220553D01*
G01X1237198Y1083038D02*
X1227385D01*
G01X1237198Y1086384D02*
X1227385D01*
G01X1301655Y1041100D02*
X1279586Y1063169D01*
X1275837Y1072220D01*
X1273820Y1074237D01*
G01X1235628Y1096424D02*
X1228964D01*
G01X1228718Y1109783D02*
X1228804Y1109810D01*
X1235415D01*
X1235584Y1109772D01*
G01X1266821Y1103175D02*
X1267280Y1102716D01*
X1267847D01*
X1268492Y1103361D01*
X1269123D01*
X1269820Y1102664D01*
Y1101356D01*
X1269490Y1101026D01*
Y1100594D01*
X1270977Y1099107D01*
X1272994Y1088966D01*
X1278589Y1078503D01*
X1304454Y1052638D01*
G01X1306468Y1045474D02*
X1305714D01*
X1305237Y1045951D01*
Y1048456D01*
X1276633Y1077060D01*
X1270708Y1088145D01*
X1268981Y1096824D01*
X1266899Y1098906D01*
X1263961D01*
X1263257Y1099610D01*
G01X1235711Y1106508D02*
X1235604Y1106463D01*
X1228840D01*
X1228607Y1106544D01*
G01X1212509Y1106463D02*
X1219701D01*
X1219705Y1106459D01*
G01X1212784Y1103117D02*
X1219796D01*
X1219904Y1103139D01*
G01X1228123Y1129888D02*
X1236961D01*
G01X1273585Y1115869D02*
X1275745Y1113709D01*
X1276361Y1112221D01*
Y1109596D01*
X1280010Y1091258D01*
X1284581Y1082705D01*
X1305851Y1061435D01*
G01X1212422Y1126605D02*
X1212612Y1126542D01*
X1219406D01*
X1219769Y1126615D01*
G01X1236920Y1119780D02*
X1236851Y1119849D01*
X1227986D01*
X1227920Y1119783D01*
G01X1211665Y1116541D02*
X1211671D01*
X1211709Y1116503D01*
X1220739D01*
X1220777Y1116541D01*
X1220819D01*
G01X1236720Y1123223D02*
X1236692D01*
X1236664Y1123195D01*
X1227866D01*
X1227795Y1123266D01*
X1227720D01*
G01X1211688Y1113115D02*
X1211730Y1113157D01*
X1220751D01*
X1220794Y1113114D01*
X1220819D01*
G01X1309346Y1066530D02*
X1307885Y1067991D01*
X1289233Y1086639D01*
X1285777Y1093097D01*
X1282770Y1108159D01*
Y1128685D01*
X1282292Y1129163D01*
G01X1235654Y1143295D02*
X1235604Y1143274D01*
X1228840D01*
X1228688Y1143327D01*
G01X1212023Y1143274D02*
X1220773D01*
G01X1211869Y1139928D02*
X1220620D01*
G01X1307549Y1063133D02*
X1286529Y1084153D01*
X1282297Y1092072D01*
X1278761Y1109845D01*
Y1117861D01*
X1277169Y1119453D01*
G01X1236920Y1133235D02*
X1228612D01*
G01X1212566Y1129858D02*
X1212663Y1129888D01*
X1220695D01*
G01X1228240Y1149967D02*
X1235924D01*
G01X1284769Y1138583D02*
X1285170Y1138182D01*
Y1108402D01*
X1288064Y1093915D01*
X1291176Y1088099D01*
X1304096Y1075180D01*
G01X1236920Y1156660D02*
X1228732D01*
X1228141Y1156523D01*
X1227920D01*
G01X1211665Y1153352D02*
X1211671D01*
X1211709Y1153314D01*
X1220739D01*
X1220777Y1153352D01*
X1220819D01*
G01X1236920Y1160006D02*
X1228731D01*
X1228044Y1160152D01*
X1227720D01*
G01X1211665Y1149945D02*
X1211688Y1149968D01*
X1220751D01*
X1220794Y1149925D01*
X1220819D01*
G01X1220620Y1176739D02*
X1211820D01*
G01X1309197Y1083681D02*
X1298978Y1093900D01*
X1297210Y1097198D01*
X1294770Y1109401D01*
Y1155305D01*
X1293446Y1156629D01*
G01X1236376Y1170046D02*
X1228226D01*
G01X1307499Y1081982D02*
X1297025Y1092456D01*
X1294926Y1096370D01*
X1292370Y1109158D01*
Y1150571D01*
X1291529Y1151412D01*
G01X1236548Y1166699D02*
X1228362D01*
G01X1211820D02*
X1220620D01*
G01X1211820Y1163353D02*
X1220620D01*
G01X1220773Y1180085D02*
X1211920D01*
G01X1220819Y1190125D02*
X1212640D01*
G01X1220819Y1186779D02*
X1212636D01*
G01X1220773Y1203510D02*
X1211920D01*
G01X1220620Y1200164D02*
X1211820D01*
G01X1228270Y1220243D02*
X1236396D01*
G01X1297508Y1168193D02*
X1299582Y1166119D01*
X1300570Y1163733D01*
Y1110401D01*
X1302800Y1099265D01*
X1305241Y1096824D01*
G01X1303502Y1095086D02*
X1300608Y1097980D01*
X1298170Y1110150D01*
Y1160404D01*
X1295895Y1162679D01*
G01X1236564Y1216896D02*
X1228250D01*
G01X1211720D02*
X1220520D01*
G01X1211920Y1213550D02*
X1220520D01*
G01X1211665Y1226974D02*
X1211671D01*
X1211709Y1226936D01*
X1220739D01*
X1220777Y1226974D01*
X1220819D01*
G01X1211665Y1223567D02*
X1211688Y1223590D01*
X1220751D01*
X1220794Y1223547D01*
X1220819D01*
G01X1311937Y1101427D02*
X1311624Y1101740D01*
X1310738D01*
X1309630Y1102848D01*
X1309514Y1103429D01*
X1309929Y1104052D01*
X1309726Y1105067D01*
X1309103Y1105482D01*
X1307770Y1112151D01*
Y1170233D01*
X1307462Y1171462D01*
X1306904Y1171795D01*
X1306650Y1172814D01*
X1307237Y1173798D01*
X1306972Y1174859D01*
X1306482Y1175151D01*
X1305975Y1175023D01*
X1305489Y1175313D01*
X1305338Y1175921D01*
X1306042Y1177093D01*
X1305973Y1177655D01*
X1305473Y1178155D01*
G01X1236424Y1240321D02*
X1228284D01*
G01X1211820D02*
X1220520D01*
G01X1211920Y1236975D02*
X1220520D01*
G01X1236720Y1230249D02*
X1236659D01*
X1236626Y1230282D01*
X1228304D01*
X1228281Y1230259D01*
X1228120D01*
G01Y1233686D02*
X1228274D01*
X1228332Y1233628D01*
X1236546D01*
X1236568Y1233650D01*
X1236620D01*
G01X1312503Y1106520D02*
X1311104Y1107919D01*
X1310170Y1112572D01*
Y1176110D01*
X1309022Y1177258D01*
Y1178282D01*
X1310199Y1179459D01*
Y1180569D01*
X1309043Y1181725D01*
G01X1236500Y1243668D02*
X1228324D01*
G01X1310899Y860818D02*
X1309818Y859737D01*
Y851567D01*
X1313466Y847919D01*
X1315198D01*
X1319793Y843324D01*
Y842652D01*
G01X1309195Y862522D02*
X1307418Y860745D01*
Y850565D01*
X1314753Y843230D01*
Y842652D01*
G01X1305842Y872775D02*
X1297818Y864751D01*
Y844045D01*
X1297057Y843284D01*
Y842653D01*
G01X1307540Y871077D02*
X1300218Y863755D01*
Y847553D01*
X1302094Y845677D01*
Y842652D01*
G01X1305644Y901974D02*
X1295358Y891688D01*
Y883267D01*
X1289038Y876947D01*
Y844425D01*
X1286365Y841752D01*
G01X1307665Y898325D02*
X1305391D01*
X1297758Y890692D01*
Y882271D01*
X1291438Y875951D01*
Y839703D01*
X1289926Y838191D01*
G01X1304965Y910604D02*
X1304085D01*
X1288158Y894677D01*
Y886253D01*
X1281838Y879933D01*
Y856511D01*
X1279599Y854272D01*
G01X1279596D02*
X1279221Y853897D01*
G01X1304966Y921931D02*
X1303583D01*
X1278068Y896416D01*
Y895760D01*
X1276665Y894357D01*
G01X1307066Y917819D02*
X1302867D01*
X1281116Y896068D01*
Y891661D01*
X1277995Y888540D01*
G01X1304965Y913029D02*
X1303114D01*
X1285758Y895673D01*
Y887249D01*
X1279438Y880929D01*
Y861385D01*
X1277565Y859512D01*
G01X1304966Y929409D02*
X1300872D01*
X1280247Y908784D01*
X1276665D01*
G01X1304966Y931809D02*
X1299876D01*
X1281977Y913910D01*
X1280268D01*
G01X1304172Y938604D02*
X1297523D01*
X1294221Y935302D01*
X1293288D01*
G01X1292628Y930263D02*
X1293383D01*
X1294605Y931485D01*
Y932289D01*
X1298520Y936204D01*
X1305819D01*
X1306227Y936612D01*
X1307666D01*
G01X1304251Y950736D02*
X1298810Y956177D01*
Y956183D01*
X1297766Y957227D01*
G01X1302845Y948745D02*
X1300588Y951002D01*
X1297866D01*
G01X1306366Y961548D02*
X1302584D01*
X1294554Y969578D01*
X1270722D01*
X1267562Y966418D01*
X1264214Y965029D01*
X1264164Y965008D01*
G01X1307366Y967821D02*
X1304803D01*
X1297046Y975578D01*
X1266566D01*
X1265744Y976400D01*
G01X1307366Y965354D02*
X1303873D01*
X1296049Y973178D01*
X1268567D01*
X1268040Y972651D01*
X1262167D01*
G01X1305867Y980378D02*
X1276434D01*
X1275613Y981199D01*
G01X1306491Y970777D02*
X1306299Y970969D01*
X1305051D01*
X1298042Y977978D01*
X1271468D01*
X1270230Y979216D01*
G01X1309619Y1012121D02*
X1305647D01*
X1301449Y1016319D01*
X1281828D01*
X1280681Y1017466D01*
G01X1308067Y1009671D02*
X1304701D01*
X1300453Y1013919D01*
X1276770D01*
X1275259Y1014545D01*
X1274377Y1015427D01*
G01X1305296Y1005680D02*
X1299457Y1011519D01*
X1271278D01*
X1270689Y1011763D01*
X1269682Y1012770D01*
G01X1305739Y1017123D02*
X1302943Y1019919D01*
X1289221D01*
X1288731Y1020122D01*
G01X1306634Y1029087D02*
X1306144Y1028597D01*
X1298874D01*
X1276652Y1050819D01*
X1273314D01*
X1273137Y1050642D01*
Y1049912D01*
X1272736Y1049511D01*
X1271738D01*
G01X1304467Y1026195D02*
X1297878D01*
X1276088Y1047985D01*
X1275002D01*
X1273976Y1046959D01*
Y1045137D01*
X1273830Y1044991D01*
G01X1301447Y1039610D02*
X1278496Y1062561D01*
X1276083Y1068388D01*
X1275728Y1068743D01*
G01X1306368Y1036518D02*
X1305862Y1036619D01*
X1301041D01*
X1279207Y1058453D01*
X1278608D01*
X1278071Y1058990D01*
Y1059258D01*
X1275728Y1061601D01*
G01X1307350Y1047234D02*
X1306750D01*
X1306464Y1047520D01*
Y1048930D01*
X1277607Y1077787D01*
X1271851Y1088555D01*
X1269983Y1097952D01*
X1267699Y1100236D01*
X1266199D01*
X1265041Y1101394D01*
G01X1306568Y1042921D02*
X1306214Y1043275D01*
X1303213D01*
X1302635Y1043853D01*
Y1045221D01*
X1303062Y1045648D01*
X1303614D01*
X1304014Y1046048D01*
Y1047598D01*
X1303614Y1047998D01*
X1303062D01*
X1302326Y1048734D01*
Y1049668D01*
X1275658Y1076336D01*
X1269565Y1087734D01*
X1267970Y1095748D01*
X1266294Y1097125D01*
X1265365D01*
X1264905Y1096665D01*
Y1095262D01*
X1264368Y1094725D01*
X1263452D01*
X1262598Y1095579D01*
Y1096693D01*
X1261469Y1097822D01*
G01X1306701Y1058885D02*
X1283608Y1081978D01*
X1278867Y1090847D01*
X1275236Y1109094D01*
X1274776Y1109554D01*
Y1110799D01*
X1275161Y1111184D01*
Y1111954D01*
X1274677Y1112438D01*
X1273454D01*
G01X1308647Y1065530D02*
X1307214Y1066963D01*
X1288259Y1085915D01*
X1284634Y1092687D01*
X1281570Y1108040D01*
Y1124958D01*
X1281172Y1125356D01*
G01X1306700Y1062284D02*
X1285555Y1083429D01*
X1281152Y1091668D01*
X1277561Y1109716D01*
Y1115497D01*
X1275387Y1117671D01*
G01X1308246Y1069329D02*
X1307332Y1070243D01*
X1290206Y1087365D01*
X1286922Y1093504D01*
X1283970Y1108281D01*
Y1133144D01*
X1283232Y1133882D01*
Y1134512D01*
G01X1308348Y1082831D02*
X1298000Y1093179D01*
X1296067Y1096789D01*
X1293570Y1109277D01*
Y1152933D01*
X1292960Y1153543D01*
G01X1306643Y1081127D02*
X1296060Y1091710D01*
X1293779Y1095969D01*
X1291170Y1109030D01*
Y1148186D01*
X1289737Y1149619D01*
G01X1304362Y1095945D02*
X1301709Y1098598D01*
X1299370Y1110274D01*
Y1162767D01*
X1295977Y1166160D01*
G01X1302633Y1094216D02*
X1299649Y1097200D01*
X1299464Y1097547D01*
X1296970Y1110028D01*
Y1158043D01*
X1294115Y1160898D01*
G01X1312875Y1102158D02*
X1312098Y1103205D01*
X1310262Y1106635D01*
X1309916Y1107598D01*
X1308970Y1112319D01*
Y1170342D01*
X1308398Y1174191D01*
X1307327Y1179567D01*
Y1179864D01*
X1307017Y1180174D01*
G01X1303692Y1176375D02*
X1304124Y1175943D01*
Y1175333D01*
X1306570Y1169426D01*
Y1112022D01*
X1308526Y1102246D01*
X1309745Y1101027D01*
G01X1330316Y230060D02*
Y233328D01*
G01Y237339D02*
Y233328D01*
G01X1513608Y995095D02*
X1513996Y995157D01*
X1514459Y995230D01*
X1516546Y995435D01*
X1520077Y995959D01*
X1527786Y997494D01*
X1529108Y997826D01*
X1535866Y1000626D01*
X1546373Y1011133D01*
X1547959D01*
G01X1508851Y991986D02*
X1512365Y993446D01*
X1515332Y994036D01*
X1519829Y994478D01*
X1529758Y996455D01*
X1535963Y999025D01*
X1545553Y1008615D01*
X1547667D01*
G01X1515867Y987566D02*
X1521721D01*
X1522198Y987089D01*
X1528843D01*
X1535544Y980388D01*
X1554473D01*
X1555323Y981238D01*
G01X1522467Y985620D02*
X1528512D01*
X1534944Y979188D01*
X1556852D01*
X1557663Y979999D01*
G01X1597529Y992886D02*
X1597731Y992684D01*
X1604109D01*
G01X1525012Y886296D02*
X1526170Y885138D01*
Y847587D01*
X1524427Y845844D01*
G01X1597545Y771817D02*
X1605306D01*
X1605369Y771880D01*
G01X1526251Y887534D02*
X1527370Y886415D01*
Y845170D01*
X1526207Y844007D01*
G01X1527553Y891237D02*
X1528570Y890220D01*
Y842437D01*
X1528173Y842040D01*
G01X1598518Y778510D02*
X1605306D01*
X1605369Y778573D01*
G01X1528558Y892242D02*
X1529770Y891030D01*
Y841665D01*
X1528612Y838867D01*
X1527729Y837984D01*
G01X1597388Y785286D02*
X1597471Y785203D01*
X1605300D01*
X1605369Y785272D01*
G01X1597389Y781802D02*
X1597444Y781857D01*
X1605240D01*
X1605323Y781774D01*
G01X1546475Y846658D02*
X1545170Y847963D01*
Y897614D01*
X1528266Y914518D01*
G01X1530502Y908886D02*
X1542770Y896618D01*
Y843022D01*
X1543954Y841838D01*
G01X1531351Y909735D02*
X1543970Y897116D01*
Y845455D01*
X1544964Y844461D01*
G01X1597545Y815321D02*
X1605306D01*
X1605369Y815384D01*
G01X1529653Y908037D02*
X1541570Y896120D01*
Y840514D01*
X1542100Y839984D01*
G01X1597545Y808628D02*
X1605306D01*
X1605369Y808691D01*
G01X1533111Y901393D02*
X1539370Y895134D01*
Y839144D01*
G01X1539812Y833105D02*
X1540360Y832557D01*
G01X1529762Y901346D02*
X1536970Y894138D01*
Y828651D01*
X1539679Y825942D01*
Y825348D01*
G01X1532325Y900481D02*
X1538170Y894636D01*
Y832442D01*
X1539455Y829338D01*
X1541202Y827591D01*
G01X1597545Y801936D02*
X1605306D01*
X1605369Y801999D01*
G01X1530564Y898846D02*
X1535770Y893640D01*
Y827318D01*
X1536957Y826131D01*
Y825348D01*
G01X1597545Y795243D02*
X1605306D01*
X1605369Y795306D01*
G01X1598892Y822014D02*
X1605283D01*
X1605340Y822071D01*
G01X1598385Y818668D02*
X1602622D01*
G01X1604197D02*
X1605332D01*
X1605353Y818647D01*
X1605369D01*
G01X1531666Y927909D02*
X1533479D01*
X1558170Y903218D01*
Y888055D01*
X1559617Y886608D01*
Y886607D01*
X1560321Y885903D01*
G01X1531666Y926709D02*
X1532981D01*
X1556970Y902720D01*
Y881190D01*
X1557846Y880314D01*
Y879248D01*
G01X1597388Y845513D02*
X1597462Y845439D01*
X1605329D01*
X1605369Y845479D01*
G01X1528666Y924584D02*
X1531786D01*
X1554770Y901600D01*
Y871038D01*
X1556212Y869596D01*
X1556213D01*
G01X1528666Y922087D02*
X1530887D01*
X1552370Y900604D01*
Y861240D01*
X1554014Y859596D01*
G01X1528666Y923321D02*
X1531351D01*
X1553570Y901102D01*
Y865701D01*
X1554360Y864911D01*
X1555065D01*
G01X1597388Y838828D02*
X1597469Y838747D01*
X1605272D01*
X1605295Y838770D01*
X1605369D01*
G01X1528666Y920887D02*
X1530389D01*
X1551170Y900106D01*
Y858758D01*
X1554429Y855499D01*
G01X1597397Y832054D02*
X1605276D01*
X1605335Y832113D01*
X1605369D01*
G01X1528659Y945343D02*
X1531892Y942110D01*
X1539579D01*
X1558874Y922815D01*
X1559141D01*
X1559887Y922069D01*
G01X1597454Y919062D02*
X1605313D01*
G01X1531066Y938709D02*
X1537967D01*
X1568246Y908430D01*
X1571165D01*
G01X1597388Y875612D02*
X1597442Y875558D01*
X1605335D01*
X1605369Y875592D01*
G01X1531066Y936309D02*
X1536965D01*
X1566971Y906303D01*
Y904624D01*
X1568516Y903079D01*
X1571565D01*
G01X1597388Y868917D02*
X1597440Y868865D01*
X1605330D01*
X1605369Y868904D01*
G01X1531666Y930309D02*
X1534475D01*
X1560570Y904214D01*
Y893239D01*
X1564113Y889696D01*
G01X1531666Y929109D02*
X1533977D01*
X1559370Y903716D01*
Y890465D01*
X1562126Y887709D01*
G01X1597388Y852133D02*
X1605369D01*
G01X1532366Y939909D02*
X1538466D01*
X1566769Y911606D01*
X1571166D01*
G01X1531066Y937509D02*
X1537463D01*
X1569102Y905874D01*
X1569311Y905665D01*
X1571565D01*
G01X1597448Y858825D02*
X1605369D01*
G01X1597388Y855415D02*
X1597452Y855479D01*
X1604842D01*
G01X1529955Y949237D02*
X1533482Y945710D01*
X1541073D01*
X1557049Y929734D01*
X1558666D01*
G01X1528250Y947534D02*
X1532474Y943310D01*
X1540077D01*
X1558777Y924610D01*
X1559866D01*
G01X1529099Y948383D02*
X1532972Y944510D01*
X1540575D01*
X1557942Y927143D01*
X1559866D01*
G01X1597423Y922408D02*
X1605309D01*
G01X1527904Y963544D02*
X1528544D01*
X1536774Y955314D01*
X1545057D01*
X1550796Y949575D01*
X1552266D01*
G01X1527966Y959500D02*
X1529192D01*
X1535778Y952914D01*
X1544061D01*
X1552612Y944363D01*
X1556166D01*
G01X1527966Y960700D02*
X1529690D01*
X1536276Y954114D01*
X1544559D01*
X1551734Y946939D01*
X1554766D01*
G01X1597487Y945833D02*
X1605242D01*
G01X1527966Y958300D02*
X1528694D01*
X1535280Y951714D01*
X1543563D01*
X1553522Y941755D01*
X1556166D01*
G01X1597388Y939140D02*
X1605249D01*
X1605312Y939077D01*
G01X1597616Y932447D02*
X1605298D01*
G01X1597415Y929101D02*
X1605257D01*
G01X1533875Y978557D02*
X1534444Y977988D01*
X1559213D01*
X1561263Y980038D01*
G01X1533467Y977265D02*
X1533944Y976788D01*
X1561216D01*
G01X1597463Y985991D02*
X1605170D01*
X1605212Y986033D01*
G01X1532626Y976406D02*
X1533444Y975588D01*
X1555010D01*
X1555331Y975267D01*
G01X1531252Y975248D02*
X1532112Y974388D01*
X1552634D01*
X1553143Y973879D01*
G01X1597461Y979392D02*
X1597555Y979298D01*
X1605139D01*
X1605212Y979371D01*
G01X1530367Y974033D02*
X1531212Y973188D01*
X1550238D01*
X1551345Y972081D01*
G01X1528567Y970788D02*
X1545388D01*
X1546719Y969457D01*
G01X1597612Y969179D02*
X1597691Y969258D01*
X1604812D01*
X1605157Y968913D01*
G01X1613530Y969355D02*
X1613627Y969258D01*
X1620066D01*
G01X1528566Y968388D02*
X1540052D01*
X1543241Y965199D01*
G01X1596597Y959219D02*
X1605293D01*
G01X1613550Y965865D02*
X1613597Y965912D01*
X1621414D01*
X1621511Y965815D01*
G01X1626347Y962565D02*
X1634895D01*
X1634932Y962528D01*
G01X1528567Y969588D02*
X1543008D01*
X1545129Y967467D01*
G01X1528566Y967188D02*
X1537664D01*
X1539653Y965199D01*
G01X1596639Y955873D02*
X1605091D01*
X1605193Y955975D01*
G01Y972682D02*
X1605116Y972605D01*
X1597561D01*
X1597512Y972654D01*
G01X1549150Y970686D02*
X1547848Y971988D01*
X1530367D01*
G01X1530767Y1001369D02*
X1531103D01*
X1534706Y1002862D01*
X1547819Y1015975D01*
X1560919D01*
X1561327Y1016383D01*
G01X1528967Y999131D02*
X1535295Y1001753D01*
X1547193Y1013651D01*
X1547959D01*
G01X1597437Y1029454D02*
X1597478Y1029495D01*
X1604955D01*
X1605369Y1029081D01*
G01X1526967Y1006228D02*
X1527389D01*
X1528196Y1007035D01*
X1529051D01*
X1529628Y1006458D01*
X1530194D01*
X1530794Y1007058D01*
X1531342D01*
X1532653Y1007601D01*
X1546398Y1021346D01*
X1548854D01*
X1552293Y1022030D01*
X1552635Y1022372D01*
G01X1528467Y1005027D02*
X1530166D01*
X1532917Y1006167D01*
X1546633Y1019883D01*
X1554143D01*
X1555476Y1021216D01*
G01X1597388Y1042813D02*
X1597455Y1042880D01*
X1605112D01*
X1605169Y1042823D01*
G01X1528467Y1003827D02*
X1530649D01*
X1533425Y1004977D01*
X1547131Y1018683D01*
X1556504D01*
X1558040Y1020219D01*
G01X1528467Y1002627D02*
X1530891D01*
X1534105Y1003959D01*
X1547629Y1017483D01*
X1558866D01*
X1559718Y1018335D01*
G01X1597369Y1036124D02*
X1597433Y1036188D01*
X1605285D01*
X1605369Y1036104D01*
G01X1527267Y1012983D02*
X1531242D01*
X1543936Y1025677D01*
X1545763Y1030088D01*
X1546288Y1030613D01*
G01X1597388Y1056227D02*
X1597427Y1056266D01*
X1605291D01*
X1605363Y1056194D01*
G01X1613712Y1056305D02*
X1613751Y1056266D01*
X1621246D01*
X1621293Y1056313D01*
G01X1527267Y1010391D02*
X1532047D01*
X1546498Y1024842D01*
X1548612Y1025718D01*
X1548976Y1026082D01*
G01X1597388Y1052979D02*
X1597447Y1052920D01*
X1603727D01*
G01X1613812Y1052867D02*
X1613865Y1052920D01*
X1621000D01*
X1621099Y1052821D01*
G01X1627212Y1052948D02*
X1627240Y1052920D01*
X1633184D01*
G01X1527267Y1011729D02*
X1531687D01*
X1546509Y1026551D01*
X1546995Y1027723D01*
X1548118Y1028846D01*
G01X1527267Y1008759D02*
X1532113D01*
X1546490Y1023136D01*
X1550531Y1023940D01*
X1551100Y1024509D01*
G01X1597388Y1049522D02*
X1597439Y1049573D01*
X1605297D01*
X1605369Y1049501D01*
G01X1528251Y1034869D02*
X1564683Y1071301D01*
X1568652Y1091142D01*
X1570984Y1093474D01*
X1571870D01*
G01X1529961Y1033183D02*
X1566900Y1070122D01*
X1569919Y1085226D01*
X1571544Y1086308D01*
X1571895Y1088059D01*
X1572899Y1088728D01*
X1574650Y1088377D01*
X1575970D01*
G01X1529097Y1034017D02*
X1565792Y1070712D01*
X1569181Y1087663D01*
X1570487Y1089621D01*
X1572738Y1090997D01*
X1575970D01*
G01X1597499Y1093077D02*
X1605239D01*
G01X1530846Y1032370D02*
X1567893Y1069417D01*
X1568037Y1069687D01*
X1570669Y1082851D01*
X1573614Y1085796D01*
X1575969D01*
G01X1597475Y1086384D02*
X1605304D01*
G01X1532113Y1025144D02*
X1573639Y1066670D01*
X1574781Y1072390D01*
X1575453Y1073062D01*
G01X1533840Y1023475D02*
X1569000Y1058635D01*
X1571068D01*
G01X1532991Y1024324D02*
X1575868Y1067201D01*
G01X1597006Y1069652D02*
X1605301D01*
G01X1534639Y1022576D02*
X1567561Y1055498D01*
X1570918D01*
G01X1597359Y1066306D02*
X1605346D01*
G01X1597388Y1079691D02*
X1605287D01*
G01X1597388Y1076344D02*
X1597389Y1076345D01*
X1605283D01*
G01X1527041Y1052075D02*
X1552338Y1077372D01*
X1558715Y1109237D01*
Y1111054D01*
X1560477Y1115750D01*
X1561422Y1116695D01*
G01X1529240Y1052576D02*
X1553446Y1076782D01*
X1560378Y1111429D01*
X1561692Y1113403D01*
X1563203Y1114914D01*
G01X1597388Y1126676D02*
X1597522Y1126542D01*
X1605300D01*
X1605369Y1126611D01*
G01X1527059Y1041759D02*
X1559008Y1073708D01*
X1564518Y1101243D01*
X1566327Y1102726D01*
X1568769Y1105168D01*
G01X1531007Y1042310D02*
X1561221Y1072524D01*
X1565548Y1094153D01*
X1567017Y1095622D01*
Y1097122D01*
X1567537Y1097642D01*
X1568473D01*
X1569424Y1098593D01*
G01X1530157Y1043159D02*
X1560115Y1073117D01*
X1565271Y1098885D01*
X1567507Y1101121D01*
X1568305D01*
X1568770Y1101586D01*
G01X1597420Y1109845D02*
X1597440D01*
X1597475Y1109810D01*
X1605320D01*
X1605369Y1109859D01*
G01X1531856Y1041460D02*
X1562328Y1071932D01*
X1566494Y1092762D01*
X1570311Y1095890D01*
X1571819Y1097398D01*
G01X1597439Y1103117D02*
X1605182D01*
X1605309Y1103244D01*
X1605369D01*
G01X1597369Y1116609D02*
X1597476Y1116502D01*
X1605298D01*
X1605369Y1116573D01*
G01X1597395Y1113129D02*
X1597422Y1113156D01*
X1605279D01*
X1605360Y1113075D01*
G01X1529582Y1066434D02*
X1544797Y1081643D01*
X1549082Y1103086D01*
Y1133482D01*
X1549669Y1134069D01*
G01X1530483Y1063933D02*
X1547010Y1080460D01*
X1551482Y1102813D01*
Y1122579D01*
X1553660Y1124757D01*
G01X1530434Y1065582D02*
X1545903Y1081051D01*
X1550282Y1102947D01*
Y1127685D01*
X1550414Y1127817D01*
Y1131253D01*
X1550869Y1131708D01*
G01X1598138Y1146621D02*
X1605290D01*
X1605369Y1146700D01*
G01X1531333Y1063084D02*
X1548117Y1079868D01*
X1552682Y1102691D01*
Y1120122D01*
X1555488Y1122928D01*
G01X1597388Y1140075D02*
X1597535Y1139928D01*
X1605259D01*
X1605369Y1140038D01*
G01X1525343Y1053773D02*
X1550126Y1078556D01*
X1556270Y1109272D01*
Y1118773D01*
X1557807Y1120310D01*
G01X1526192Y1052924D02*
X1551232Y1077964D01*
X1557515Y1109374D01*
Y1111657D01*
X1558677Y1117618D01*
X1559588Y1118529D01*
G01X1597388Y1133336D02*
X1597489Y1133235D01*
X1605316D01*
X1605369Y1133288D01*
G01X1597394Y1153364D02*
X1597444Y1153314D01*
X1605161D01*
G01X1597389Y1149914D02*
X1597442Y1149967D01*
X1605276D01*
X1605359Y1149884D01*
G01X1529978Y1080438D02*
X1535869Y1086329D01*
X1539467Y1104347D01*
Y1143228D01*
X1540978Y1150820D01*
X1541839Y1151679D01*
G01X1528127Y1075191D02*
X1538084Y1085148D01*
X1541867Y1104072D01*
Y1140549D01*
X1544599Y1147147D01*
X1545585Y1148133D01*
G01X1530827Y1079589D02*
X1536975Y1085737D01*
X1540667Y1104193D01*
Y1140935D01*
X1540926Y1142235D01*
X1543062Y1149280D01*
X1543750Y1149968D01*
G01X1597388Y1170046D02*
X1604738D01*
X1605152Y1170189D01*
X1605369D01*
G01X1532526Y1077890D02*
X1539193Y1084557D01*
X1543067Y1103949D01*
Y1139732D01*
X1544598Y1143428D01*
X1547444Y1146274D01*
G01X1597522Y1163353D02*
X1605369D01*
G01X1527783Y1083333D02*
X1532722Y1088272D01*
X1535906Y1104177D01*
Y1143793D01*
X1538279Y1155727D01*
G01X1538907Y1157243D02*
X1540454Y1158790D01*
G01X1528634Y1082482D02*
X1533829Y1087677D01*
X1537106Y1104049D01*
Y1143059D01*
X1539115Y1153150D01*
X1539965Y1154740D01*
X1540821Y1155596D01*
G01X1597388Y1213576D02*
X1597414Y1213550D01*
X1605343D01*
X1605369Y1213576D01*
G01X1526286Y1106549D02*
Y1167166D01*
X1527813Y1168693D01*
Y1170582D01*
G01X1527486Y1106549D02*
Y1166232D01*
X1530335Y1169081D01*
Y1170582D01*
G01X1597388Y1237040D02*
X1597453Y1236975D01*
X1604581D01*
G01X1527026Y1085992D02*
X1530512Y1089478D01*
X1533506Y1104436D01*
Y1145747D01*
X1533596Y1146789D01*
X1535511Y1157764D01*
X1536927Y1161957D01*
X1537459Y1162982D01*
X1538101Y1163624D01*
G01X1527879Y1085139D02*
X1531618Y1088878D01*
X1534706Y1104308D01*
Y1144500D01*
X1537611Y1159118D01*
X1538063Y1159963D01*
X1538672Y1160572D01*
G01X1597612Y1216873D02*
X1597635Y1216896D01*
X1605173D01*
X1605193Y1216876D01*
G01X1597388Y1226962D02*
X1597414Y1226936D01*
X1605349D01*
X1605369Y1226956D01*
G01X1597389Y1223569D02*
X1597409Y1223589D01*
X1602622D01*
G01X1604197D02*
X1605332D01*
X1605353Y1223568D01*
X1605369D01*
G01X1523886Y1106549D02*
Y1166371D01*
X1523521Y1166736D01*
Y1168572D01*
X1522700Y1169393D01*
G01X1525086Y1106549D02*
Y1168026D01*
G01X1525287Y1168227D02*
Y1170582D01*
G01X1598413Y1243668D02*
X1604829D01*
G01X1621511Y778448D02*
X1621448Y778511D01*
X1613687D01*
G01X1621511Y771755D02*
X1621448Y771818D01*
X1613687D01*
G01X1621511Y788518D02*
X1621479Y788550D01*
X1613582D01*
X1613530Y788498D01*
G01X1621511Y795180D02*
X1621448Y795243D01*
X1613687D01*
G01X1621511Y791937D02*
X1621471Y791897D01*
X1613599D01*
X1613524Y791972D01*
G01X1621511Y815258D02*
X1621448Y815321D01*
X1613687D01*
G01X1621511Y808565D02*
X1621448Y808628D01*
X1613687D01*
G01X1621511Y801873D02*
X1621448Y801936D01*
X1613687D01*
G01X1621511Y831996D02*
X1621453Y832054D01*
X1613791D01*
X1613730Y831993D01*
X1613530D01*
G01X1621488Y825320D02*
X1621447Y825361D01*
X1613645D01*
X1613530Y825246D01*
G01X1621492Y828783D02*
X1621417Y828708D01*
X1613599D01*
X1613537Y828770D01*
G01X1621408Y845420D02*
X1621388Y845440D01*
X1613641D01*
G01X1621511Y838689D02*
X1621453Y838747D01*
X1613582D01*
X1613530Y838695D01*
G01X1621443Y852133D02*
X1613694D01*
X1613640Y852079D01*
G01X1621511Y862106D02*
X1621445Y862172D01*
X1613617D01*
X1613511Y862066D01*
G01X1621511Y865583D02*
X1621447Y865519D01*
X1613624D01*
X1613573Y865570D01*
X1613553D01*
G01X1612869Y882251D02*
X1621486D01*
X1621511Y882226D01*
G01X1621391Y875558D02*
X1613568D01*
X1613530Y875520D01*
G01X1621391Y868865D02*
X1613564D01*
X1613530Y868831D01*
G01X1612975Y888944D02*
X1621486D01*
X1621511Y888919D01*
G01X1621437Y898888D02*
X1621342Y898983D01*
X1612783D01*
G01X1621511Y902404D02*
X1621437Y902330D01*
X1612788D01*
G01X1612975Y912369D02*
X1621486D01*
G01X1612869Y905676D02*
X1621486D01*
X1621511Y905651D01*
G01X1621467Y925755D02*
X1613651D01*
G01X1621328Y919062D02*
X1613582D01*
G01X1621438Y942487D02*
X1613624D01*
G01X1613596Y935794D02*
X1621429D01*
G01X1621439Y939141D02*
X1613606D01*
G01X1620730Y949180D02*
X1613594D01*
G01X1621511Y982720D02*
X1621435Y982644D01*
X1613614D01*
X1613530Y982728D01*
G01X1621511Y975989D02*
X1621473Y975951D01*
X1613586D01*
X1613530Y976007D01*
G01X1621097Y992684D02*
X1614268D01*
X1613530Y993422D01*
G01X1621511Y989391D02*
X1621457Y989337D01*
X1613582D01*
X1613530Y989389D01*
G01X1621511Y1029560D02*
X1621446Y1029495D01*
X1613794D01*
X1613641Y1029648D01*
X1613530D01*
G01X1621370Y1025694D02*
X1620916Y1026148D01*
X1614149D01*
X1613695Y1025694D01*
G01X1621508Y1049619D02*
X1621462Y1049573D01*
X1613593D01*
X1613530Y1049636D01*
G01X1621511Y1042919D02*
X1621472Y1042880D01*
X1613578D01*
X1613511Y1042947D01*
G01Y1036275D02*
X1613598Y1036188D01*
X1621395D01*
X1621511Y1036304D01*
G01X1620795Y1059613D02*
X1613634D01*
G01X1620826Y1072999D02*
X1613566D01*
G01X1621431Y1066306D02*
X1613841D01*
G01X1621462Y1089731D02*
X1613559D01*
G01X1621385Y1083038D02*
X1613592D01*
G01X1621278Y1086385D02*
X1613574D01*
G01X1621211Y1096022D02*
X1620809Y1096424D01*
X1613575D01*
G01X1621511Y1109734D02*
X1621435Y1109810D01*
X1613567D01*
X1613530Y1109773D01*
G01X1621511Y1106502D02*
X1621472Y1106463D01*
X1613588D01*
X1613517Y1106534D01*
G01X1621511Y1126475D02*
X1621444Y1126542D01*
X1613574D01*
X1613530Y1126498D01*
G01X1621511Y1119823D02*
X1621485Y1119849D01*
X1613592D01*
X1613530Y1119787D01*
G01X1621511Y1123269D02*
X1621438Y1123196D01*
X1613576D01*
X1613530Y1123242D01*
G01X1621476Y1139928D02*
X1616741D01*
G01X1621472Y1133264D02*
X1621443Y1133235D01*
X1616741D01*
G01X1621495Y1146621D02*
X1616741D01*
G01X1621511Y1156634D02*
X1621485Y1156660D01*
X1613592D01*
X1613530Y1156598D01*
G01X1621511Y1160080D02*
X1621438Y1160007D01*
X1613576D01*
X1613530Y1160053D01*
G01X1618325Y1170046D02*
X1613609D01*
X1613580Y1170017D01*
G01X1618325Y1163353D02*
X1613609D01*
X1613580Y1163324D01*
G01X1612975Y1183432D02*
X1621486D01*
X1621511Y1183407D01*
G01X1612869Y1176739D02*
X1621486D01*
X1621511Y1176714D01*
G01Y1193406D02*
X1621446Y1193471D01*
X1613530D01*
G01X1621511Y1206819D02*
X1621473Y1206857D01*
X1613530D01*
G01X1621511Y1200129D02*
X1621476Y1200164D01*
X1613530D01*
G01X1621464Y1196863D02*
X1621419Y1196818D01*
X1613530D01*
G01X1621511Y1220205D02*
X1621473Y1220243D01*
X1613573D01*
X1613530Y1220200D01*
G01X1621511Y1213528D02*
X1621489Y1213550D01*
X1613552D01*
X1613530Y1213528D01*
G01X1621511Y1236936D02*
X1621472Y1236975D01*
X1613565D01*
X1613530Y1236940D01*
G01X1621511Y1230259D02*
X1621488Y1230282D01*
X1613645D01*
X1613530Y1230167D01*
G01X1621511Y1233648D02*
X1621492Y1233629D01*
X1613530D01*
G01X1620759Y1250358D02*
X1614299D01*
G01X1620483Y1243668D02*
X1613877D01*
X1613730Y1243521D01*
X1613530D01*
G01X1635069Y771880D02*
X1635006Y771817D01*
X1627245D01*
G01X1635069Y778573D02*
X1635006Y778510D01*
X1627245D01*
G01X1635069Y785247D02*
X1635026Y785204D01*
X1627112D01*
X1627088Y785228D01*
G01X1635069Y781828D02*
X1635040Y781857D01*
X1627116D01*
X1627088Y781829D01*
G01X1635069Y801999D02*
X1635006Y801936D01*
X1627245D01*
G01X1635069Y795306D02*
X1635006Y795243D01*
X1627245D01*
G01X1635069Y815384D02*
X1635006Y815321D01*
X1627245D01*
G01X1635069Y808691D02*
X1635006Y808628D01*
X1627245D01*
G01X1635069Y818642D02*
X1635043Y818668D01*
X1627251D01*
X1627171Y818588D01*
X1627151D01*
G01X1635069Y832117D02*
X1635006Y832054D01*
X1627245D01*
G01X1635069Y822053D02*
X1635030Y822014D01*
X1633820D01*
G01X1632248D02*
X1627590D01*
G01X1634979Y852186D02*
X1634925Y852132D01*
X1627150D01*
X1627085Y852197D01*
G01X1635069Y845502D02*
X1635006Y845439D01*
X1627245D01*
G01X1635069Y838810D02*
X1635006Y838747D01*
X1627245D01*
G01X1634866Y868865D02*
X1627166D01*
X1627109Y868922D01*
G01X1635069Y858869D02*
X1635026Y858826D01*
X1627112D01*
X1627088Y858850D01*
G01X1635069Y855450D02*
X1635040Y855479D01*
X1627116D01*
X1627088Y855451D01*
G01X1634866Y875558D02*
X1627166D01*
X1627109Y875615D01*
G01X1634866Y882250D02*
X1627166D01*
X1627109Y882307D01*
G01X1634866Y888943D02*
X1627166D01*
X1627109Y889000D01*
G01X1635069Y895680D02*
X1635026Y895637D01*
X1627112D01*
X1627088Y895661D01*
G01X1635069Y892261D02*
X1635040Y892290D01*
X1627116D01*
X1627088Y892262D01*
G01X1634965Y919062D02*
X1627224D01*
G01X1635069Y912420D02*
X1635018Y912369D01*
X1627193D01*
X1627134Y912428D01*
G01X1635069Y905767D02*
X1634978Y905676D01*
X1627193D01*
X1627138Y905731D01*
G01X1635025Y925755D02*
X1627193D01*
G01X1635026Y932448D02*
X1627112D01*
G01X1635040Y929101D02*
X1627116D01*
G01X1635069Y945762D02*
X1634997Y945834D01*
X1627198D01*
G01X1634989Y942487D02*
X1627176D01*
G01X1635069Y979391D02*
X1634976Y979298D01*
X1627177D01*
X1627145Y979330D01*
G01X1635069Y972655D02*
X1635019Y972605D01*
X1627200D01*
X1627138Y972667D01*
G01X1635069Y992736D02*
X1635017Y992684D01*
X1627198D01*
X1627121Y992761D01*
G01X1635069Y986041D02*
X1635019Y985991D01*
X1627175D01*
X1627138Y986028D01*
G01X1635069Y1032905D02*
X1635005Y1032841D01*
X1627151D01*
X1627089Y1032903D01*
G01X1635069Y1046312D02*
X1634984Y1046227D01*
X1627672D01*
G01X1635069Y1039611D02*
X1634992Y1039534D01*
X1627193D01*
X1627138Y1039589D01*
G01X1635009Y1059613D02*
X1626939D01*
G01X1635020Y1072999D02*
X1627198D01*
G01X1634771Y1066306D02*
X1627253D01*
G01X1635026Y1079692D02*
X1627112D01*
G01X1635040Y1076345D02*
X1627116D01*
G01X1634907Y1093078D02*
X1627174D01*
G01X1634654Y1089731D02*
X1627206D01*
G01X1635069Y1109839D02*
X1635040Y1109810D01*
X1627173D01*
X1627138Y1109845D01*
G01X1635069Y1103149D02*
X1635037Y1103117D01*
X1627170D01*
X1627138Y1103149D01*
G01X1631883Y1126542D02*
X1627167D01*
X1627138Y1126571D01*
G01X1635069Y1116546D02*
X1635026Y1116503D01*
X1627112D01*
X1627088Y1116527D01*
G01X1635069Y1113127D02*
X1635040Y1113156D01*
X1627116D01*
X1627088Y1113128D01*
G01X1631883Y1146621D02*
X1627167D01*
X1627138Y1146650D01*
G01X1631883Y1139928D02*
X1627167D01*
X1627138Y1139957D01*
G01X1631883Y1133235D02*
X1627167D01*
X1627138Y1133264D01*
G01X1635069Y1153357D02*
X1635026Y1153314D01*
X1627112D01*
X1627088Y1153338D01*
G01X1635069Y1149939D02*
X1635040Y1149968D01*
X1627116D01*
X1627088Y1149940D01*
G01X1631883Y1176739D02*
X1627167D01*
X1627138Y1176768D01*
G01X1631883Y1170046D02*
X1627167D01*
X1627138Y1170075D01*
G01X1631883Y1163353D02*
X1627167D01*
X1627138Y1163382D01*
G01X1632642Y1183432D02*
X1627160D01*
X1627138Y1183454D01*
G01X1635069Y1190145D02*
X1635049Y1190125D01*
X1627108D01*
X1627088Y1190145D01*
G01X1635069Y1186759D02*
X1635049Y1186779D01*
X1627108D01*
X1627088Y1186759D01*
G01X1632518Y1206857D02*
X1627174D01*
X1627138Y1206893D01*
G01X1631873Y1200164D02*
X1627180D01*
X1627138Y1200206D01*
G01X1632219Y1220243D02*
X1627324D01*
X1627233Y1220269D01*
X1627172D01*
G01X1632896Y1213550D02*
X1627158D01*
X1627138Y1213570D01*
G01X1635069Y1226975D02*
X1635030Y1226936D01*
X1633820D01*
G01X1632248D02*
X1627199D01*
G01X1635069Y1223564D02*
X1635043Y1223590D01*
X1627250D01*
X1627207Y1223547D01*
X1627187D01*
G01X1634631Y1243668D02*
X1627381D01*
G01X1634955Y1236975D02*
X1627177D01*
X1627138Y1237014D01*
G01X1650279Y1253705D02*
X1643999D01*
G01X1664769Y1059613D02*
X1656889D01*
G01X1680911Y778486D02*
X1680886Y778511D01*
X1672375D01*
G01X1680911Y771793D02*
X1680886Y771818D01*
X1672269D01*
G01X1672309Y788550D02*
X1680890D01*
X1680911Y788529D01*
G01Y801911D02*
X1680886Y801936D01*
X1672375D01*
G01X1680911Y795218D02*
X1680886Y795243D01*
X1672269D01*
G01X1672394Y791897D02*
X1680887D01*
X1680911Y791921D01*
G01Y815297D02*
X1680886Y815322D01*
X1672375D01*
G01X1680911Y808604D02*
X1680886Y808629D01*
X1672269D01*
G01X1680911Y832029D02*
X1680886Y832054D01*
X1672269D01*
G01X1672309Y825361D02*
X1680890D01*
X1680911Y825340D01*
G01X1672394Y828708D02*
X1680887D01*
X1680911Y828732D01*
G01Y852108D02*
X1680886Y852133D01*
X1672375D01*
G01X1680911Y845415D02*
X1680886Y845440D01*
X1672269D01*
G01X1680911Y838722D02*
X1680886Y838747D01*
X1672375D01*
G01X1672309Y862172D02*
X1680890D01*
X1680911Y862151D01*
G01X1672394Y865519D02*
X1680887D01*
X1680911Y865543D01*
G01Y882226D02*
X1680886Y882251D01*
X1672269D01*
G01X1680911Y875533D02*
X1680886Y875558D01*
X1672375D01*
G01X1680911Y868840D02*
X1680886Y868865D01*
X1672269D01*
G01X1680911Y888919D02*
X1680886Y888944D01*
X1672375D01*
G01X1672309Y898983D02*
X1680890D01*
X1680911Y898962D01*
G01X1672394Y902330D02*
X1680887D01*
X1680911Y902354D01*
G01Y912344D02*
X1680886Y912369D01*
X1672375D01*
G01X1680911Y905651D02*
X1680886Y905676D01*
X1672269D01*
G01X1680911Y925730D02*
X1680886Y925755D01*
X1672375D01*
G01X1680911Y919037D02*
X1680886Y919062D01*
X1672269D01*
G01X1680911Y949155D02*
X1680886Y949180D01*
X1672375D01*
G01X1680911Y942462D02*
X1680886Y942487D01*
X1672269D01*
G01X1672309Y935794D02*
X1680890D01*
X1680911Y935773D01*
G01X1672394Y939141D02*
X1680887D01*
X1680911Y939165D01*
G01X1672309Y982644D02*
X1680862D01*
X1680911Y982693D01*
G01X1672309Y975951D02*
X1680862D01*
X1680911Y976000D01*
G01X1672309Y989337D02*
X1680862D01*
X1680911Y989386D01*
G01X1672309Y1029495D02*
X1680862D01*
X1680911Y1029544D01*
G01X1672299Y1019456D02*
X1680862D01*
X1680911Y1019505D01*
G01X1672309Y1049573D02*
X1680862D01*
X1680911Y1049622D01*
G01X1671943Y1042880D02*
X1680862D01*
X1680911Y1042929D01*
G01Y1036237D02*
X1680862Y1036188D01*
X1671986D01*
G01X1672930Y1059556D02*
X1672987Y1059613D01*
X1680886D01*
X1680911Y1059588D01*
G01Y1072974D02*
X1680886Y1072999D01*
X1672375D01*
G01X1680911Y1066281D02*
X1680886Y1066306D01*
X1672269D01*
G01X1680911Y1089706D02*
X1680886Y1089731D01*
X1672269D01*
G01X1672309Y1083038D02*
X1680890D01*
X1680911Y1083017D01*
G01X1672394Y1086385D02*
X1680887D01*
X1680911Y1086409D01*
G01Y1096399D02*
X1680886Y1096424D01*
X1672375D01*
G01X1680911Y1109785D02*
X1680886Y1109810D01*
X1672375D01*
G01X1680911Y1103092D02*
X1680886Y1103117D01*
X1672269D01*
G01X1680911Y1126517D02*
X1680886Y1126542D01*
X1672269D01*
G01X1672309Y1119849D02*
X1680890D01*
X1680911Y1119828D01*
G01X1672394Y1123196D02*
X1680887D01*
X1680911Y1123220D01*
G01Y1139903D02*
X1680886Y1139928D01*
X1672269D01*
G01X1680911Y1133210D02*
X1680886Y1133235D01*
X1672375D01*
G01X1680911Y1146596D02*
X1680886Y1146621D01*
X1672375D01*
G01X1672309Y1156660D02*
X1680890D01*
X1680911Y1156639D01*
G01X1672394Y1160007D02*
X1680887D01*
X1680911Y1160031D01*
G01Y1176714D02*
X1680886Y1176739D01*
X1672269D01*
G01X1680911Y1170021D02*
X1680886Y1170046D01*
X1672375D01*
G01X1680911Y1163328D02*
X1680886Y1163353D01*
X1672269D01*
G01X1680911Y1183407D02*
X1680886Y1183432D01*
X1672375D01*
G01X1672309Y1193471D02*
X1680890D01*
X1680911Y1193450D01*
G01Y1206832D02*
X1680886Y1206857D01*
X1672375D01*
G01X1680911Y1200139D02*
X1680886Y1200164D01*
X1672269D01*
G01X1672394Y1196818D02*
X1680887D01*
X1680911Y1196842D01*
G01Y1220218D02*
X1680886Y1220243D01*
X1672375D01*
G01X1680911Y1213525D02*
X1680886Y1213550D01*
X1672269D01*
G01X1680911Y1236950D02*
X1680886Y1236975D01*
X1672269D01*
G01X1672309Y1230282D02*
X1680890D01*
X1680911Y1230261D01*
G01X1672394Y1233629D02*
X1680887D01*
X1680911Y1233653D01*
G01X1680289Y1250358D02*
X1672829D01*
G01X1680911Y1243643D02*
X1680886Y1243668D01*
X1672375D01*
G01X1686488Y771845D02*
X1686516Y771817D01*
X1694421D01*
X1694469Y771865D01*
G01X1686488Y778538D02*
X1686516Y778510D01*
X1694421D01*
X1694469Y778558D01*
G01X1686488Y785228D02*
X1686512Y785204D01*
X1694426D01*
X1694469Y785247D01*
G01X1686488Y781829D02*
X1686516Y781857D01*
X1694440D01*
X1694469Y781828D01*
G01X1686488Y801964D02*
X1686516Y801936D01*
X1694421D01*
X1694469Y801984D01*
G01X1686488Y795271D02*
X1686516Y795243D01*
X1694421D01*
X1694469Y795291D01*
G01X1686488Y815349D02*
X1686516Y815321D01*
X1694421D01*
X1694469Y815369D01*
G01X1686488Y808656D02*
X1686516Y808628D01*
X1694421D01*
X1694469Y808676D01*
G01X1686488Y818640D02*
X1686516Y818668D01*
X1694440D01*
X1694469Y818639D01*
G01X1686488Y832082D02*
X1686516Y832054D01*
X1694421D01*
X1694469Y832102D01*
G01X1686488Y822039D02*
X1686512Y822015D01*
X1694426D01*
X1694469Y822058D01*
G01X1686488Y852160D02*
X1686516Y852132D01*
X1694421D01*
X1694469Y852180D01*
G01X1686488Y845467D02*
X1686516Y845439D01*
X1694421D01*
X1694469Y845487D01*
G01X1686488Y838775D02*
X1686516Y838747D01*
X1694421D01*
X1694469Y838795D01*
G01X1686488Y868893D02*
X1686516Y868865D01*
X1694421D01*
X1694469Y868913D01*
G01X1686488Y858850D02*
X1686512Y858826D01*
X1694426D01*
X1694469Y858869D01*
G01X1686488Y855451D02*
X1686516Y855479D01*
X1694440D01*
X1694469Y855450D01*
G01X1686488Y875586D02*
X1686516Y875558D01*
X1694421D01*
X1694469Y875606D01*
G01X1686488Y882278D02*
X1686516Y882250D01*
X1694421D01*
X1694469Y882298D01*
G01X1686488Y888971D02*
X1686516Y888943D01*
X1694421D01*
X1694469Y888991D01*
G01X1686488Y895661D02*
X1686512Y895637D01*
X1694426D01*
X1694469Y895680D01*
G01X1686488Y892262D02*
X1686516Y892290D01*
X1694440D01*
X1694469Y892261D01*
G01X1686488Y912397D02*
X1686516Y912369D01*
X1694421D01*
X1694469Y912417D01*
G01X1686488Y905704D02*
X1686516Y905676D01*
X1694421D01*
X1694469Y905724D01*
G01X1686488Y925782D02*
X1686516Y925754D01*
X1694421D01*
X1694469Y925802D01*
G01X1686488Y919090D02*
X1686516Y919062D01*
X1694421D01*
X1694469Y919110D01*
G01X1686488Y932472D02*
X1686512Y932448D01*
X1694426D01*
X1694469Y932491D01*
G01X1686488Y929073D02*
X1686516Y929101D01*
X1694440D01*
X1694469Y929072D01*
G01X1686488Y949208D02*
X1686516Y949180D01*
X1694421D01*
X1694469Y949228D01*
G01X1686488Y942515D02*
X1686516Y942487D01*
X1694421D01*
X1694469Y942535D01*
G01X1686488Y979340D02*
X1686530Y979298D01*
X1694440D01*
X1694469Y979327D01*
G01X1686488Y972647D02*
X1686530Y972605D01*
X1694440D01*
X1694469Y972634D01*
G01X1686488Y992726D02*
X1686530Y992684D01*
X1694440D01*
X1694469Y992713D01*
G01X1686488Y986033D02*
X1686530Y985991D01*
X1694440D01*
X1694469Y986020D01*
G01X1686488Y1032883D02*
X1686530Y1032841D01*
X1694440D01*
X1694469Y1032870D01*
G01X1686488Y1046269D02*
X1686530Y1046227D01*
X1694440D01*
X1694469Y1046256D01*
G01X1686488Y1039576D02*
X1686530Y1039534D01*
X1694440D01*
X1694469Y1039563D01*
G01X1686839Y1059613D02*
X1694189D01*
G01X1694469Y1073047D02*
X1694421Y1072999D01*
X1686516D01*
X1686488Y1073027D01*
G01Y1066334D02*
X1686516Y1066306D01*
X1694421D01*
X1694469Y1066354D01*
G01X1686488Y1079716D02*
X1686512Y1079692D01*
X1694426D01*
X1694469Y1079735D01*
G01X1686488Y1076317D02*
X1686516Y1076345D01*
X1694440D01*
X1694469Y1076316D01*
G01X1686488Y1096452D02*
X1686516Y1096424D01*
X1694421D01*
X1694469Y1096472D01*
G01X1686488Y1089759D02*
X1686516Y1089731D01*
X1694421D01*
X1694469Y1089779D01*
G01Y1109858D02*
X1694421Y1109810D01*
X1686516D01*
X1686488Y1109838D01*
G01Y1103145D02*
X1686516Y1103117D01*
X1694421D01*
X1694469Y1103165D01*
G01X1686488Y1126570D02*
X1686516Y1126542D01*
X1694421D01*
X1694469Y1126590D01*
G01X1686488Y1116527D02*
X1686512Y1116503D01*
X1694426D01*
X1694469Y1116546D01*
G01X1686488Y1113128D02*
X1686516Y1113156D01*
X1694440D01*
X1694469Y1113127D01*
G01Y1146669D02*
X1694421Y1146621D01*
X1686516D01*
X1686488Y1146649D01*
G01Y1139956D02*
X1686516Y1139928D01*
X1694421D01*
X1694469Y1139976D01*
G01X1686488Y1133263D02*
X1686516Y1133235D01*
X1694421D01*
X1694469Y1133283D01*
G01X1686488Y1153338D02*
X1686512Y1153314D01*
X1694426D01*
X1694469Y1153357D01*
G01Y1149939D02*
X1694440Y1149968D01*
X1686516D01*
X1686488Y1149940D01*
G01Y1176767D02*
X1686516Y1176739D01*
X1694421D01*
X1694469Y1176787D01*
G01X1686488Y1170074D02*
X1686516Y1170046D01*
X1694421D01*
X1694469Y1170094D01*
G01X1686488Y1163381D02*
X1686516Y1163353D01*
X1694421D01*
X1694469Y1163401D01*
G01Y1183480D02*
X1694421Y1183432D01*
X1686516D01*
X1686488Y1183460D01*
G01Y1190149D02*
X1686512Y1190125D01*
X1694426D01*
X1694469Y1190168D01*
G01Y1186750D02*
X1694440Y1186779D01*
X1686516D01*
X1686488Y1186751D01*
G01Y1206885D02*
X1686516Y1206857D01*
X1694421D01*
X1694469Y1206905D01*
G01X1686488Y1200192D02*
X1686516Y1200164D01*
X1694421D01*
X1694469Y1200212D01*
G01Y1220291D02*
X1694421Y1220243D01*
X1686516D01*
X1686488Y1220271D01*
G01Y1213578D02*
X1686516Y1213550D01*
X1694421D01*
X1694469Y1213598D01*
G01X1686488Y1226960D02*
X1686512Y1226936D01*
X1694426D01*
X1694469Y1226979D01*
G01Y1223561D02*
X1694440Y1223590D01*
X1686516D01*
X1686488Y1223562D01*
G01Y1243696D02*
X1686516Y1243668D01*
X1694421D01*
X1694469Y1243716D01*
G01X1686488Y1237003D02*
X1686516Y1236975D01*
X1694421D01*
X1694469Y1237023D01*
G01X1709889Y1250358D02*
X1703399D01*
G01X1740311Y778486D02*
X1740286Y778511D01*
X1731775D01*
G01X1740311Y771793D02*
X1740286Y771818D01*
X1731669D01*
G01X1731709Y788550D02*
X1740290D01*
X1740311Y788529D01*
G01Y795218D02*
X1740286Y795243D01*
X1731669D01*
G01X1731794Y791897D02*
X1740287D01*
X1740311Y791921D01*
G01Y815297D02*
X1740286Y815322D01*
X1731775D01*
G01X1740311Y808604D02*
X1740286Y808629D01*
X1731669D01*
G01X1740311Y801911D02*
X1740286Y801936D01*
X1731775D01*
G01X1740311Y832029D02*
X1740286Y832054D01*
X1731669D01*
G01X1731709Y825361D02*
X1740290D01*
X1740311Y825340D01*
G01X1731794Y828708D02*
X1740287D01*
X1740311Y828732D01*
G01Y845415D02*
X1740286Y845440D01*
X1731669D01*
G01X1740311Y838722D02*
X1740286Y838747D01*
X1731775D01*
G01X1740311Y852108D02*
X1740286Y852133D01*
X1731775D01*
G01X1731709Y862172D02*
X1740290D01*
X1740311Y862151D01*
G01X1731794Y865519D02*
X1740287D01*
X1740311Y865543D01*
G01Y882226D02*
X1740286Y882251D01*
X1731669D01*
G01X1740311Y875533D02*
X1740286Y875558D01*
X1731775D01*
G01X1740311Y868840D02*
X1740286Y868865D01*
X1731669D01*
G01X1740311Y888919D02*
X1740286Y888944D01*
X1731775D01*
G01X1731709Y898983D02*
X1740290D01*
X1740311Y898962D01*
G01X1731794Y902330D02*
X1740287D01*
X1740311Y902354D01*
G01Y912344D02*
X1740286Y912369D01*
X1731775D01*
G01X1740311Y905651D02*
X1740286Y905676D01*
X1731669D01*
G01X1740871Y925755D02*
X1731775D01*
G01X1740871Y919062D02*
X1731775D01*
G01X1740871Y942487D02*
X1731775D01*
G01X1731709Y935794D02*
X1740290D01*
G01X1731794Y939141D02*
X1740287D01*
G01X1740871Y949180D02*
X1731775D01*
G01X1731709Y982644D02*
X1740262D01*
X1740311Y982693D01*
G01X1731709Y975951D02*
X1740262D01*
X1740311Y976000D01*
G01X1731709Y989337D02*
X1740262D01*
X1740311Y989386D01*
G01X1731709Y1029495D02*
X1740262D01*
X1740311Y1029544D01*
G01X1731699Y1019456D02*
X1740262D01*
X1740311Y1019505D01*
G01X1731343Y1042880D02*
X1740262D01*
X1740311Y1042929D01*
G01X1731386Y1036188D02*
X1740262D01*
X1740311Y1036237D01*
G01X1740871Y1059613D02*
X1731775D01*
G01X1731709Y1049573D02*
X1740262D01*
X1740311Y1049622D01*
G01X1740871Y1072999D02*
X1731775D01*
G01X1740871Y1066306D02*
X1731775D01*
G01X1740871Y1089731D02*
X1731775D01*
G01X1731709Y1083038D02*
X1740290D01*
G01X1731794Y1086385D02*
X1740287D01*
G01X1740871Y1096424D02*
X1731775D01*
G01X1740311Y1109785D02*
X1740286Y1109810D01*
X1731775D01*
G01X1740311Y1103092D02*
X1740286Y1103117D01*
X1731669D01*
G01X1740311Y1126517D02*
X1740286Y1126542D01*
X1731669D01*
G01X1731709Y1119849D02*
X1740290D01*
X1740311Y1119828D01*
G01X1731794Y1123196D02*
X1740287D01*
X1740311Y1123220D01*
G01Y1139903D02*
X1740286Y1139928D01*
X1731669D01*
G01X1740311Y1133210D02*
X1740286Y1133235D01*
X1731775D01*
G01X1740311Y1146596D02*
X1740286Y1146621D01*
X1731775D01*
G01X1731709Y1156660D02*
X1740290D01*
X1740311Y1156639D01*
G01X1731794Y1160007D02*
X1740287D01*
X1740311Y1160031D01*
G01Y1170021D02*
X1740286Y1170046D01*
X1731775D01*
G01X1740311Y1163328D02*
X1740286Y1163353D01*
X1731669D01*
G01X1740311Y1183407D02*
X1740286Y1183432D01*
X1731399D01*
G01X1740311Y1176714D02*
X1740286Y1176739D01*
X1731669D01*
G01X1731709Y1193471D02*
X1740290D01*
X1740311Y1193450D01*
G01Y1206832D02*
X1740286Y1206857D01*
X1731775D01*
G01X1740311Y1200139D02*
X1740286Y1200164D01*
X1731669D01*
G01X1731794Y1196818D02*
X1740287D01*
X1740311Y1196842D01*
G01Y1220218D02*
X1740286Y1220243D01*
X1731775D01*
G01X1740311Y1213525D02*
X1740286Y1213550D01*
X1731669D01*
G01X1740311Y1236950D02*
X1740286Y1236975D01*
X1731669D01*
G01X1731709Y1230282D02*
X1740290D01*
X1740311Y1230261D01*
G01X1731794Y1233629D02*
X1740287D01*
X1740311Y1233653D01*
G01X1739599Y1250358D02*
X1733099D01*
G01X1740311Y1243643D02*
X1740286Y1243668D01*
X1731775D01*
G01X1745888Y771845D02*
X1745916Y771817D01*
X1753821D01*
X1753869Y771865D01*
G01X1745888Y778538D02*
X1745916Y778510D01*
X1753821D01*
X1753869Y778558D01*
G01X1745888Y785228D02*
X1745912Y785204D01*
X1753826D01*
X1753869Y785247D01*
G01X1745888Y781829D02*
X1745916Y781857D01*
X1753840D01*
X1753869Y781828D01*
G01X1745888Y801964D02*
X1745916Y801936D01*
X1753821D01*
X1753869Y801984D01*
G01X1745888Y795271D02*
X1745916Y795243D01*
X1753821D01*
X1753869Y795291D01*
G01X1745888Y815349D02*
X1745916Y815321D01*
X1753821D01*
X1753869Y815369D01*
G01X1745888Y808656D02*
X1745916Y808628D01*
X1753821D01*
X1753869Y808676D01*
G01X1745888Y832082D02*
X1745916Y832054D01*
X1753821D01*
X1753869Y832102D01*
G01X1745888Y822039D02*
X1745912Y822015D01*
X1753826D01*
X1753869Y822058D01*
G01X1745888Y818640D02*
X1745916Y818668D01*
X1753840D01*
X1753869Y818639D01*
G01X1745888Y852160D02*
X1745916Y852132D01*
X1753821D01*
X1753869Y852180D01*
G01X1745888Y845467D02*
X1745916Y845439D01*
X1753821D01*
X1753869Y845487D01*
G01X1745888Y838775D02*
X1745916Y838747D01*
X1753821D01*
X1753869Y838795D01*
G01X1745888Y868893D02*
X1745916Y868865D01*
X1753821D01*
X1753869Y868913D01*
G01X1745888Y858850D02*
X1745912Y858826D01*
X1753826D01*
X1753869Y858869D01*
G01X1745888Y855451D02*
X1745916Y855479D01*
X1753840D01*
X1753869Y855450D01*
G01X1745888Y875586D02*
X1745916Y875558D01*
X1753821D01*
X1753869Y875606D01*
G01X1745888Y882278D02*
X1745916Y882250D01*
X1753821D01*
X1753869Y882298D01*
G01X1745888Y888971D02*
X1745916Y888943D01*
X1753821D01*
X1753869Y888991D01*
G01X1745888Y895661D02*
X1745912Y895637D01*
X1753826D01*
X1753869Y895680D01*
G01X1745888Y892262D02*
X1745916Y892290D01*
X1753840D01*
X1753869Y892261D01*
G01X1745888Y912397D02*
X1745916Y912369D01*
X1753821D01*
X1753869Y912417D01*
G01X1745888Y905704D02*
X1745916Y905676D01*
X1753821D01*
X1753869Y905724D01*
G01X1745916Y925754D02*
X1753657D01*
G01X1745916Y919062D02*
X1753821D01*
G01X1745916Y929101D02*
X1753840D01*
G01X1745916Y949180D02*
X1753657D01*
G01X1745916Y942487D02*
X1753821D01*
G01X1745912Y932448D02*
X1753826D01*
G01X1745888Y979340D02*
X1745930Y979298D01*
X1753840D01*
X1753869Y979327D01*
G01X1745888Y972647D02*
X1745930Y972605D01*
X1753840D01*
X1753869Y972634D01*
G01X1745888Y992726D02*
X1745930Y992684D01*
X1753840D01*
X1753869Y992713D01*
G01X1745888Y986033D02*
X1745930Y985991D01*
X1753840D01*
X1753869Y986020D01*
G01X1745888Y1046269D02*
X1745930Y1046227D01*
X1753840D01*
X1753869Y1046256D01*
G01X1745888Y1039576D02*
X1745930Y1039534D01*
X1753840D01*
X1753869Y1039563D01*
G01X1745888Y1032883D02*
X1745930Y1032841D01*
X1753840D01*
X1753869Y1032870D01*
G01X1753809Y1059613D02*
X1745839D01*
G01X1745916Y1072999D02*
X1753657D01*
G01X1745916Y1066306D02*
X1753821D01*
G01X1745916Y1076345D02*
X1753840D01*
G01X1745916Y1096424D02*
X1753657D01*
G01X1745916Y1089731D02*
X1753821D01*
G01X1745912Y1079692D02*
X1753826D01*
G01X1745888Y1109838D02*
X1745916Y1109810D01*
X1753821D01*
X1753869Y1109858D01*
G01X1745888Y1103145D02*
X1745916Y1103117D01*
X1753821D01*
X1753869Y1103165D01*
G01X1745888Y1126570D02*
X1745916Y1126542D01*
X1753821D01*
X1753869Y1126590D01*
G01X1745888Y1116527D02*
X1745912Y1116503D01*
X1753826D01*
X1753869Y1116546D01*
G01X1745888Y1113128D02*
X1745916Y1113156D01*
X1753840D01*
X1753869Y1113127D01*
G01X1745888Y1139956D02*
X1745916Y1139928D01*
X1753821D01*
X1753869Y1139976D01*
G01X1745888Y1133263D02*
X1745916Y1133235D01*
X1753821D01*
X1753869Y1133283D01*
G01X1745888Y1146649D02*
X1745916Y1146621D01*
X1753821D01*
X1753869Y1146669D01*
G01X1745888Y1153338D02*
X1745912Y1153314D01*
X1753826D01*
X1753869Y1153357D01*
G01X1745888Y1149940D02*
X1745916Y1149968D01*
X1753840D01*
X1753869Y1149939D01*
G01X1745888Y1176767D02*
X1745916Y1176739D01*
X1753821D01*
X1753869Y1176787D01*
G01X1745888Y1170074D02*
X1745916Y1170046D01*
X1753821D01*
X1753869Y1170094D01*
G01X1745888Y1163381D02*
X1745916Y1163353D01*
X1753821D01*
X1753869Y1163401D01*
G01X1745888Y1183460D02*
X1745916Y1183432D01*
X1753821D01*
X1753869Y1183480D01*
G01X1745888Y1190149D02*
X1745912Y1190125D01*
X1753826D01*
X1753869Y1190168D01*
G01X1745888Y1186751D02*
X1745916Y1186779D01*
X1753840D01*
X1753869Y1186750D01*
G01X1745888Y1206885D02*
X1745916Y1206857D01*
X1753821D01*
X1753869Y1206905D01*
G01X1745888Y1200192D02*
X1745916Y1200164D01*
X1753821D01*
X1753869Y1200212D01*
G01X1745888Y1220271D02*
X1745916Y1220243D01*
X1753821D01*
X1753869Y1220291D01*
G01X1745888Y1213578D02*
X1745916Y1213550D01*
X1753821D01*
X1753869Y1213598D01*
G01X1745888Y1223562D02*
X1745916Y1223590D01*
X1753840D01*
X1753869Y1223561D01*
G01X1745888Y1243696D02*
X1745916Y1243668D01*
X1753821D01*
X1753869Y1243716D01*
G01X1745888Y1237003D02*
X1745916Y1236975D01*
X1753821D01*
X1753869Y1237023D01*
G01X1745888Y1226960D02*
X1745912Y1226936D01*
X1753826D01*
X1753869Y1226979D01*
G01X1769329Y1250358D02*
X1762799D01*
G01X1783509Y1059613D02*
X1775599D01*
G01X1799711Y778486D02*
X1799686Y778511D01*
X1791175D01*
G01X1799711Y771793D02*
X1799686Y771818D01*
X1791069D01*
G01X1799711Y788529D02*
X1799690Y788550D01*
X1791109D01*
G01X1799711Y795218D02*
X1799686Y795243D01*
X1791069D01*
G01X1799711Y791921D02*
X1799687Y791897D01*
X1791194D01*
G01X1799711Y815297D02*
X1799686Y815322D01*
X1791175D01*
G01X1799711Y808604D02*
X1799686Y808629D01*
X1791069D01*
G01X1799711Y801911D02*
X1799686Y801936D01*
X1791175D01*
G01X1799711Y832029D02*
X1799686Y832054D01*
X1791069D01*
G01X1791109Y825361D02*
X1799690D01*
X1799711Y825340D01*
G01X1791194Y828708D02*
X1799687D01*
X1799711Y828732D01*
G01Y845415D02*
X1799686Y845440D01*
X1791069D01*
G01X1799711Y838722D02*
X1799686Y838747D01*
X1791175D01*
G01X1799711Y852108D02*
X1799686Y852133D01*
X1791175D01*
G01X1799711Y862151D02*
X1799690Y862172D01*
X1791109D01*
G01X1799711Y865543D02*
X1799687Y865519D01*
X1791194D01*
G01X1799711Y882226D02*
X1799686Y882251D01*
X1791069D01*
G01X1799711Y875533D02*
X1799686Y875558D01*
X1791175D01*
G01X1799711Y868840D02*
X1799686Y868865D01*
X1791069D01*
G01X1799711Y888919D02*
X1799686Y888944D01*
X1791175D01*
G01X1799711Y898962D02*
X1799690Y898983D01*
X1791109D01*
G01X1799711Y902354D02*
X1799687Y902330D01*
X1791194D01*
G01X1799711Y912344D02*
X1799686Y912369D01*
X1791175D01*
G01X1799711Y905651D02*
X1799686Y905676D01*
X1791069D01*
G01X1799711Y925730D02*
X1799686Y925755D01*
X1791175D01*
G01X1799711Y919037D02*
X1799686Y919062D01*
X1791069D01*
G01X1799711Y942462D02*
X1799686Y942487D01*
X1791069D01*
G01X1799711Y935773D02*
X1799690Y935794D01*
X1791109D01*
G01X1799711Y939165D02*
X1799687Y939141D01*
X1791194D01*
G01X1799711Y949155D02*
X1799686Y949180D01*
X1791175D01*
G01X1791109Y982644D02*
X1799662D01*
X1799711Y982693D01*
G01X1791109Y975951D02*
X1799662D01*
X1799711Y976000D01*
G01X1791109Y989337D02*
X1799662D01*
X1799711Y989386D01*
G01X1791109Y1029495D02*
X1799662D01*
X1799711Y1029544D01*
G01X1791099Y1019456D02*
X1799662D01*
X1799711Y1019505D01*
G01X1790767Y1049573D02*
X1799662D01*
X1799711Y1049622D01*
G01X1791109Y1042880D02*
X1799662D01*
X1799711Y1042929D01*
G01X1791109Y1036188D02*
X1799662D01*
X1799711Y1036237D01*
G01Y1059450D02*
X1799653D01*
X1799115Y1059613D01*
X1791730D01*
G01X1799711Y1072974D02*
X1799686Y1072999D01*
X1791175D01*
G01X1799711Y1066281D02*
X1799686Y1066306D01*
X1791069D01*
G01X1799711Y1089706D02*
X1799686Y1089731D01*
X1791069D01*
G01X1799711Y1083017D02*
X1799690Y1083038D01*
X1791109D01*
G01X1799711Y1086409D02*
X1799687Y1086385D01*
X1791194D01*
G01X1799711Y1096399D02*
X1799686Y1096424D01*
X1791175D01*
G01X1799711Y1109785D02*
X1799686Y1109810D01*
X1791175D01*
G01X1799711Y1103092D02*
X1799686Y1103117D01*
X1791069D01*
G01X1799711Y1126517D02*
X1799686Y1126542D01*
X1791069D01*
G01X1799711Y1119828D02*
X1799690Y1119849D01*
X1791109D01*
G01X1799711Y1123220D02*
X1799687Y1123196D01*
X1791194D01*
G01X1799711Y1139903D02*
X1799686Y1139928D01*
X1791069D01*
G01X1799711Y1133210D02*
X1799686Y1133235D01*
X1791175D01*
G01X1799711Y1146596D02*
X1799686Y1146621D01*
X1791175D01*
G01X1799711Y1156639D02*
X1799690Y1156660D01*
X1791109D01*
G01X1799711Y1160031D02*
X1799687Y1160007D01*
X1791194D01*
G01X1799711Y1170021D02*
X1799686Y1170046D01*
X1791175D01*
G01X1799711Y1163328D02*
X1799686Y1163353D01*
X1791069D01*
G01X1799711Y1183407D02*
X1799686Y1183432D01*
X1791175D01*
G01X1799711Y1176714D02*
X1799686Y1176739D01*
X1791069D01*
G01X1799711Y1193450D02*
X1799690Y1193471D01*
X1791109D01*
G01X1799711Y1206832D02*
X1799686Y1206857D01*
X1791175D01*
G01X1799711Y1200139D02*
X1799686Y1200164D01*
X1791069D01*
G01X1799711Y1196842D02*
X1799687Y1196818D01*
X1791194D01*
G01X1799711Y1220218D02*
X1799686Y1220243D01*
X1791175D01*
G01X1799711Y1213525D02*
X1799686Y1213550D01*
X1791069D01*
G01X1799711Y1236950D02*
X1799686Y1236975D01*
X1791069D01*
G01X1791109Y1230282D02*
X1799690D01*
X1799711Y1230261D01*
G01X1791194Y1233629D02*
X1799687D01*
X1799711Y1233653D01*
G01X1798919Y1250358D02*
X1792499D01*
G01X1799711Y1243643D02*
X1799686Y1243668D01*
X1791175D01*
G01X1805288Y771845D02*
X1805316Y771817D01*
X1813221D01*
X1813269Y771865D01*
G01X1805288Y778538D02*
X1805316Y778510D01*
X1813221D01*
X1813269Y778558D01*
G01Y785247D02*
X1813226Y785204D01*
X1805312D01*
X1805288Y785228D01*
G01X1813269Y781828D02*
X1813240Y781857D01*
X1805316D01*
X1805288Y781829D01*
G01Y801964D02*
X1805316Y801936D01*
X1813221D01*
X1813269Y801984D01*
G01X1805288Y795271D02*
X1805316Y795243D01*
X1813221D01*
X1813269Y795291D01*
G01X1805288Y815349D02*
X1805316Y815321D01*
X1813221D01*
X1813269Y815369D01*
G01X1805288Y808656D02*
X1805316Y808628D01*
X1813221D01*
X1813269Y808676D01*
G01X1805288Y818640D02*
X1805316Y818668D01*
X1813240D01*
X1813269Y818639D01*
G01X1805288Y832082D02*
X1805316Y832054D01*
X1813221D01*
X1813269Y832102D01*
G01X1805288Y822039D02*
X1805312Y822015D01*
X1813226D01*
X1813269Y822058D01*
G01X1805288Y852160D02*
X1805316Y852132D01*
X1813221D01*
X1813269Y852180D01*
G01X1805288Y845467D02*
X1805316Y845439D01*
X1813221D01*
X1813269Y845487D01*
G01X1805288Y838775D02*
X1805316Y838747D01*
X1813221D01*
X1813269Y838795D01*
G01X1805288Y868893D02*
X1805316Y868865D01*
X1813221D01*
X1813269Y868913D01*
G01Y858869D02*
X1813226Y858826D01*
X1805312D01*
X1805288Y858850D01*
G01X1813269Y855450D02*
X1813240Y855479D01*
X1805316D01*
X1805288Y855451D01*
G01Y875586D02*
X1805316Y875558D01*
X1813221D01*
X1813269Y875606D01*
G01X1805288Y882278D02*
X1805316Y882250D01*
X1813221D01*
X1813269Y882298D01*
G01X1805288Y888971D02*
X1805316Y888943D01*
X1813221D01*
X1813269Y888991D01*
G01Y895680D02*
X1813226Y895637D01*
X1805312D01*
X1805288Y895661D01*
G01X1813269Y892261D02*
X1813240Y892290D01*
X1805316D01*
X1805288Y892262D01*
G01Y912397D02*
X1805316Y912369D01*
X1813221D01*
X1813269Y912417D01*
G01X1805288Y905704D02*
X1805316Y905676D01*
X1813221D01*
X1813269Y905724D01*
G01X1805288Y925782D02*
X1805316Y925754D01*
X1813221D01*
X1813269Y925802D01*
G01X1805288Y919090D02*
X1805316Y919062D01*
X1813221D01*
X1813269Y919110D01*
G01Y932491D02*
X1813226Y932448D01*
X1805312D01*
X1805288Y932472D01*
G01X1813269Y929072D02*
X1813240Y929101D01*
X1805316D01*
X1805288Y929073D01*
G01Y949208D02*
X1805316Y949180D01*
X1813221D01*
X1813269Y949228D01*
G01X1805288Y942515D02*
X1805316Y942487D01*
X1813221D01*
X1813269Y942535D01*
G01X1805288Y979340D02*
X1805330Y979298D01*
X1813240D01*
X1813269Y979327D01*
G01X1805288Y972647D02*
X1805330Y972605D01*
X1813240D01*
X1813269Y972634D01*
G01X1805288Y992726D02*
X1805330Y992684D01*
X1813240D01*
X1813269Y992713D01*
G01X1805288Y986033D02*
X1805330Y985991D01*
X1813240D01*
X1813269Y986020D01*
G01X1805288Y1046269D02*
X1805330Y1046227D01*
X1813240D01*
X1813269Y1046256D01*
G01X1805288Y1039576D02*
X1805330Y1039534D01*
X1813240D01*
X1813269Y1039563D01*
G01X1805288Y1032883D02*
X1805330Y1032841D01*
X1813240D01*
X1813269Y1032870D01*
G01X1813239Y1059613D02*
X1805369D01*
G01X1805288Y1073027D02*
X1805316Y1072999D01*
X1813221D01*
X1813269Y1073047D01*
G01X1805288Y1066334D02*
X1805316Y1066306D01*
X1813221D01*
X1813269Y1066354D01*
G01Y1079735D02*
X1813226Y1079692D01*
X1805312D01*
X1805288Y1079716D01*
G01X1813269Y1076316D02*
X1813240Y1076345D01*
X1805316D01*
X1805288Y1076317D01*
G01Y1096452D02*
X1805316Y1096424D01*
X1813221D01*
X1813269Y1096472D01*
G01X1805288Y1089759D02*
X1805316Y1089731D01*
X1813221D01*
X1813269Y1089779D01*
G01X1805288Y1109838D02*
X1805316Y1109810D01*
X1813221D01*
X1813269Y1109858D01*
G01X1805288Y1103145D02*
X1805316Y1103117D01*
X1813221D01*
X1813269Y1103165D01*
G01X1805288Y1126570D02*
X1805316Y1126542D01*
X1813221D01*
X1813269Y1126590D01*
G01Y1116546D02*
X1813226Y1116503D01*
X1805312D01*
X1805288Y1116527D01*
G01X1813269Y1113127D02*
X1813240Y1113156D01*
X1805316D01*
X1805288Y1113128D01*
G01Y1139956D02*
X1805316Y1139928D01*
X1813221D01*
X1813269Y1139976D01*
G01X1805288Y1133263D02*
X1805316Y1133235D01*
X1813221D01*
X1813269Y1133283D01*
G01X1805288Y1146649D02*
X1805316Y1146621D01*
X1813221D01*
X1813269Y1146669D01*
G01Y1153357D02*
X1813226Y1153314D01*
X1805312D01*
X1805288Y1153338D01*
G01Y1149940D02*
X1805316Y1149968D01*
X1813240D01*
X1813269Y1149939D01*
G01X1805288Y1176767D02*
X1805316Y1176739D01*
X1813221D01*
X1813269Y1176787D01*
G01X1805288Y1170074D02*
X1805316Y1170046D01*
X1813221D01*
X1813269Y1170094D01*
G01X1805288Y1163381D02*
X1805316Y1163353D01*
X1813221D01*
X1813269Y1163401D01*
G01X1805288Y1183460D02*
X1805316Y1183432D01*
X1813221D01*
X1813269Y1183480D01*
G01Y1190168D02*
X1813226Y1190125D01*
X1805312D01*
X1805288Y1190149D01*
G01Y1186751D02*
X1805316Y1186779D01*
X1813240D01*
X1813269Y1186750D01*
G01X1805288Y1206885D02*
X1805316Y1206857D01*
X1813221D01*
X1813269Y1206905D01*
G01X1805288Y1200192D02*
X1805316Y1200164D01*
X1813221D01*
X1813269Y1200212D01*
G01X1805288Y1220271D02*
X1805316Y1220243D01*
X1813221D01*
X1813269Y1220291D01*
G01X1805288Y1213578D02*
X1805316Y1213550D01*
X1813221D01*
X1813269Y1213598D01*
G01X1805288Y1226960D02*
X1805312Y1226936D01*
X1813226D01*
X1813269Y1226979D01*
G01X1805288Y1223562D02*
X1805316Y1223590D01*
X1813240D01*
X1813269Y1223561D01*
G01X1805288Y1243696D02*
X1805316Y1243668D01*
X1813221D01*
X1813269Y1243716D01*
G01X1805288Y1237003D02*
X1805316Y1236975D01*
X1813221D01*
X1813269Y1237023D01*
G01X1828619Y1250358D02*
X1822199D01*
G01X1807274Y1510568D02*
Y1509253D01*
X1811178Y1505349D01*
X1811494D01*
G54D47*
X77416Y1541244D03*
G54D284*
X1285787Y127643D03*
G54D248*
X969075Y150629D03*
Y166377D03*
G54D293*
X1388056Y1415546D03*
G54D185*
X493760Y1406144D03*
X496122Y1416380D03*
X493760D03*
X1469901Y1406144D03*
X1472263Y1416380D03*
X1469901D03*
G54D38*
X59272Y1318588D03*
Y1322328D03*
Y1326068D03*
X69508Y1318588D03*
Y1326068D03*
X1753305Y1323508D03*
Y1316028D03*
X1743069D03*
Y1319768D03*
Y1323508D03*
G54D158*
X362889Y217622D03*
X371551Y221362D03*
X362889Y225102D03*
X513979Y444062D03*
X522641Y440322D03*
Y447802D03*
X660941Y110412D03*
X652279Y106672D03*
Y114152D03*
X843669Y374622D03*
Y382102D03*
X852331Y378362D03*
X1769520Y433793D03*
X1778182Y430053D03*
Y437533D03*
G54D176*
X442578Y1579509D03*
X440019D03*
X437460D03*
Y1586989D03*
X440019D03*
X442578D03*
X598661Y489622D03*
Y497102D03*
X604779Y426622D03*
X602220D03*
X599661D03*
Y434102D03*
X604779D03*
X603779Y489622D03*
X601220D03*
X603779Y497102D03*
X1213016Y1661115D03*
X1210457D03*
X1207898D03*
Y1668595D03*
X1210457D03*
X1213016D03*
G54D275*
X1212643Y228495D03*
X1210084D03*
X1207525D03*
Y236369D03*
X1210084D03*
X1212643D03*
X1313919Y81133D03*
Y89007D03*
X1329891Y72577D03*
X1327332D03*
X1324773D03*
Y80451D03*
X1327332D03*
X1329891D03*
X1319037Y81133D03*
X1316478D03*
Y89007D03*
X1319037D03*
G54D74*
X110757Y388071D03*
Y392071D03*
X113907Y388071D03*
D03*
X117057D03*
X113907Y392071D03*
D03*
X117057D03*
X155226Y425383D03*
X158376D03*
D03*
X155226Y421383D03*
X158376D03*
D03*
X155226Y417383D03*
X158376D03*
D03*
X155226Y443319D03*
X158376D03*
D03*
Y439397D03*
X155226D03*
X158376D03*
Y435383D03*
X155226D03*
X158376D03*
X155226Y430883D03*
X158376D03*
D03*
X161526Y425383D03*
Y421383D03*
Y417383D03*
Y443319D03*
Y439397D03*
Y435383D03*
Y430883D03*
X235147Y127118D03*
X238297D03*
X1013620Y226423D03*
X1016770D03*
X1671605Y201670D03*
X1674755D03*
X1710268Y128242D03*
X1713418D03*
G54D149*
X333568Y388690D03*
Y394596D03*
Y400628D03*
Y406534D03*
X340654Y394596D03*
Y388690D03*
Y406534D03*
Y400628D03*
X366714Y363438D03*
Y369344D03*
Y375696D03*
Y381602D03*
Y400628D03*
Y406534D03*
X373800Y363438D03*
Y369344D03*
Y375696D03*
Y381602D03*
Y406534D03*
Y400628D03*
G54D257*
X1004657Y379678D03*
X1002688D03*
X1000719D03*
X998751D03*
X996782D03*
Y404284D03*
X998751D03*
X1000719D03*
X1002688D03*
X1004657D03*
X1016468Y379678D03*
X1014499D03*
X1012531D03*
X1010562D03*
X1008593D03*
X1006625D03*
Y404284D03*
X1008593D03*
X1010562D03*
X1012531D03*
X1014499D03*
X1016468D03*
G54D83*
X106818Y1586793D03*
Y1589352D03*
Y1591911D03*
Y1598572D03*
Y1617262D03*
Y1601131D03*
Y1603690D03*
Y1619821D03*
Y1622380D03*
Y1635303D03*
Y1637862D03*
Y1640421D03*
X114298Y1591911D03*
Y1589352D03*
Y1586793D03*
Y1598572D03*
Y1617262D03*
Y1603690D03*
Y1601131D03*
Y1622380D03*
Y1619821D03*
Y1640421D03*
Y1637862D03*
Y1635303D03*
X242215Y144320D03*
Y146879D03*
Y149438D03*
X249695D03*
Y146879D03*
Y144320D03*
X249735Y160162D03*
Y157603D03*
Y155044D03*
X242255D03*
Y157603D03*
Y160162D03*
X333174Y363143D03*
Y375364D03*
Y377923D03*
Y380482D03*
Y365702D03*
Y368261D03*
X340654Y363143D03*
Y380482D03*
Y377923D03*
Y375364D03*
Y368261D03*
Y365702D03*
X366679Y389478D03*
Y392037D03*
Y394596D03*
X374159D03*
Y392037D03*
Y389478D03*
X395960Y323761D03*
Y321202D03*
Y318643D03*
X388480D03*
Y321202D03*
Y323761D03*
X401175Y363081D03*
X393695D03*
X401081Y378439D03*
Y375880D03*
X393601D03*
Y378439D03*
X401175Y368199D03*
Y365640D03*
X393695D03*
Y368199D03*
X401070Y393992D03*
Y391433D03*
Y388874D03*
X393590D03*
Y391433D03*
Y393992D03*
X401081Y380998D03*
X393601D03*
X401129Y406863D03*
Y404304D03*
Y401745D03*
X393649D03*
Y404304D03*
Y406863D03*
X418960Y1606441D03*
Y1609000D03*
Y1611559D03*
X429249Y363644D03*
X421769D03*
X429003Y379201D03*
Y376642D03*
X421523D03*
Y379201D03*
X429249Y368762D03*
Y366203D03*
X421769D03*
Y368762D03*
X429003Y381760D03*
X421523D03*
X428839Y394722D03*
Y392163D03*
Y389604D03*
X421359D03*
Y392163D03*
Y394722D03*
X428962Y407847D03*
Y405288D03*
Y402729D03*
X421482D03*
Y405288D03*
Y407847D03*
X426440Y1611559D03*
Y1609000D03*
Y1606441D03*
X531980Y178803D03*
Y181362D03*
Y183921D03*
X539460D03*
Y181362D03*
Y178803D03*
X586760Y514303D03*
Y516862D03*
Y519421D03*
X594240D03*
Y516862D03*
Y514303D03*
X673612Y1634844D03*
Y1637403D03*
Y1639962D03*
X679148Y1652262D03*
Y1654821D03*
Y1657380D03*
X681092Y1639962D03*
Y1637403D03*
Y1634844D03*
X686628Y1657380D03*
Y1654821D03*
Y1652262D03*
X761245Y167518D03*
Y170077D03*
Y172636D03*
X768725Y167518D03*
Y172636D03*
Y170077D03*
X819684Y264580D03*
Y267139D03*
Y269698D03*
X827164Y264580D03*
Y269698D03*
Y267139D03*
X1134512Y1620851D03*
Y1623410D03*
Y1625969D03*
X1141992D03*
Y1623410D03*
Y1620851D03*
X1408260Y1583441D03*
Y1586000D03*
Y1588559D03*
X1415740Y1583441D03*
Y1588559D03*
Y1586000D03*
X1419270Y1623391D03*
Y1625950D03*
Y1628509D03*
X1426750D03*
Y1625950D03*
Y1623391D03*
X1423240Y1639921D03*
Y1637362D03*
Y1634803D03*
X1415760D03*
Y1637362D03*
Y1639921D03*
X1440273Y1518976D03*
X1432793D03*
X1440513Y1534796D03*
X1433033D03*
X1440273Y1524094D03*
Y1521535D03*
X1432793D03*
Y1524094D03*
X1440663Y1551134D03*
Y1548575D03*
Y1546016D03*
X1433183D03*
Y1548575D03*
Y1551134D03*
X1440513Y1539914D03*
Y1537355D03*
X1433033D03*
Y1539914D03*
X1457540Y1607559D03*
Y1605000D03*
Y1602441D03*
X1450060D03*
Y1605000D03*
Y1607559D03*
X1682008Y1498303D03*
Y1500862D03*
Y1503421D03*
Y1517803D03*
Y1520362D03*
Y1522921D03*
Y1538803D03*
Y1541362D03*
Y1543921D03*
Y1558262D03*
Y1560821D03*
Y1563380D03*
Y1578762D03*
Y1581321D03*
Y1583880D03*
X1689488Y1503421D03*
Y1500862D03*
Y1498303D03*
Y1517803D03*
Y1522921D03*
Y1520362D03*
Y1543921D03*
Y1541362D03*
Y1538803D03*
Y1563380D03*
Y1560821D03*
Y1558262D03*
Y1583880D03*
Y1581321D03*
Y1578762D03*
X1813335Y158868D03*
Y161427D03*
Y163986D03*
X1831277Y151402D03*
X1820815Y163986D03*
Y161427D03*
Y158868D03*
X1831277Y153961D03*
Y156520D03*
X1838757Y151402D03*
Y156520D03*
Y153961D03*
G54D239*
X925189Y499086D03*
G54D65*
X93361Y1533173D03*
G54D56*
X91949Y714088D03*
X1705381Y718214D03*
G54D29*
X45812Y451602D03*
X49212D03*
X64410Y1599102D03*
Y1602502D03*
X723041Y-19800D03*
Y-23200D03*
X840001Y6800D03*
Y10200D03*
X980899Y-19800D03*
Y-23200D03*
Y6800D03*
Y10200D03*
X1032433Y-29811D03*
Y-33211D03*
Y-13211D03*
Y-9811D03*
X1290291Y-29811D03*
Y-33211D03*
Y-13211D03*
Y-9811D03*
X1307677Y322996D03*
X1311077D03*
X1319618Y318073D03*
X1325080Y323902D03*
X1316218Y318073D03*
X1328480Y323902D03*
X1341752Y-29811D03*
Y-33211D03*
Y-9811D03*
Y-13211D03*
X1335145Y332616D03*
X1341431Y322693D03*
X1331745Y332616D03*
X1338031Y322693D03*
X1345424Y328981D03*
X1348824D03*
X1358371Y332275D03*
X1361771D03*
X1355200Y337843D03*
X1351800D03*
X1482650Y-29811D03*
Y-33211D03*
Y-9811D03*
Y-13211D03*
G54D194*
X572690Y1323203D03*
Y1341313D03*
X1263605Y1322514D03*
Y1340624D03*
G54D167*
X401767Y1415210D03*
G54D266*
X1055563Y253771D03*
X1080759D03*
G54D92*
X163642Y1380504D03*
X201785D03*
X317625Y1338650D03*
X349753Y1315852D03*
X381881Y1302426D03*
X414009D03*
X446137D03*
X478265D03*
X510393Y1315852D03*
X542521Y1338650D03*
X677261Y1380529D03*
X715404D03*
X1136953Y1416833D03*
X1175096D03*
X1293886Y1338886D03*
X1325894Y1315852D03*
X1358022Y1302426D03*
X1390150D03*
X1422278D03*
X1454406D03*
X1486534Y1315852D03*
X1518662Y1338650D03*
X1638427Y1414125D03*
X1676570D03*
G54D348*
G01X32049Y780184D02*
X37302D01*
X38242Y781124D01*
X40048D01*
X40728Y780444D01*
Y779304D01*
X41553Y778479D01*
X43765D01*
G01X52919Y778511D02*
X54686D01*
X56359Y780184D01*
X61749D01*
G01X32049Y773491D02*
X37302D01*
X38134Y774323D01*
X40120D01*
X40728Y773715D01*
Y772423D01*
X41368Y771783D01*
X43765D01*
G01X52919Y771818D02*
X53622D01*
X55295Y773491D01*
X61749D01*
G01Y786877D02*
X59597D01*
X58569Y787905D01*
X56968D01*
X55294Y789579D01*
X54559D01*
X53530Y788550D01*
X52919D01*
G01X43765Y788508D02*
X42961D01*
X41890Y789579D01*
X39764D01*
X37260Y787905D01*
X35237D01*
X34209Y786877D01*
X32049D01*
G01Y803609D02*
X37302D01*
X38242Y804549D01*
X40048D01*
X40728Y803869D01*
Y802729D01*
X41553Y801904D01*
X43765D01*
G01X52919Y801936D02*
X54686D01*
X56359Y803609D01*
X61749D01*
G01X32049Y796916D02*
X37302D01*
X38134Y797748D01*
X40120D01*
X40728Y797140D01*
Y795848D01*
X41368Y795208D01*
X43765D01*
G01X52919Y795243D02*
X53622D01*
X55295Y796916D01*
X61749D01*
G01Y790223D02*
X59589D01*
X58561Y789195D01*
X57503D01*
X55829Y790869D01*
X54546D01*
X53518Y791897D01*
X52919D01*
G01X43765Y791934D02*
X42906D01*
X41841Y790869D01*
X39372D01*
X36868Y789195D01*
X35195D01*
X34167Y790223D01*
X32049D01*
G01Y816995D02*
X37302D01*
X38242Y817935D01*
X40048D01*
X40728Y817255D01*
Y816115D01*
X41553Y815290D01*
X43765D01*
G01X52919Y815322D02*
X54686D01*
X56359Y816995D01*
X61749D01*
G01X32049Y810302D02*
X37302D01*
X38134Y811134D01*
X40120D01*
X40728Y810526D01*
Y809234D01*
X41368Y808594D01*
X43765D01*
G01X52919Y808629D02*
X53622D01*
X55295Y810302D01*
X61749D01*
G01X32049Y833727D02*
X37302D01*
X38134Y834559D01*
X40120D01*
X40728Y833951D01*
Y832659D01*
X41368Y832019D01*
X43765D01*
G01X52919Y832054D02*
X53622D01*
X55295Y833727D01*
X61749D01*
G01Y823688D02*
X59597D01*
X58569Y824716D01*
X56968D01*
X55294Y826390D01*
X54559D01*
X53530Y825361D01*
X52919D01*
G01X43765Y825319D02*
X42961D01*
X41890Y826390D01*
X39764D01*
X37260Y824716D01*
X35237D01*
X34209Y823688D01*
X32049D01*
G01X61749Y827034D02*
X59589D01*
X58561Y826006D01*
X57503D01*
X55829Y827680D01*
X54546D01*
X53518Y828708D01*
X52919D01*
G01X43765Y828745D02*
X42906D01*
X41841Y827680D01*
X39372D01*
X36868Y826006D01*
X35195D01*
X34167Y827034D01*
X32049D01*
G01Y853806D02*
X37302D01*
X38242Y854746D01*
X40048D01*
X40728Y854066D01*
Y852926D01*
X41553Y852101D01*
X43765D01*
G01X52919Y852133D02*
X54686D01*
X56359Y853806D01*
X61749D01*
G01X32049Y847113D02*
X37302D01*
X38134Y847945D01*
X40120D01*
X40728Y847337D01*
Y846045D01*
X41368Y845405D01*
X43765D01*
G01X52919Y845440D02*
X53622D01*
X55295Y847113D01*
X61749D01*
G01X32049Y840420D02*
X37302D01*
X38242Y841360D01*
X40048D01*
X40728Y840680D01*
Y839540D01*
X41553Y838715D01*
X43765D01*
G01X52919Y838747D02*
X54686D01*
X56359Y840420D01*
X61749D01*
G01Y860499D02*
X59597D01*
X58569Y861527D01*
X56968D01*
X55294Y863201D01*
X54559D01*
X53530Y862172D01*
X52919D01*
G01X43765Y862130D02*
X42961D01*
X41890Y863201D01*
X39764D01*
X37260Y861527D01*
X35237D01*
X34209Y860499D01*
X32049D01*
G01X61749Y863845D02*
X59589D01*
X58561Y862817D01*
X57503D01*
X55829Y864491D01*
X54546D01*
X53518Y865519D01*
X52919D01*
G01X43765Y865556D02*
X42906D01*
X41841Y864491D01*
X39372D01*
X36868Y862817D01*
X35195D01*
X34167Y863845D01*
X32049D01*
G01Y883924D02*
X37302D01*
X38134Y884756D01*
X40120D01*
X40728Y884148D01*
Y882856D01*
X41368Y882216D01*
X43765D01*
G01X52919Y882251D02*
X53622D01*
X55295Y883924D01*
X61749D01*
G01X32049Y877231D02*
X37302D01*
X38242Y878171D01*
X40048D01*
X40728Y877491D01*
Y876351D01*
X41553Y875526D01*
X43765D01*
G01X52919Y875558D02*
X54686D01*
X56359Y877231D01*
X61749D01*
G01X32049Y870538D02*
X37302D01*
X38134Y871370D01*
X40120D01*
X40728Y870762D01*
Y869470D01*
X41368Y868830D01*
X43765D01*
G01X52919Y868865D02*
X53622D01*
X55295Y870538D01*
X61749D01*
G01X32049Y890617D02*
X37302D01*
X38242Y891557D01*
X40048D01*
X40728Y890877D01*
Y889737D01*
X41553Y888912D01*
X43765D01*
G01X52919Y888944D02*
X54686D01*
X56359Y890617D01*
X61749D01*
G01Y897310D02*
X59597D01*
X58569Y898338D01*
X56968D01*
X55294Y900012D01*
X54559D01*
X53530Y898983D01*
X52919D01*
G01X43765Y898941D02*
X42961D01*
X41890Y900012D01*
X39764D01*
X37260Y898338D01*
X35237D01*
X34209Y897310D01*
X32049D01*
G01X61749Y900656D02*
X59589D01*
X58561Y899628D01*
X57503D01*
X55829Y901302D01*
X54546D01*
X53518Y902330D01*
X52919D01*
G01X43765Y902367D02*
X42906D01*
X41841Y901302D01*
X39372D01*
X36868Y899628D01*
X35195D01*
X34167Y900656D01*
X32049D01*
G01Y914042D02*
X37302D01*
X38242Y914982D01*
X40048D01*
X40728Y914302D01*
Y913162D01*
X41553Y912337D01*
X43765D01*
G01X52919Y912369D02*
X54686D01*
X56359Y914042D01*
X61749D01*
G01X32049Y907349D02*
X37302D01*
X38134Y908181D01*
X40120D01*
X40728Y907573D01*
Y906281D01*
X41368Y905641D01*
X43765D01*
G01X52919Y905676D02*
X53622D01*
X55295Y907349D01*
X61749D01*
G01X32049Y927428D02*
X37302D01*
X38242Y928368D01*
X40048D01*
X40728Y927688D01*
Y926548D01*
X41553Y925723D01*
X43765D01*
G01X52919Y925755D02*
X54686D01*
X56359Y927428D01*
X61749D01*
G01X32049Y920735D02*
X37302D01*
X38134Y921567D01*
X40120D01*
X40728Y920959D01*
Y919667D01*
X41368Y919027D01*
X43765D01*
G01X52919Y919062D02*
X53622D01*
X55295Y920735D01*
X61749D01*
G01X32049Y950853D02*
X37302D01*
X38242Y951793D01*
X40048D01*
X40728Y951113D01*
Y949973D01*
X41553Y949148D01*
X43765D01*
G01X52919Y949180D02*
X54686D01*
X56359Y950853D01*
X61749D01*
G01X32049Y944160D02*
X37302D01*
X38134Y944992D01*
X40120D01*
X40728Y944384D01*
Y943092D01*
X41368Y942452D01*
X43765D01*
G01X52919Y942487D02*
X53622D01*
X55295Y944160D01*
X61749D01*
G01Y934121D02*
X59597D01*
X58569Y935149D01*
X56968D01*
X55294Y936823D01*
X54559D01*
X53530Y935794D01*
X52919D01*
G01X43765Y935752D02*
X42961D01*
X41890Y936823D01*
X39764D01*
X37260Y935149D01*
X35237D01*
X34209Y934121D01*
X32049D01*
G01X61749Y937467D02*
X59589D01*
X58561Y936439D01*
X57503D01*
X55829Y938113D01*
X54546D01*
X53518Y939141D01*
X52919D01*
G01X43765Y939178D02*
X42906D01*
X41841Y938113D01*
X39372D01*
X36868Y936439D01*
X35195D01*
X34167Y937467D01*
X32049D01*
G01Y960892D02*
X36399D01*
G01X32049Y957546D02*
X36399D01*
G01X32049Y980971D02*
X37302D01*
X38134Y981803D01*
X40120D01*
X40728Y981195D01*
Y979903D01*
X41368Y979263D01*
X43765D01*
G01X52919Y979298D02*
X53622D01*
X55295Y980971D01*
X61749D01*
G01X32049Y974278D02*
X37302D01*
X38134Y975110D01*
X40120D01*
X40728Y974502D01*
Y973210D01*
X41368Y972570D01*
X43765D01*
G01X52919Y972605D02*
X53622D01*
X55295Y974278D01*
X61749D01*
G01X32049Y967585D02*
X36399D01*
G01X32049Y994357D02*
X37302D01*
X38134Y995189D01*
X40120D01*
X40728Y994581D01*
Y993289D01*
X41368Y992649D01*
X43765D01*
G01X52919Y992684D02*
X53622D01*
X55295Y994357D01*
X61749D01*
G01X32049Y987664D02*
X37302D01*
X38134Y988496D01*
X40120D01*
X40728Y987888D01*
Y986596D01*
X41368Y985956D01*
X43765D01*
G01X52919Y985991D02*
X53622D01*
X55295Y987664D01*
X61749D01*
G01X32049Y1027822D02*
X37302D01*
X38134Y1028654D01*
X40120D01*
X40728Y1028046D01*
Y1026754D01*
X41368Y1026114D01*
X43765D01*
G01X52919Y1026149D02*
X53622D01*
X55295Y1027822D01*
X61749D01*
G01X32049Y1021129D02*
X37302D01*
X38243Y1022070D01*
X39927D01*
X40728Y1021269D01*
Y1020061D01*
X41280Y1019509D01*
X41281Y1019510D01*
X43765D01*
G01X52919Y1019456D02*
X53358D01*
X55031Y1021129D01*
X61749D01*
G01X32049Y1047900D02*
X37302D01*
X38134Y1048732D01*
X40120D01*
X40728Y1048124D01*
Y1046832D01*
X41368Y1046192D01*
X43765D01*
G01X52919Y1046227D02*
X53622D01*
X55295Y1047900D01*
X61749D01*
G01X32049Y1041207D02*
X37302D01*
X38134Y1042039D01*
X40120D01*
X40728Y1041431D01*
Y1040139D01*
X41368Y1039499D01*
X43765D01*
G01X52919Y1039534D02*
X53622D01*
X55295Y1041207D01*
X61749D01*
G01X32049Y1034515D02*
X37302D01*
X38134Y1035347D01*
X40120D01*
X40728Y1034739D01*
Y1033447D01*
X41368Y1032807D01*
X43765D01*
G01X52919Y1032842D02*
X53622D01*
X55295Y1034515D01*
X61749D01*
G01X32049Y1061286D02*
X37302D01*
X38134Y1062118D01*
X40120D01*
X40728Y1061510D01*
Y1060218D01*
X41368Y1059578D01*
X43765D01*
G01X52919Y1059613D02*
X53714D01*
X55387Y1061286D01*
X61749D01*
G01X32049Y1054593D02*
X36399D01*
G01X32049Y1074672D02*
X37302D01*
X38242Y1075612D01*
X40048D01*
X40728Y1074932D01*
Y1073792D01*
X41553Y1072967D01*
X43765D01*
G01X52919Y1072999D02*
X54686D01*
X56359Y1074672D01*
X61749D01*
G01X32049Y1067979D02*
X37302D01*
X38134Y1068811D01*
X40120D01*
X40728Y1068203D01*
Y1066911D01*
X41368Y1066271D01*
X43765D01*
G01X52919Y1066306D02*
X53622D01*
X55295Y1067979D01*
X61749D01*
G01X32049Y1091404D02*
X37302D01*
X38134Y1092236D01*
X40120D01*
X40728Y1091628D01*
Y1090336D01*
X41368Y1089696D01*
X43765D01*
G01X52919Y1089731D02*
X53622D01*
X55295Y1091404D01*
X61749D01*
G01Y1081365D02*
X59597D01*
X58569Y1082393D01*
X56968D01*
X55294Y1084067D01*
X54559D01*
X53530Y1083038D01*
X52919D01*
G01X43765Y1082996D02*
X42961D01*
X41890Y1084067D01*
X39764D01*
X37260Y1082393D01*
X35237D01*
X34209Y1081365D01*
X32049D01*
G01X61749Y1084711D02*
X59589D01*
X58561Y1083683D01*
X57503D01*
X55829Y1085357D01*
X54546D01*
X53518Y1086385D01*
X52919D01*
G01X43765Y1086422D02*
X42906D01*
X41841Y1085357D01*
X39372D01*
X36868Y1083683D01*
X35195D01*
X34167Y1084711D01*
X32049D01*
G01Y1098097D02*
X37302D01*
X38242Y1099037D01*
X40048D01*
X40728Y1098357D01*
Y1097217D01*
X41553Y1096392D01*
X43765D01*
G01X52919Y1096424D02*
X54686D01*
X56359Y1098097D01*
X61749D01*
G01X32049Y1111483D02*
X37302D01*
X38242Y1112423D01*
X40048D01*
X40728Y1111743D01*
Y1110603D01*
X41553Y1109778D01*
X43765D01*
G01X52919Y1109810D02*
X54686D01*
X56359Y1111483D01*
X61749D01*
G01X32049Y1104790D02*
X37302D01*
X38134Y1105622D01*
X40120D01*
X40728Y1105014D01*
Y1103722D01*
X41368Y1103082D01*
X43765D01*
G01X52919Y1103117D02*
X53622D01*
X55295Y1104790D01*
X61749D01*
G01X32049Y1128215D02*
X37302D01*
X38134Y1129047D01*
X40120D01*
X40728Y1128439D01*
Y1127147D01*
X41368Y1126507D01*
X43765D01*
G01X52919Y1126542D02*
X53622D01*
X55295Y1128215D01*
X61749D01*
G01Y1118176D02*
X59597D01*
X58569Y1119204D01*
X56968D01*
X55294Y1120878D01*
X54559D01*
X53530Y1119849D01*
X52919D01*
G01X43765Y1119807D02*
X42961D01*
X41890Y1120878D01*
X39764D01*
X37260Y1119204D01*
X35237D01*
X34209Y1118176D01*
X32049D01*
G01X61749Y1121522D02*
X59589D01*
X58561Y1120494D01*
X57503D01*
X55829Y1122168D01*
X54546D01*
X53518Y1123196D01*
X52919D01*
G01X43765Y1123233D02*
X42906D01*
X41841Y1122168D01*
X39372D01*
X36868Y1120494D01*
X35195D01*
X34167Y1121522D01*
X32049D01*
G01Y1141601D02*
X37302D01*
X38134Y1142433D01*
X40120D01*
X40728Y1141825D01*
Y1140533D01*
X41368Y1139893D01*
X43765D01*
G01X52919Y1139928D02*
X53622D01*
X55295Y1141601D01*
X61749D01*
G01X32049Y1134908D02*
X37302D01*
X38242Y1135848D01*
X40048D01*
X40728Y1135168D01*
Y1134028D01*
X41553Y1133203D01*
X43765D01*
G01X52919Y1133235D02*
X54686D01*
X56359Y1134908D01*
X61749D01*
G01X32049Y1148294D02*
X37302D01*
X38242Y1149234D01*
X40048D01*
X40728Y1148554D01*
Y1147414D01*
X41553Y1146589D01*
X43765D01*
G01X52919Y1146621D02*
X54686D01*
X56359Y1148294D01*
X61749D01*
G01Y1154987D02*
X59597D01*
X58569Y1156015D01*
X56968D01*
X55294Y1157689D01*
X54559D01*
X53530Y1156660D01*
X52919D01*
G01X43765Y1156618D02*
X42961D01*
X41890Y1157689D01*
X39764D01*
X37260Y1156015D01*
X35237D01*
X34209Y1154987D01*
X32049D01*
G01X61749Y1158333D02*
X59589D01*
X58561Y1157305D01*
X57503D01*
X55829Y1158979D01*
X54546D01*
X53518Y1160007D01*
X52919D01*
G01X43765Y1160044D02*
X42906D01*
X41841Y1158979D01*
X39372D01*
X36868Y1157305D01*
X35195D01*
X34167Y1158333D01*
X32049D01*
G01Y1178412D02*
X37302D01*
X38134Y1179244D01*
X40120D01*
X40728Y1178636D01*
Y1177344D01*
X41368Y1176704D01*
X43765D01*
G01X52919Y1176739D02*
X53622D01*
X55295Y1178412D01*
X61749D01*
G01X32049Y1171719D02*
X37302D01*
X38242Y1172659D01*
X40048D01*
X40728Y1171979D01*
Y1170839D01*
X41553Y1170014D01*
X43765D01*
G01X52919Y1170046D02*
X54686D01*
X56359Y1171719D01*
X61749D01*
G01X32049Y1165026D02*
X37302D01*
X38134Y1165858D01*
X40120D01*
X40728Y1165250D01*
Y1163958D01*
X41368Y1163318D01*
X43765D01*
G01X52919Y1163353D02*
X53622D01*
X55295Y1165026D01*
X61749D01*
G01X32049Y1185105D02*
X37302D01*
X38242Y1186045D01*
X40048D01*
X40728Y1185365D01*
Y1184225D01*
X41553Y1183400D01*
X43765D01*
G01X52919Y1183432D02*
X54686D01*
X56359Y1185105D01*
X61749D01*
G01Y1191798D02*
X59597D01*
X58569Y1192826D01*
X56968D01*
X55294Y1194500D01*
X54559D01*
X53530Y1193471D01*
X52919D01*
G01X43765Y1193429D02*
X42961D01*
X41890Y1194500D01*
X39764D01*
X37260Y1192826D01*
X35237D01*
X34209Y1191798D01*
X32049D01*
G01Y1208530D02*
X37302D01*
X38242Y1209470D01*
X40048D01*
X40728Y1208790D01*
Y1207650D01*
X41553Y1206825D01*
X43765D01*
G01X52919Y1206857D02*
X54686D01*
X56359Y1208530D01*
X61749D01*
G01X32049Y1201837D02*
X37302D01*
X38134Y1202669D01*
X40120D01*
X40728Y1202061D01*
Y1200769D01*
X41368Y1200129D01*
X43765D01*
G01X52919Y1200164D02*
X53622D01*
X55295Y1201837D01*
X61749D01*
G01Y1195144D02*
X59589D01*
X58561Y1194116D01*
X57503D01*
X55829Y1195790D01*
X54546D01*
X53518Y1196818D01*
X52919D01*
G01X43765Y1196855D02*
X42906D01*
X41841Y1195790D01*
X39372D01*
X36868Y1194116D01*
X35195D01*
X34167Y1195144D01*
X32049D01*
G01Y1221916D02*
X37302D01*
X38242Y1222856D01*
X40048D01*
X40728Y1222176D01*
Y1221036D01*
X41553Y1220211D01*
X43765D01*
G01X52919Y1220243D02*
X54686D01*
X56359Y1221916D01*
X61749D01*
G01X32049Y1215223D02*
X37302D01*
X38134Y1216055D01*
X40120D01*
X40728Y1215447D01*
Y1214155D01*
X41368Y1213515D01*
X43765D01*
G01X52919Y1213550D02*
X53622D01*
X55295Y1215223D01*
X61749D01*
G01X32049Y1238648D02*
X37302D01*
X38134Y1239480D01*
X40120D01*
X40728Y1238872D01*
Y1237580D01*
X41368Y1236940D01*
X43765D01*
G01X52919Y1236975D02*
X53622D01*
X55295Y1238648D01*
X61749D01*
G01Y1228609D02*
X59597D01*
X58569Y1229637D01*
X56968D01*
X55294Y1231311D01*
X54559D01*
X53530Y1230282D01*
X52919D01*
G01X43765Y1230240D02*
X42961D01*
X41890Y1231311D01*
X39764D01*
X37260Y1229637D01*
X35237D01*
X34209Y1228609D01*
X32049D01*
G01X61749Y1231955D02*
X59589D01*
X58561Y1230927D01*
X57503D01*
X55829Y1232601D01*
X54546D01*
X53518Y1233629D01*
X52919D01*
G01X43765Y1233666D02*
X42906D01*
X41841Y1232601D01*
X39372D01*
X36868Y1230927D01*
X35195D01*
X34167Y1231955D01*
X32049D01*
G01Y1245341D02*
X37302D01*
X38242Y1246281D01*
X40048D01*
X40728Y1245601D01*
Y1244461D01*
X41553Y1243636D01*
X43765D01*
G01X52919Y1243668D02*
X54686D01*
X56359Y1245341D01*
X61749D01*
G01X48191Y770144D02*
X54873D01*
X55369Y770640D01*
Y771312D01*
X55930Y771873D01*
X57323D01*
G01X66477Y771817D02*
X68620D01*
X69207Y771230D01*
Y770633D01*
X69713Y770127D01*
X71269D01*
X72103Y770961D01*
X73861D01*
X74678Y770144D01*
X77891D01*
G01X48191Y776837D02*
X52707D01*
X54420Y775124D01*
X57323D01*
G01X66477Y775164D02*
X68969D01*
X69535Y775730D01*
Y777012D01*
X70194Y777671D01*
X71881D01*
X72715Y776837D01*
X77891D01*
G01Y786877D02*
X75960D01*
X74932Y785849D01*
X72162D01*
X69658Y784176D01*
X68065D01*
X67037Y785204D01*
X66477D01*
G01X57323Y785235D02*
X56595D01*
X55546Y784186D01*
X54602D01*
X52939Y785849D01*
X51076D01*
X50048Y786877D01*
X48191D01*
G01X77891Y783530D02*
X75963D01*
X74934Y784559D01*
X72554D01*
X70050Y782886D01*
X68062D01*
X67034Y781858D01*
X66477D01*
G01X57323Y781835D02*
X56546D01*
X55485Y782896D01*
X54067D01*
X52404Y784559D01*
X51088D01*
X50059Y783530D01*
X48191D01*
G01Y800263D02*
X52707D01*
X54420Y798550D01*
X57323D01*
G01X66477Y798590D02*
X68969D01*
X69535Y799156D01*
Y800438D01*
X70194Y801097D01*
X71881D01*
X72715Y800263D01*
X77891D01*
G01X48191Y793570D02*
X54873D01*
X55369Y794066D01*
Y794738D01*
X55930Y795299D01*
X57323D01*
G01X66477Y795243D02*
X68620D01*
X69207Y794656D01*
Y794059D01*
X69713Y793553D01*
X71269D01*
X72103Y794387D01*
X73861D01*
X74678Y793570D01*
X77891D01*
G01X48191Y813648D02*
X52707D01*
X54420Y811935D01*
X57323D01*
G01X66477Y811975D02*
X68969D01*
X69535Y812541D01*
Y813823D01*
X70194Y814482D01*
X71881D01*
X72715Y813648D01*
X77891D01*
G01X48191Y806955D02*
X54873D01*
X55369Y807451D01*
Y808123D01*
X55930Y808684D01*
X57323D01*
G01X66477Y808628D02*
X68620D01*
X69207Y808041D01*
Y807444D01*
X69713Y806938D01*
X71269D01*
X72103Y807772D01*
X73861D01*
X74678Y806955D01*
X77891D01*
G01Y820341D02*
X75963D01*
X74934Y821370D01*
X72554D01*
X70050Y819697D01*
X68062D01*
X67034Y818669D01*
X66477D01*
G01X57323Y818646D02*
X56546D01*
X55485Y819707D01*
X54067D01*
X52404Y821370D01*
X51088D01*
X50059Y820341D01*
X48191D01*
G01Y837074D02*
X52707D01*
X54420Y835361D01*
X57323D01*
G01X66477Y835401D02*
X68969D01*
X69535Y835967D01*
Y837249D01*
X70194Y837908D01*
X71881D01*
X72715Y837074D01*
X77891D01*
G01X48191Y830381D02*
X54873D01*
X55369Y830877D01*
Y831549D01*
X55930Y832110D01*
X57323D01*
G01X66477Y832054D02*
X68620D01*
X69207Y831467D01*
Y830870D01*
X69713Y830364D01*
X71269D01*
X72103Y831198D01*
X73861D01*
X74678Y830381D01*
X77891D01*
G01Y823688D02*
X75960D01*
X74932Y822660D01*
X72162D01*
X69658Y820987D01*
X68065D01*
X67037Y822015D01*
X66477D01*
G01X57323Y822046D02*
X56595D01*
X55546Y820997D01*
X54602D01*
X52939Y822660D01*
X51076D01*
X50048Y823688D01*
X48191D01*
G01Y850459D02*
X52707D01*
X54420Y848746D01*
X57323D01*
G01X66477Y848786D02*
X68969D01*
X69535Y849352D01*
Y850634D01*
X70194Y851293D01*
X71881D01*
X72715Y850459D01*
X77891D01*
G01X48191Y843766D02*
X54873D01*
X55369Y844262D01*
Y844934D01*
X55930Y845495D01*
X57323D01*
G01X66477Y845439D02*
X68620D01*
X69207Y844852D01*
Y844255D01*
X69713Y843749D01*
X71269D01*
X72103Y844583D01*
X73861D01*
X74678Y843766D01*
X77891D01*
G01X48191Y867192D02*
X54873D01*
X55369Y867688D01*
Y868360D01*
X55930Y868921D01*
X57323D01*
G01X66477Y868865D02*
X68620D01*
X69207Y868278D01*
Y867681D01*
X69713Y867175D01*
X71269D01*
X72103Y868009D01*
X73861D01*
X74678Y867192D01*
X77891D01*
G01Y860499D02*
X75960D01*
X74932Y859471D01*
X72162D01*
X69658Y857798D01*
X68065D01*
X67037Y858826D01*
X66477D01*
G01X57323Y858857D02*
X56595D01*
X55546Y857808D01*
X54602D01*
X52939Y859471D01*
X51076D01*
X50048Y860499D01*
X48191D01*
G01X77891Y857152D02*
X75963D01*
X74934Y858181D01*
X72554D01*
X70050Y856508D01*
X68062D01*
X67034Y855480D01*
X66477D01*
G01X57323Y855457D02*
X56546D01*
X55485Y856518D01*
X54067D01*
X52404Y858181D01*
X51088D01*
X50059Y857152D01*
X48191D01*
G01Y873885D02*
X52707D01*
X54420Y872172D01*
X57323D01*
G01X66477Y872212D02*
X68969D01*
X69535Y872778D01*
Y874060D01*
X70194Y874719D01*
X71881D01*
X72715Y873885D01*
X77891D01*
G01X48191Y880577D02*
X54873D01*
X55369Y881073D01*
Y881745D01*
X55930Y882306D01*
X57323D01*
G01X66477Y882250D02*
X68620D01*
X69207Y881663D01*
Y881066D01*
X69713Y880560D01*
X71269D01*
X72103Y881394D01*
X73861D01*
X74678Y880577D01*
X77891D01*
G01X48191Y887270D02*
X52707D01*
X54420Y885557D01*
X57323D01*
G01X66477Y885597D02*
X68969D01*
X69535Y886163D01*
Y887445D01*
X70194Y888104D01*
X71881D01*
X72715Y887270D01*
X77891D01*
G01Y897310D02*
X75960D01*
X74932Y896282D01*
X72162D01*
X69658Y894609D01*
X68065D01*
X67037Y895637D01*
X66477D01*
G01X57323Y895668D02*
X56595D01*
X55546Y894619D01*
X54602D01*
X52939Y896282D01*
X51076D01*
X50048Y897310D01*
X48191D01*
G01X77891Y893963D02*
X75963D01*
X74934Y894992D01*
X72554D01*
X70050Y893319D01*
X68062D01*
X67034Y892291D01*
X66477D01*
G01X57323Y892268D02*
X56546D01*
X55485Y893329D01*
X54067D01*
X52404Y894992D01*
X51088D01*
X50059Y893963D01*
X48191D01*
G01Y910696D02*
X52707D01*
X54420Y908983D01*
X57323D01*
G01X66477Y909023D02*
X68969D01*
X69535Y909589D01*
Y910871D01*
X70194Y911530D01*
X71881D01*
X72715Y910696D01*
X77891D01*
G01X48191Y904003D02*
X54873D01*
X55369Y904499D01*
Y905171D01*
X55930Y905732D01*
X57323D01*
G01X66477Y905676D02*
X68620D01*
X69207Y905089D01*
Y904492D01*
X69713Y903986D01*
X71269D01*
X72103Y904820D01*
X73861D01*
X74678Y904003D01*
X77891D01*
G01X48191Y924081D02*
X52707D01*
X54420Y922368D01*
X57323D01*
G01X66477Y922408D02*
X68969D01*
X69535Y922974D01*
Y924256D01*
X70194Y924915D01*
X71881D01*
X72715Y924081D01*
X77891D01*
G01X48191Y917389D02*
X54873D01*
X55369Y917885D01*
Y918557D01*
X55930Y919118D01*
X57323D01*
G01X66477Y919062D02*
X68620D01*
X69207Y918475D01*
Y917878D01*
X69713Y917372D01*
X71269D01*
X72103Y918206D01*
X73861D01*
X74678Y917389D01*
X77891D01*
G01Y934121D02*
X75960D01*
X74932Y933093D01*
X72162D01*
X69658Y931420D01*
X68065D01*
X67037Y932448D01*
X66477D01*
G01X57323Y932479D02*
X56595D01*
X55546Y931430D01*
X54602D01*
X52939Y933093D01*
X51076D01*
X50048Y934121D01*
X48191D01*
G01X77891Y930774D02*
X75963D01*
X74934Y931803D01*
X72554D01*
X70050Y930130D01*
X68062D01*
X67034Y929102D01*
X66477D01*
G01X57323Y929079D02*
X56546D01*
X55485Y930140D01*
X54067D01*
X52404Y931803D01*
X51088D01*
X50059Y930774D01*
X48191D01*
G01Y947507D02*
X52707D01*
X54420Y945794D01*
X57323D01*
G01X66477Y945834D02*
X68969D01*
X69535Y946400D01*
Y947682D01*
X70194Y948341D01*
X71881D01*
X72715Y947507D01*
X77891D01*
G01X48191Y940814D02*
X54873D01*
X55369Y941310D01*
Y941982D01*
X55930Y942543D01*
X57323D01*
G01X66477Y942487D02*
X68620D01*
X69207Y941900D01*
Y941303D01*
X69713Y940797D01*
X71269D01*
X72103Y941631D01*
X73861D01*
X74678Y940814D01*
X77891D01*
G01X48191Y964239D02*
X52541D01*
G01X48191Y977625D02*
X54873D01*
X55369Y978121D01*
Y978793D01*
X55930Y979354D01*
X57323D01*
G01X66477Y979298D02*
X68620D01*
X69207Y978711D01*
Y978114D01*
X69713Y977608D01*
X71269D01*
X72103Y978442D01*
X73861D01*
X74678Y977625D01*
X77891D01*
G01X48191Y970932D02*
X54873D01*
X55369Y971428D01*
Y972100D01*
X55930Y972661D01*
X57323D01*
G01X66477Y972605D02*
X68620D01*
X69207Y972018D01*
Y971421D01*
X69713Y970915D01*
X71269D01*
X72103Y971749D01*
X73861D01*
X74678Y970932D01*
X77891D01*
G01X48191Y991011D02*
X54873D01*
X55369Y991507D01*
Y992179D01*
X55930Y992740D01*
X57323D01*
G01X66477Y992684D02*
X68620D01*
X69207Y992097D01*
Y991500D01*
X69713Y990994D01*
X71269D01*
X72103Y991828D01*
X73861D01*
X74678Y991011D01*
X77891D01*
G01X48191Y984318D02*
X54873D01*
X55369Y984814D01*
Y985486D01*
X55930Y986047D01*
X57323D01*
G01X66477Y985991D02*
X68620D01*
X69207Y985404D01*
Y984807D01*
X69713Y984301D01*
X71269D01*
X72103Y985135D01*
X73861D01*
X74678Y984318D01*
X77891D01*
G01X48191Y1021129D02*
X52541D01*
G01X48191Y1024475D02*
X52541D01*
G01X48191Y1031168D02*
X54873D01*
X55369Y1031664D01*
Y1032336D01*
X55930Y1032897D01*
X57323D01*
G01X66477Y1032841D02*
X68620D01*
X69207Y1032254D01*
Y1031657D01*
X69713Y1031151D01*
X71269D01*
X72103Y1031985D01*
X73861D01*
X74678Y1031168D01*
X77891D01*
G01X48191Y1044554D02*
X54873D01*
X55369Y1045050D01*
Y1045722D01*
X55930Y1046283D01*
X57323D01*
G01X66477Y1046227D02*
X68620D01*
X69207Y1045640D01*
Y1045043D01*
X69713Y1044537D01*
X71269D01*
X72103Y1045371D01*
X73861D01*
X74678Y1044554D01*
X77891D01*
G01X48191Y1037861D02*
X54873D01*
X55369Y1038357D01*
Y1039029D01*
X55930Y1039590D01*
X57323D01*
G01X66477Y1039534D02*
X68620D01*
X69207Y1038947D01*
Y1038350D01*
X69713Y1037844D01*
X71269D01*
X72103Y1038678D01*
X73861D01*
X74678Y1037861D01*
X77891D01*
G01X48191Y1051247D02*
X52541D01*
G01X48191Y1071326D02*
X52707D01*
X54420Y1069613D01*
X57323D01*
G01X66477Y1069653D02*
X68969D01*
X69535Y1070219D01*
Y1071501D01*
X70194Y1072160D01*
X71881D01*
X72715Y1071326D01*
X77891D01*
G01X48191Y1064633D02*
X54873D01*
X55369Y1065129D01*
Y1065801D01*
X55930Y1066362D01*
X57323D01*
G01X66477Y1066306D02*
X68620D01*
X69207Y1065719D01*
Y1065122D01*
X69713Y1064616D01*
X71269D01*
X72103Y1065450D01*
X73861D01*
X74678Y1064633D01*
X77891D01*
G01Y1081365D02*
X75960D01*
X74932Y1080337D01*
X72162D01*
X69658Y1078664D01*
X68065D01*
X67037Y1079692D01*
X66478D01*
G01X57324Y1079730D02*
X56602D01*
X55546Y1078674D01*
X54602D01*
X52939Y1080337D01*
X51076D01*
X50048Y1081365D01*
X48191D01*
G01X77891Y1078018D02*
X75963D01*
X74934Y1079047D01*
X72554D01*
X70050Y1077374D01*
X68062D01*
X67034Y1076346D01*
X66477D01*
G01X57323Y1076323D02*
X56546D01*
X55485Y1077384D01*
X54067D01*
X52404Y1079047D01*
X51088D01*
X50059Y1078018D01*
X48191D01*
G01Y1094751D02*
X52707D01*
X54420Y1093038D01*
X57323D01*
G01X66477Y1093078D02*
X68969D01*
X69535Y1093644D01*
Y1094926D01*
X70194Y1095585D01*
X71881D01*
X72715Y1094751D01*
X77891D01*
G01X48191Y1088058D02*
X54873D01*
X55369Y1088554D01*
Y1089226D01*
X55930Y1089787D01*
X57323D01*
G01X66477Y1089731D02*
X68620D01*
X69207Y1089144D01*
Y1088547D01*
X69713Y1088041D01*
X71269D01*
X72103Y1088875D01*
X73861D01*
X74678Y1088058D01*
X77891D01*
G01X48191Y1108137D02*
X52707D01*
X54420Y1106424D01*
X57323D01*
G01X66477Y1106464D02*
X68969D01*
X69535Y1107030D01*
Y1108312D01*
X70194Y1108971D01*
X71881D01*
X72715Y1108137D01*
X77891D01*
G01X48191Y1101444D02*
X54873D01*
X55369Y1101940D01*
Y1102612D01*
X55930Y1103173D01*
X57323D01*
G01X66477Y1103117D02*
X68620D01*
X69207Y1102530D01*
Y1101933D01*
X69713Y1101427D01*
X71269D01*
X72103Y1102261D01*
X73861D01*
X74678Y1101444D01*
X77891D01*
G01X48191Y1124869D02*
X54873D01*
X55369Y1125365D01*
Y1126037D01*
X55930Y1126598D01*
X57323D01*
G01X66477Y1126542D02*
X68620D01*
X69207Y1125955D01*
Y1125358D01*
X69713Y1124852D01*
X71269D01*
X72103Y1125686D01*
X73861D01*
X74678Y1124869D01*
X77891D01*
G01Y1118176D02*
X75960D01*
X74932Y1117148D01*
X72162D01*
X69658Y1115475D01*
X68065D01*
X67037Y1116503D01*
X66477D01*
G01X57323Y1116541D02*
X56602D01*
X55546Y1115485D01*
X54602D01*
X52939Y1117148D01*
X51076D01*
X50048Y1118176D01*
X48191D01*
G01X77891Y1114829D02*
X75963D01*
X74934Y1115858D01*
X72554D01*
X70050Y1114185D01*
X68062D01*
X67034Y1113157D01*
X66477D01*
G01X57323Y1113134D02*
X56546D01*
X55485Y1114195D01*
X54067D01*
X52404Y1115858D01*
X51088D01*
X50059Y1114829D01*
X48191D01*
G01Y1144948D02*
X52707D01*
X54420Y1143235D01*
X57323D01*
G01X66477Y1143275D02*
X68969D01*
X69535Y1143841D01*
Y1145123D01*
X70194Y1145782D01*
X71881D01*
X72715Y1144948D01*
X77891D01*
G01X48191Y1138255D02*
X54873D01*
X55369Y1138751D01*
Y1139423D01*
X55930Y1139984D01*
X57323D01*
G01X66477Y1139928D02*
X68620D01*
X69207Y1139341D01*
Y1138744D01*
X69713Y1138238D01*
X71269D01*
X72103Y1139072D01*
X73861D01*
X74678Y1138255D01*
X77891D01*
G01X48191Y1131562D02*
X52707D01*
X54420Y1129849D01*
X57323D01*
G01X66477Y1129889D02*
X68969D01*
X69535Y1130455D01*
Y1131737D01*
X70194Y1132396D01*
X71881D01*
X72715Y1131562D01*
X77891D01*
G01Y1154987D02*
X75960D01*
X74932Y1153959D01*
X72162D01*
X69658Y1152286D01*
X68065D01*
X67037Y1153314D01*
X66477D01*
G01X57323Y1153352D02*
X56602D01*
X55546Y1152296D01*
X54602D01*
X52939Y1153959D01*
X51076D01*
X50048Y1154987D01*
X48191D01*
G01X77891Y1151641D02*
X75962D01*
X74934Y1152669D01*
X72554D01*
X70050Y1150996D01*
X68062D01*
X67034Y1149968D01*
X66477D01*
G01X57323Y1149945D02*
X56546D01*
X55485Y1151006D01*
X54067D01*
X52404Y1152669D01*
X51088D01*
X50060Y1151641D01*
X48191D01*
G01Y1175066D02*
X54873D01*
X55369Y1175562D01*
Y1176234D01*
X55930Y1176795D01*
X57323D01*
G01X66477Y1176739D02*
X68620D01*
X69207Y1176152D01*
Y1175555D01*
X69713Y1175049D01*
X71269D01*
X72103Y1175883D01*
X73861D01*
X74678Y1175066D01*
X77891D01*
G01X48191Y1168373D02*
X52707D01*
X54420Y1166660D01*
X57323D01*
G01X66477Y1166700D02*
X68969D01*
X69535Y1167266D01*
Y1168548D01*
X70194Y1169207D01*
X71881D01*
X72715Y1168373D01*
X77891D01*
G01X48191Y1161680D02*
X54873D01*
X55369Y1162176D01*
Y1162848D01*
X55930Y1163409D01*
X57323D01*
G01X66477Y1163353D02*
X68620D01*
X69207Y1162766D01*
Y1162169D01*
X69713Y1161663D01*
X71269D01*
X72103Y1162497D01*
X73861D01*
X74678Y1161680D01*
X77891D01*
G01X48191Y1181759D02*
X52707D01*
X54420Y1180046D01*
X57323D01*
G01X66477Y1180086D02*
X68969D01*
X69535Y1180652D01*
Y1181934D01*
X70194Y1182593D01*
X71881D01*
X72715Y1181759D01*
X77891D01*
G01Y1191798D02*
X75960D01*
X74932Y1190770D01*
X72162D01*
X69658Y1189097D01*
X68065D01*
X67037Y1190125D01*
X66477D01*
G01X57323Y1190163D02*
X56602D01*
X55546Y1189107D01*
X54602D01*
X52939Y1190770D01*
X51076D01*
X50048Y1191798D01*
X48191D01*
G01X77891Y1188452D02*
X75962D01*
X74934Y1189480D01*
X72554D01*
X70050Y1187807D01*
X68062D01*
X67034Y1186779D01*
X66477D01*
G01X57323Y1186756D02*
X56546D01*
X55485Y1187817D01*
X54067D01*
X52404Y1189480D01*
X51088D01*
X50060Y1188452D01*
X48191D01*
G01Y1205184D02*
X52707D01*
X54420Y1203471D01*
X57323D01*
G01X66477Y1203511D02*
X68969D01*
X69535Y1204077D01*
Y1205359D01*
X70194Y1206018D01*
X71881D01*
X72715Y1205184D01*
X77891D01*
G01X48191Y1198491D02*
X54873D01*
X55369Y1198987D01*
Y1199659D01*
X55930Y1200220D01*
X57323D01*
G01X66477Y1200164D02*
X68620D01*
X69207Y1199577D01*
Y1198980D01*
X69713Y1198474D01*
X71269D01*
X72103Y1199308D01*
X73861D01*
X74678Y1198491D01*
X77891D01*
G01X48191Y1218570D02*
X52707D01*
X54420Y1216857D01*
X57323D01*
G01X66477Y1216897D02*
X68969D01*
X69535Y1217463D01*
Y1218745D01*
X70194Y1219404D01*
X71881D01*
X72715Y1218570D01*
X77891D01*
G01X48191Y1211877D02*
X54873D01*
X55369Y1212373D01*
Y1213045D01*
X55930Y1213606D01*
X57323D01*
G01X66477Y1213550D02*
X68620D01*
X69207Y1212963D01*
Y1212366D01*
X69713Y1211860D01*
X71269D01*
X72103Y1212694D01*
X73861D01*
X74678Y1211877D01*
X77891D01*
G01Y1228609D02*
X75960D01*
X74932Y1227581D01*
X72162D01*
X69658Y1225908D01*
X68065D01*
X67037Y1226936D01*
X66477D01*
G01X57323Y1226974D02*
X56602D01*
X55546Y1225918D01*
X54602D01*
X52939Y1227581D01*
X51076D01*
X50048Y1228609D01*
X48191D01*
G01X77891Y1225263D02*
X75962D01*
X74934Y1226291D01*
X72554D01*
X70050Y1224618D01*
X68062D01*
X67034Y1223590D01*
X66477D01*
G01X57323Y1223567D02*
X56546D01*
X55485Y1224628D01*
X54067D01*
X52404Y1226291D01*
X51088D01*
X50060Y1225263D01*
X48191D01*
G01Y1241995D02*
X52707D01*
X54420Y1240282D01*
X57323D01*
G01X66477Y1240322D02*
X68969D01*
X69535Y1240888D01*
Y1242170D01*
X70194Y1242829D01*
X71881D01*
X72715Y1241995D01*
X77891D01*
G01X48191Y1235302D02*
X54873D01*
X55369Y1235798D01*
Y1236470D01*
X55930Y1237031D01*
X57323D01*
G01X66477Y1236975D02*
X68620D01*
X69207Y1236388D01*
Y1235791D01*
X69713Y1235285D01*
X71269D01*
X72103Y1236119D01*
X73861D01*
X74678Y1235302D01*
X77891D01*
G01X82241Y770144D02*
X77891D01*
G01X66099Y780184D02*
X61749D01*
G01X66099Y773491D02*
X61749D01*
G01X82241Y776837D02*
X77891D01*
G01X66099Y786877D02*
X61749D01*
G01X82241D02*
X77891D01*
G01X82241Y783530D02*
X77891D01*
G01X66099Y796916D02*
X61749D01*
G01X82241Y800263D02*
X77891D01*
G01X82241Y793570D02*
X77891D01*
G01X66099Y790223D02*
X61749D01*
G01X66099Y816995D02*
X61749D01*
G01X66099Y810302D02*
X61749D01*
G01X82241Y813648D02*
X77891D01*
G01X82241Y806955D02*
X77891D01*
G01X66099Y803609D02*
X61749D01*
G01X66099Y833727D02*
X61749D01*
G01X82241Y830381D02*
X77891D01*
G01X66099Y823688D02*
X61749D01*
G01X82241D02*
X77891D01*
G01X66099Y827034D02*
X61749D01*
G01X82241Y820341D02*
X77891D01*
G01X66099Y847113D02*
X61749D01*
G01X82241Y850459D02*
X77891D01*
G01X82241Y843766D02*
X77891D01*
G01X66099Y840420D02*
X61749D01*
G01X82241Y837074D02*
X77891D01*
G01X82241Y867192D02*
X77891D01*
G01X66099Y853806D02*
X61749D01*
G01X66099Y860499D02*
X61749D01*
G01X82241D02*
X77891D01*
G01X66099Y863845D02*
X61749D01*
G01X82241Y857152D02*
X77891D01*
G01X82241Y873885D02*
X77891D01*
G01X66099Y883924D02*
X61749D01*
G01X82241Y880577D02*
X77891D01*
G01X66099Y877231D02*
X61749D01*
G01X66099Y870538D02*
X61749D01*
G01X66099Y890617D02*
X61749D01*
G01X82241Y887270D02*
X77891D01*
G01X66099Y897310D02*
X61749D01*
G01X82241D02*
X77891D01*
G01X66099Y900656D02*
X61749D01*
G01X82241Y893963D02*
X77891D01*
G01X66099Y914042D02*
X61749D01*
G01X66099Y907349D02*
X61749D01*
G01X82241Y910696D02*
X77891D01*
G01X82241Y904003D02*
X77891D01*
G01X66099Y927428D02*
X61749D01*
G01X66099Y920735D02*
X61749D01*
G01X82241Y924081D02*
X77891D01*
G01X82241Y917389D02*
X77891D01*
G01X82241Y930774D02*
X77891D01*
G01X66099Y944160D02*
X61749D01*
G01X82241Y947507D02*
X77891D01*
G01X82241Y940814D02*
X77891D01*
G01X82241Y934121D02*
X77891D01*
G01X66099D02*
X61749D01*
G01X66099Y937467D02*
X61749D01*
G01Y960892D02*
X66099D01*
G01Y950853D02*
X61749D01*
G01X77891Y964239D02*
X82241D01*
G01X61749Y957546D02*
X66099D01*
G01Y980971D02*
X61749D01*
G01X82241Y977625D02*
X77891D01*
G01X66099Y974278D02*
X61749D01*
G01Y967585D02*
X66099D01*
G01X82241Y970932D02*
X77891D01*
G01X61749Y994357D02*
X66099D01*
G01X82241Y991011D02*
X77891D01*
G01X66099Y987664D02*
X61749D01*
G01X82241Y984318D02*
X77891D01*
G01Y1021129D02*
X82241D01*
G01X77891Y1024475D02*
X82241D01*
G01X66099Y1027822D02*
X61749D01*
G01X66099Y1021129D02*
X61749D01*
G01X82241Y1044554D02*
X77891D01*
G01X66099Y1041207D02*
X61749D01*
G01X82241Y1037861D02*
X77891D01*
G01X66099Y1034515D02*
X61749D01*
G01X82241Y1031168D02*
X77891D01*
G01X66099Y1061286D02*
X61749D01*
G01X66099Y1047900D02*
X61749D01*
G01Y1054593D02*
X66099D01*
G01X77891Y1051247D02*
X82241D01*
G01X66099Y1074672D02*
X61749D01*
G01X66099Y1067979D02*
X61749D01*
G01X82241Y1071326D02*
X77891D01*
G01X82241Y1064633D02*
X77891D01*
G01X82241Y1078018D02*
X77891D01*
G01X66099Y1091404D02*
X61749D01*
G01X82241Y1094751D02*
X77891D01*
G01X82241Y1088058D02*
X77891D01*
G01X66099Y1081365D02*
X61749D01*
G01X82241D02*
X77891D01*
G01X66099Y1084711D02*
X61749D01*
G01X66099Y1098097D02*
X61749D01*
G01X66099Y1111483D02*
X61749D01*
G01X66099Y1104790D02*
X61749D01*
G01X82241Y1108137D02*
X77891D01*
G01X82241Y1101444D02*
X77891D01*
G01X61749Y1128215D02*
X66099D01*
G01X82241Y1124869D02*
X77891D01*
G01X61749Y1118176D02*
X66099D01*
G01X82241D02*
X77891D01*
G01X61749Y1121522D02*
X66099D01*
G01X82241Y1114829D02*
X77891D01*
G01X61749Y1141601D02*
X66099D01*
G01X82241Y1138255D02*
X77891D01*
G01X61749Y1134908D02*
X66099D01*
G01X77891Y1131562D02*
X82241D01*
G01X61749Y1148294D02*
X66099D01*
G01X82241Y1144948D02*
X77891D01*
G01X61749Y1154987D02*
X66099D01*
G01X82241D02*
X77891D01*
G01X61749Y1158333D02*
X66099D01*
G01X82241Y1151641D02*
X77891D01*
G01X82241Y1175066D02*
X77891D01*
G01X61749Y1171719D02*
X66099D01*
G01X61749Y1165026D02*
X66099D01*
G01X82241Y1168373D02*
X77891D01*
G01X82241Y1161680D02*
X77891D01*
G01X61749Y1185105D02*
X66099D01*
G01X61749Y1178412D02*
X66099D01*
G01X82241Y1181759D02*
X77891D01*
G01X61749Y1191798D02*
X66099D01*
G01X82241D02*
X77891D01*
G01X82241Y1188452D02*
X77891D01*
G01X82241Y1205184D02*
X77891D01*
G01X82241Y1198491D02*
X77891D01*
G01X61749Y1208530D02*
X66099D01*
G01X61749Y1201837D02*
X66099D01*
G01X61749Y1195144D02*
X66099D01*
G01X61749Y1221916D02*
X66099D01*
G01X61749Y1215223D02*
X66099D01*
G01X82241Y1218570D02*
X77891D01*
G01X82241Y1211877D02*
X77891D01*
G01X82241Y1225263D02*
X77891D01*
G01X61749Y1238648D02*
X66099D01*
G01X82241Y1241995D02*
X77891D01*
G01X82241Y1235302D02*
X77891D01*
G01X61749Y1228609D02*
X66099D01*
G01X82241D02*
X77891D01*
G01X61749Y1231955D02*
X66099D01*
G01X61749Y1245341D02*
X66099D01*
G01X91449Y780184D02*
X96702D01*
X97642Y781124D01*
X99448D01*
X100128Y780444D01*
Y779304D01*
X100953Y778479D01*
X103165D01*
G01X112319Y778511D02*
X114086D01*
X115759Y780184D01*
X121149D01*
G01X91449Y773491D02*
X96702D01*
X97534Y774323D01*
X99520D01*
X100128Y773715D01*
Y772423D01*
X100768Y771783D01*
X103165D01*
G01X112319Y771818D02*
X113022D01*
X114695Y773491D01*
X121149D01*
G01X91449Y786877D02*
X93609D01*
X94637Y787905D01*
X96660D01*
X99164Y789579D01*
X101290D01*
X102361Y788508D01*
X103165D01*
G01X112319Y788550D02*
X112930D01*
X113959Y789579D01*
X114694D01*
X116368Y787905D01*
X117969D01*
X118997Y786877D01*
X121149D01*
G01X91449Y796916D02*
X96702D01*
X97534Y797748D01*
X99520D01*
X100128Y797140D01*
Y795848D01*
X100768Y795208D01*
X103165D01*
G01X112319Y795243D02*
X113022D01*
X114695Y796916D01*
X121149D01*
G01X91449Y790223D02*
X93567D01*
X94595Y789195D01*
X96268D01*
X98772Y790869D01*
X101241D01*
X102306Y791934D01*
X103165D01*
G01X112319Y791897D02*
X112918D01*
X113946Y790869D01*
X115229D01*
X116903Y789195D01*
X117961D01*
X118989Y790223D01*
X121149D01*
G01X91449Y816995D02*
X96702D01*
X97642Y817935D01*
X99448D01*
X100128Y817255D01*
Y816115D01*
X100953Y815290D01*
X103165D01*
G01X112319Y815322D02*
X114086D01*
X115759Y816995D01*
X121149D01*
G01X91449Y810302D02*
X96702D01*
X97534Y811134D01*
X99520D01*
X100128Y810526D01*
Y809234D01*
X100768Y808594D01*
X103165D01*
G01X112319Y808629D02*
X113022D01*
X114695Y810302D01*
X121149D01*
G01X91449Y803609D02*
X96702D01*
X97642Y804549D01*
X99448D01*
X100128Y803869D01*
Y802729D01*
X100953Y801904D01*
X103165D01*
G01X112319Y801936D02*
X114086D01*
X115759Y803609D01*
X121149D01*
G01X91449Y833727D02*
X96702D01*
X97534Y834559D01*
X99520D01*
X100128Y833951D01*
Y832659D01*
X100768Y832019D01*
X103165D01*
G01X112319Y832054D02*
X113022D01*
X114695Y833727D01*
X121149D01*
G01X91449Y823688D02*
X93609D01*
X94637Y824716D01*
X96660D01*
X99164Y826390D01*
X101290D01*
X102361Y825319D01*
X103165D01*
G01X112319Y825361D02*
X112930D01*
X113959Y826390D01*
X114694D01*
X116368Y824716D01*
X117969D01*
X118997Y823688D01*
X121149D01*
G01X91449Y827034D02*
X93567D01*
X94595Y826006D01*
X96268D01*
X98772Y827680D01*
X101241D01*
X102306Y828745D01*
X103165D01*
G01X112319Y828708D02*
X112918D01*
X113946Y827680D01*
X115229D01*
X116903Y826006D01*
X117961D01*
X118989Y827034D01*
X121149D01*
G01X91449Y847113D02*
X96702D01*
X97534Y847945D01*
X99520D01*
X100128Y847337D01*
Y846045D01*
X100768Y845405D01*
X103165D01*
G01X112319Y845440D02*
X113022D01*
X114695Y847113D01*
X121149D01*
G01X91449Y840420D02*
X96702D01*
X97642Y841360D01*
X99448D01*
X100128Y840680D01*
Y839540D01*
X100953Y838715D01*
X103165D01*
G01X112319Y838747D02*
X114086D01*
X115759Y840420D01*
X121149D01*
G01X91449Y853806D02*
X96702D01*
X97642Y854746D01*
X99448D01*
X100128Y854066D01*
Y852926D01*
X100953Y852101D01*
X103165D01*
G01X112319Y852133D02*
X114086D01*
X115759Y853806D01*
X121149D01*
G01X91449Y860499D02*
X93609D01*
X94637Y861527D01*
X96660D01*
X99164Y863201D01*
X101290D01*
X102361Y862130D01*
X103165D01*
G01X112319Y862172D02*
X112930D01*
X113959Y863201D01*
X114694D01*
X116368Y861527D01*
X117969D01*
X118997Y860499D01*
X121149D01*
G01X91449Y863845D02*
X93567D01*
X94595Y862817D01*
X96268D01*
X98772Y864491D01*
X101241D01*
X102306Y865556D01*
X103165D01*
G01X112319Y865519D02*
X112918D01*
X113946Y864491D01*
X115229D01*
X116903Y862817D01*
X117961D01*
X118989Y863845D01*
X121149D01*
G01X91449Y883924D02*
X96702D01*
X97534Y884756D01*
X99520D01*
X100128Y884148D01*
Y882856D01*
X100768Y882216D01*
X103165D01*
G01X112319Y882251D02*
X113022D01*
X114695Y883924D01*
X121149D01*
G01X91449Y877231D02*
X96702D01*
X97642Y878171D01*
X99448D01*
X100128Y877491D01*
Y876351D01*
X100953Y875526D01*
X103165D01*
G01X112319Y875558D02*
X114086D01*
X115759Y877231D01*
X121149D01*
G01X91449Y870538D02*
X96702D01*
X97534Y871370D01*
X99520D01*
X100128Y870762D01*
Y869470D01*
X100768Y868830D01*
X103165D01*
G01X112319Y868865D02*
X113022D01*
X114695Y870538D01*
X121149D01*
G01X91449Y890617D02*
X96702D01*
X97642Y891557D01*
X99448D01*
X100128Y890877D01*
Y889737D01*
X100953Y888912D01*
X103165D01*
G01X112319Y888944D02*
X114086D01*
X115759Y890617D01*
X121149D01*
G01X91449Y897310D02*
X93609D01*
X94637Y898338D01*
X96664D01*
X99164Y900012D01*
X101290D01*
X102361Y898941D01*
X103165D01*
G01X112319Y898983D02*
X112930D01*
X113959Y900012D01*
X114694D01*
X116368Y898338D01*
X117969D01*
X118997Y897310D01*
X121149D01*
G01X91449Y900656D02*
X93567D01*
X94595Y899628D01*
X96271D01*
X98771Y901302D01*
X101241D01*
X102306Y902367D01*
X103165D01*
X103166Y902366D01*
G01X112320Y902330D02*
X112918D01*
X113946Y901302D01*
X115229D01*
X116903Y899628D01*
X117961D01*
X118989Y900656D01*
X121149D01*
G01X91449Y914042D02*
X96702D01*
X97642Y914982D01*
X99448D01*
X100128Y914302D01*
Y913162D01*
X100953Y912337D01*
X103165D01*
G01X112319Y912369D02*
X114086D01*
X115759Y914042D01*
X121149D01*
G01X91449Y907349D02*
X96702D01*
X97534Y908181D01*
X99520D01*
X100128Y907573D01*
Y906281D01*
X100768Y905641D01*
X103165D01*
G01X112319Y905676D02*
X113022D01*
X114695Y907349D01*
X121149D01*
G01X91449Y927428D02*
X96702D01*
X97642Y928368D01*
X99448D01*
X100128Y927688D01*
Y926548D01*
X100921Y925755D01*
X102637D01*
G01X112593D02*
X114086D01*
X115759Y927428D01*
X121149D01*
G01X91449Y920735D02*
X96702D01*
X97534Y921567D01*
X99520D01*
X100128Y920959D01*
Y919702D01*
X100768Y919062D01*
X102621D01*
G01X112561D02*
X113022D01*
X114695Y920735D01*
X121149D01*
G01X91449Y944160D02*
X96702D01*
X97534Y944992D01*
X99520D01*
X100128Y944384D01*
Y943127D01*
X100768Y942487D01*
X102653D01*
G01X112561D02*
X113022D01*
X114695Y944160D01*
X121149D01*
G01X91449Y934121D02*
X93609D01*
X94637Y935149D01*
X96660D01*
X99164Y936823D01*
X101332D01*
X102361Y935794D01*
X102621D01*
G01X112561D02*
X112930D01*
X113959Y936823D01*
X114694D01*
X116368Y935149D01*
X117969D01*
X118997Y934121D01*
X121149D01*
G01X91449Y937467D02*
X93567D01*
X94595Y936439D01*
X96268D01*
X98772Y938113D01*
X101241D01*
X102269Y939141D01*
X102621D01*
G01X112561D02*
X112918D01*
X113946Y938113D01*
X115229D01*
X116903Y936439D01*
X117961D01*
X118989Y937467D01*
X121149D01*
G01X91449Y960892D02*
X95799D01*
G01X91449Y950853D02*
X96702D01*
X97642Y951793D01*
X99448D01*
X100128Y951113D01*
Y949973D01*
X100921Y949180D01*
X102637D01*
G01X112593D02*
X114086D01*
X115759Y950853D01*
X121149D01*
G01X91449Y957546D02*
X95799D01*
G01X91449Y980971D02*
X96702D01*
X97534Y981803D01*
X99520D01*
X100128Y981195D01*
Y979903D01*
X100768Y979263D01*
X103165D01*
G01X112319Y979298D02*
X113022D01*
X114695Y980971D01*
X121149D01*
G01X91449Y974278D02*
X96702D01*
X97534Y975110D01*
X99520D01*
X100128Y974502D01*
Y973210D01*
X100768Y972570D01*
X103165D01*
G01X112319Y972605D02*
X113022D01*
X114695Y974278D01*
X121149D01*
G01X91449Y967585D02*
X95799D01*
G01X91449Y994357D02*
X96702D01*
X97534Y995189D01*
X99520D01*
X100128Y994581D01*
Y993289D01*
X100768Y992649D01*
X103165D01*
G01X112319Y992684D02*
X113022D01*
X114695Y994357D01*
X121149D01*
G01X91449Y987664D02*
X96702D01*
X97534Y988496D01*
X99520D01*
X100128Y987888D01*
Y986596D01*
X100768Y985956D01*
X103165D01*
G01X112319Y985991D02*
X113022D01*
X114695Y987664D01*
X121149D01*
G01X91449Y1027822D02*
X96702D01*
X97534Y1028654D01*
X99520D01*
X100128Y1028046D01*
Y1026754D01*
X100768Y1026114D01*
X103165D01*
G01X112319Y1026149D02*
X113022D01*
X114695Y1027822D01*
X121149D01*
G01X91449Y1021129D02*
X96702D01*
X97643Y1022070D01*
X99257D01*
X100128Y1021199D01*
Y1020061D01*
X100680Y1019509D01*
X100681Y1019510D01*
X103165D01*
G01X112319Y1019456D02*
X112758D01*
X114431Y1021129D01*
X121149D01*
G01X91449Y1041207D02*
X96702D01*
X97534Y1042039D01*
X99520D01*
X100128Y1041431D01*
Y1040139D01*
X100768Y1039499D01*
X103165D01*
G01X112319Y1039534D02*
X113022D01*
X114695Y1041207D01*
X121149D01*
G01X91449Y1034515D02*
X96702D01*
X97534Y1035347D01*
X99520D01*
X100128Y1034739D01*
Y1033447D01*
X100768Y1032807D01*
X103165D01*
G01X112319Y1032842D02*
X113022D01*
X114695Y1034515D01*
X121149D01*
G01X91449Y1061286D02*
X96702D01*
X97534Y1062118D01*
X99520D01*
X100128Y1061510D01*
Y1060218D01*
X100768Y1059578D01*
X103165D01*
G01X112319Y1059613D02*
X113022D01*
X114695Y1061286D01*
X121149D01*
G01X91449Y1047900D02*
X96702D01*
X97534Y1048732D01*
X99520D01*
X100128Y1048124D01*
Y1046832D01*
X100768Y1046192D01*
X103165D01*
G01X112319Y1046227D02*
X113022D01*
X114695Y1047900D01*
X121149D01*
G01X91449Y1054593D02*
X95799D01*
G01X91449Y1074672D02*
X96702D01*
X97642Y1075612D01*
X99448D01*
X100128Y1074932D01*
Y1073792D01*
X100921Y1072999D01*
X102702D01*
G01X112594D02*
X114086D01*
X115759Y1074672D01*
X121149D01*
G01X91449Y1067979D02*
X96702D01*
X97534Y1068811D01*
X99520D01*
X100128Y1068203D01*
Y1066946D01*
X100768Y1066306D01*
X102687D01*
G01X112611D02*
X113022D01*
X114695Y1067979D01*
X121149D01*
G01X91449Y1091404D02*
X96702D01*
X97534Y1092236D01*
X99520D01*
X100128Y1091628D01*
Y1090371D01*
X100768Y1089731D01*
X102638D01*
G01X112578D02*
X113022D01*
X114695Y1091404D01*
X121149D01*
G01X91449Y1081365D02*
X93609D01*
X94637Y1082393D01*
X96660D01*
X99164Y1084067D01*
X101290D01*
X102319Y1083038D01*
X102654D01*
G01X112578D02*
X112930D01*
X113959Y1084067D01*
X114694D01*
X116368Y1082393D01*
X117969D01*
X118997Y1081365D01*
X121149D01*
G01X91449Y1084711D02*
X93567D01*
X94595Y1083683D01*
X96268D01*
X98772Y1085357D01*
X101241D01*
X102269Y1086385D01*
X102654D01*
G01X112578D02*
X112918D01*
X113946Y1085357D01*
X115229D01*
X116903Y1083683D01*
X117961D01*
X118989Y1084711D01*
X121149D01*
G01X91449Y1098097D02*
X96702D01*
X97642Y1099037D01*
X99448D01*
X100128Y1098357D01*
Y1097217D01*
X100921Y1096424D01*
X102637D01*
G01X112577D02*
X114086D01*
X115759Y1098097D01*
X121149D01*
G01X91449Y1111483D02*
X96702D01*
X97642Y1112423D01*
X99448D01*
X100128Y1111743D01*
Y1110603D01*
X100953Y1109778D01*
X103165D01*
G01X112319Y1109810D02*
X114086D01*
X115759Y1111483D01*
X121149D01*
G01X91449Y1104790D02*
X96702D01*
X97534Y1105622D01*
X99520D01*
X100128Y1105014D01*
Y1103722D01*
X100768Y1103082D01*
X103165D01*
G01X112319Y1103117D02*
X113022D01*
X114695Y1104790D01*
X121149D01*
G01X91449Y1128215D02*
X96702D01*
X97534Y1129047D01*
X99520D01*
X100128Y1128439D01*
Y1127147D01*
X100768Y1126507D01*
X103165D01*
G01X112319Y1126542D02*
X113022D01*
X114695Y1128215D01*
X121149D01*
G01X91449Y1118176D02*
X93609D01*
X94637Y1119204D01*
X96660D01*
X99164Y1120878D01*
X101290D01*
X102361Y1119807D01*
X103165D01*
G01X112319Y1119849D02*
X112930D01*
X113959Y1120878D01*
X114694D01*
X116368Y1119204D01*
X117969D01*
X118997Y1118176D01*
X121149D01*
G01X91449Y1121522D02*
X93567D01*
X94595Y1120494D01*
X96268D01*
X98772Y1122168D01*
X101241D01*
X102306Y1123233D01*
X103165D01*
G01X112319Y1123196D02*
X112918D01*
X113946Y1122168D01*
X115229D01*
X116903Y1120494D01*
X117961D01*
X118989Y1121522D01*
X121149D01*
G01X91449Y1141601D02*
X96702D01*
X97534Y1142433D01*
X99520D01*
X100128Y1141825D01*
Y1140533D01*
X100768Y1139893D01*
X103165D01*
G01X112319Y1139928D02*
X113022D01*
X114695Y1141601D01*
X121149D01*
G01X91449Y1134908D02*
X96702D01*
X97642Y1135848D01*
X99448D01*
X100128Y1135168D01*
Y1134028D01*
X100953Y1133203D01*
X103165D01*
G01X112319Y1133235D02*
X114086D01*
X115759Y1134908D01*
X121149D01*
G01X91449Y1148294D02*
X96702D01*
X97642Y1149234D01*
X99448D01*
X100128Y1148554D01*
Y1147414D01*
X100953Y1146589D01*
X103165D01*
G01X112319Y1146621D02*
X114086D01*
X115759Y1148294D01*
X121149D01*
G01X91449Y1154987D02*
X93609D01*
X94637Y1156015D01*
X96660D01*
X99164Y1157689D01*
X101290D01*
X102361Y1156618D01*
X103165D01*
G01X112319Y1156660D02*
X112930D01*
X113959Y1157689D01*
X114694D01*
X116368Y1156015D01*
X117969D01*
X118997Y1154987D01*
X121149D01*
G01X91449Y1158333D02*
X93567D01*
X94595Y1157305D01*
X96268D01*
X98772Y1158979D01*
X101241D01*
X102306Y1160044D01*
X103165D01*
G01X112319Y1160007D02*
X112918D01*
X113946Y1158979D01*
X115229D01*
X116903Y1157305D01*
X117961D01*
X118989Y1158333D01*
X121149D01*
G01X91449Y1171719D02*
X96702D01*
X97642Y1172659D01*
X99448D01*
X100128Y1171979D01*
Y1170839D01*
X100953Y1170014D01*
X103165D01*
G01X112319Y1170046D02*
X114086D01*
X115759Y1171719D01*
X121149D01*
G01X91449Y1165026D02*
X96702D01*
X97534Y1165858D01*
X99520D01*
X100128Y1165250D01*
Y1163958D01*
X100768Y1163318D01*
X103165D01*
G01X112319Y1163353D02*
X113022D01*
X114695Y1165026D01*
X121149D01*
G01X91449Y1185105D02*
X96702D01*
X97642Y1186045D01*
X99448D01*
X100128Y1185365D01*
Y1184225D01*
X100953Y1183400D01*
X103165D01*
G01X112319Y1183432D02*
X114086D01*
X115759Y1185105D01*
X121149D01*
G01X91449Y1178412D02*
X96702D01*
X97534Y1179244D01*
X99520D01*
X100128Y1178636D01*
Y1177344D01*
X100768Y1176704D01*
X103165D01*
G01X112319Y1176739D02*
X113022D01*
X114695Y1178412D01*
X121149D01*
G01X91449Y1191798D02*
X93609D01*
X94637Y1192826D01*
X96660D01*
X99164Y1194500D01*
X101290D01*
X102361Y1193429D01*
X103165D01*
G01X112319Y1193471D02*
X112930D01*
X113959Y1194500D01*
X114694D01*
X116368Y1192826D01*
X117969D01*
X118997Y1191798D01*
X121149D01*
G01X91449Y1208530D02*
X96702D01*
X97642Y1209470D01*
X99448D01*
X100128Y1208790D01*
Y1207650D01*
X100953Y1206825D01*
X103165D01*
G01X112319Y1206857D02*
X114086D01*
X115759Y1208530D01*
X121149D01*
G01X91449Y1201837D02*
X96702D01*
X97534Y1202669D01*
X99520D01*
X100128Y1202061D01*
Y1200769D01*
X100768Y1200129D01*
X103165D01*
G01X112319Y1200164D02*
X113022D01*
X114695Y1201837D01*
X121149D01*
G01X91449Y1195144D02*
X93567D01*
X94595Y1194116D01*
X96268D01*
X98772Y1195790D01*
X101241D01*
X102306Y1196855D01*
X103165D01*
G01X112319Y1196818D02*
X112918D01*
X113946Y1195790D01*
X115229D01*
X116903Y1194116D01*
X117961D01*
X118989Y1195144D01*
X121149D01*
G01X91449Y1221916D02*
X96702D01*
X97642Y1222856D01*
X99448D01*
X100128Y1222176D01*
Y1221036D01*
X100953Y1220211D01*
X103165D01*
G01X112319Y1220243D02*
X114086D01*
X115759Y1221916D01*
X121149D01*
G01X91449Y1215223D02*
X96702D01*
X97534Y1216055D01*
X99520D01*
X100128Y1215447D01*
Y1214155D01*
X100768Y1213515D01*
X103165D01*
G01X112319Y1213550D02*
X113022D01*
X114695Y1215223D01*
X121149D01*
G01X91449Y1238648D02*
X96702D01*
X97534Y1239480D01*
X99520D01*
X100128Y1238872D01*
Y1237580D01*
X100768Y1236940D01*
X103165D01*
G01X112319Y1236975D02*
X113022D01*
X114695Y1238648D01*
X121149D01*
G01X91449Y1228609D02*
X93609D01*
X94637Y1229637D01*
X96660D01*
X99164Y1231311D01*
X101290D01*
X102361Y1230240D01*
X103165D01*
G01X112319Y1230282D02*
X112930D01*
X113959Y1231311D01*
X114694D01*
X116368Y1229637D01*
X117969D01*
X118997Y1228609D01*
X121149D01*
G01X91449Y1231955D02*
X93567D01*
X94595Y1230927D01*
X96268D01*
X98772Y1232601D01*
X101241D01*
X102306Y1233666D01*
X103165D01*
G01X112319Y1233629D02*
X112918D01*
X113946Y1232601D01*
X115229D01*
X116903Y1230927D01*
X117961D01*
X118989Y1231955D01*
X121149D01*
G01X91449Y1245341D02*
X96702D01*
X97642Y1246281D01*
X99448D01*
X100128Y1245601D01*
Y1244461D01*
X100953Y1243636D01*
X103165D01*
G01X112319Y1243668D02*
X114086D01*
X115759Y1245341D01*
X121149D01*
G01X107591Y770144D02*
X114273D01*
X114769Y770640D01*
Y771312D01*
X115330Y771873D01*
X116723D01*
G01X125877Y771817D02*
X128020D01*
X128607Y771230D01*
Y770633D01*
X129113Y770127D01*
X130669D01*
X131503Y770961D01*
X133261D01*
X134078Y770144D01*
X137291D01*
G01X107591Y776837D02*
X112107D01*
X113820Y775124D01*
X116723D01*
G01X125877Y775164D02*
X128369D01*
X128935Y775730D01*
Y777012D01*
X129594Y777671D01*
X131281D01*
X132115Y776837D01*
X137291D01*
G01X107591Y786877D02*
X109448D01*
X110476Y785849D01*
X112339D01*
X114002Y784186D01*
X114946D01*
X115995Y785235D01*
X116723D01*
G01X125877Y785204D02*
X126437D01*
X127465Y784176D01*
X129058D01*
X131562Y785849D01*
X134332D01*
X135360Y786877D01*
X137291D01*
G01X107591Y783530D02*
X109459D01*
X110488Y784559D01*
X111804D01*
X113467Y782896D01*
X114885D01*
X115946Y781835D01*
X116723D01*
G01X125877Y781858D02*
X126434D01*
X127462Y782886D01*
X129450D01*
X131954Y784559D01*
X134334D01*
X135363Y783530D01*
X137291D01*
G01X107591Y800263D02*
X112107D01*
X113820Y798550D01*
X116723D01*
G01X125877Y798590D02*
X128369D01*
X128935Y799156D01*
Y800438D01*
X129594Y801097D01*
X131281D01*
X132115Y800263D01*
X137291D01*
G01X107591Y793570D02*
X114273D01*
X114769Y794066D01*
Y794738D01*
X115330Y795299D01*
X116723D01*
G01X125877Y795243D02*
X128020D01*
X128607Y794656D01*
Y794059D01*
X129113Y793553D01*
X130669D01*
X131503Y794387D01*
X133261D01*
X134078Y793570D01*
X137291D01*
G01X107591Y813648D02*
X112107D01*
X113820Y811935D01*
X116723D01*
G01X125877Y811975D02*
X128369D01*
X128935Y812541D01*
Y813823D01*
X129594Y814482D01*
X131281D01*
X132115Y813648D01*
X137291D01*
G01X107591Y806955D02*
X114273D01*
X114769Y807451D01*
Y808123D01*
X115330Y808684D01*
X116723D01*
G01X125877Y808628D02*
X128020D01*
X128607Y808041D01*
Y807444D01*
X129113Y806938D01*
X130669D01*
X131503Y807772D01*
X133261D01*
X134078Y806955D01*
X137291D01*
G01X107591Y830381D02*
X114273D01*
X114769Y830877D01*
Y831549D01*
X115330Y832110D01*
X116723D01*
G01X125877Y832054D02*
X128020D01*
X128607Y831467D01*
Y830870D01*
X129113Y830364D01*
X130669D01*
X131503Y831198D01*
X133261D01*
X134078Y830381D01*
X137291D01*
G01X107591Y823688D02*
X109448D01*
X110476Y822660D01*
X112339D01*
X114002Y820997D01*
X114946D01*
X115995Y822046D01*
X116723D01*
G01X125877Y822015D02*
X126437D01*
X127465Y820987D01*
X129058D01*
X131562Y822660D01*
X134332D01*
X135360Y823688D01*
X137291D01*
G01X107591Y820341D02*
X109459D01*
X110488Y821370D01*
X111804D01*
X113467Y819707D01*
X114885D01*
X115946Y818646D01*
X116723D01*
G01X125877Y818669D02*
X126434D01*
X127462Y819697D01*
X129450D01*
X131954Y821370D01*
X134334D01*
X135363Y820341D01*
X137291D01*
G01X107591Y850459D02*
X112107D01*
X113820Y848746D01*
X116723D01*
G01X125877Y848786D02*
X128369D01*
X128935Y849352D01*
Y850634D01*
X129594Y851293D01*
X131281D01*
X132115Y850459D01*
X137291D01*
G01X107591Y843766D02*
X114273D01*
X114769Y844262D01*
Y844934D01*
X115330Y845495D01*
X116723D01*
G01X125877Y845439D02*
X128020D01*
X128607Y844852D01*
Y844255D01*
X129113Y843749D01*
X130669D01*
X131503Y844583D01*
X133261D01*
X134078Y843766D01*
X137291D01*
G01X107591Y837074D02*
X112107D01*
X113820Y835361D01*
X116723D01*
G01X125877Y835401D02*
X128369D01*
X128935Y835967D01*
Y837249D01*
X129594Y837908D01*
X131281D01*
X132115Y837074D01*
X137291D01*
G01X107591Y867192D02*
X114273D01*
X114769Y867688D01*
Y868360D01*
X115330Y868921D01*
X116723D01*
G01X125877Y868865D02*
X128020D01*
X128607Y868278D01*
Y867681D01*
X129113Y867175D01*
X130669D01*
X131503Y868009D01*
X133261D01*
X134078Y867192D01*
X137291D01*
G01X107591Y860499D02*
X109448D01*
X110476Y859471D01*
X112339D01*
X114002Y857808D01*
X114946D01*
X115995Y858857D01*
X116723D01*
G01X125877Y858826D02*
X126437D01*
X127465Y857798D01*
X129058D01*
X131562Y859471D01*
X134332D01*
X135360Y860499D01*
X137291D01*
G01X107591Y857152D02*
X109459D01*
X110488Y858181D01*
X111804D01*
X113467Y856518D01*
X114885D01*
X115946Y855457D01*
X116723D01*
G01X125877Y855480D02*
X126434D01*
X127462Y856508D01*
X129450D01*
X131954Y858181D01*
X134334D01*
X135363Y857152D01*
X137291D01*
G01X107591Y873885D02*
X112107D01*
X113820Y872172D01*
X116723D01*
G01X125877Y872212D02*
X128369D01*
X128935Y872778D01*
Y874060D01*
X129594Y874719D01*
X131281D01*
X132115Y873885D01*
X137291D01*
G01X107591Y880577D02*
X114273D01*
X114769Y881073D01*
Y881745D01*
X115330Y882306D01*
X116723D01*
G01X125877Y882250D02*
X128020D01*
X128607Y881663D01*
Y881066D01*
X129113Y880560D01*
X130669D01*
X131503Y881394D01*
X133261D01*
X134078Y880577D01*
X137291D01*
G01X107591Y887270D02*
X112107D01*
X113820Y885557D01*
X116723D01*
G01X125877Y885597D02*
X128369D01*
X128935Y886163D01*
Y887445D01*
X129594Y888104D01*
X131281D01*
X132115Y887270D01*
X137291D01*
G01X107591Y897310D02*
X109448D01*
X110476Y896282D01*
X112339D01*
X114002Y894619D01*
X114946D01*
X115995Y895668D01*
X116723D01*
G01X125877Y895637D02*
X126437D01*
X127465Y894609D01*
X129058D01*
X131562Y896282D01*
X134332D01*
X135360Y897310D01*
X137291D01*
G01X107591Y893963D02*
X109459D01*
X110488Y894992D01*
X111804D01*
X113467Y893329D01*
X114885D01*
X115946Y892268D01*
X116723D01*
G01X125877Y892291D02*
X126434D01*
X127462Y893319D01*
X129450D01*
X131954Y894992D01*
X134334D01*
X135363Y893963D01*
X137291D01*
G01X107591Y910696D02*
X112107D01*
X113820Y908983D01*
X116723D01*
G01X125877Y909023D02*
X128369D01*
X128935Y909589D01*
Y910871D01*
X129594Y911530D01*
X131281D01*
X132115Y910696D01*
X137291D01*
G01X107591Y904003D02*
X114273D01*
X114769Y904499D01*
Y905171D01*
X115330Y905732D01*
X116723D01*
G01X125877Y905676D02*
X128020D01*
X128607Y905089D01*
Y904492D01*
X129113Y903986D01*
X130669D01*
X131503Y904820D01*
X133261D01*
X134078Y904003D01*
X137291D01*
G01X107591Y924081D02*
X112107D01*
X113780Y922408D01*
X116175D01*
G01X126163D02*
X128369D01*
X128935Y922974D01*
Y924256D01*
X129594Y924915D01*
X131281D01*
X132115Y924081D01*
X137291D01*
G01X107591Y917389D02*
X114273D01*
X114769Y917885D01*
Y918501D01*
X115330Y919062D01*
X116207D01*
G01X126131D02*
X128020D01*
X128607Y918475D01*
Y917758D01*
X129372Y916993D01*
X130490D01*
X131382Y917885D01*
X133182D01*
X133678Y917389D01*
X137291D01*
G01X107591Y934121D02*
X109448D01*
X110476Y933093D01*
X112339D01*
X114002Y931430D01*
X114946D01*
X115964Y932448D01*
X116160D01*
G01X126084D02*
X126437D01*
X127465Y931420D01*
X129058D01*
X131562Y933093D01*
X134332D01*
X135360Y934121D01*
X137291D01*
G01X107591Y930774D02*
X109459D01*
X110488Y931803D01*
X111804D01*
X113467Y930140D01*
X114885D01*
X115924Y929101D01*
X116160D01*
G01X126084D02*
X126433D01*
X127462Y930130D01*
X129450D01*
X131954Y931803D01*
X134334D01*
X135363Y930774D01*
X137291D01*
G01X107591Y947507D02*
X112107D01*
X113780Y945834D01*
X116192D01*
G01X126147D02*
X128289D01*
X128935Y946480D01*
Y947682D01*
X129861Y948608D01*
X131014D01*
X132115Y947507D01*
X137291D01*
G01X107591Y940814D02*
X114273D01*
X114769Y941310D01*
Y941926D01*
X115330Y942487D01*
X116193D01*
G01X126148D02*
X128020D01*
X128607Y941900D01*
Y941195D01*
X129397Y940405D01*
X130637D01*
X131483Y941251D01*
X133301D01*
X133738Y940814D01*
X137291D01*
G01X107591Y964239D02*
X111941D01*
G01X107591Y977625D02*
X114273D01*
X114769Y978121D01*
Y978793D01*
X115330Y979354D01*
X116723D01*
G01X125877Y979298D02*
X128020D01*
X128607Y978711D01*
Y978114D01*
X129113Y977608D01*
X130669D01*
X131503Y978442D01*
X133261D01*
X134078Y977625D01*
X137291D01*
G01X107591Y970932D02*
X114273D01*
X114769Y971428D01*
Y972100D01*
X115330Y972661D01*
X116723D01*
G01X125877Y972605D02*
X128020D01*
X128607Y972018D01*
Y971421D01*
X129113Y970915D01*
X130669D01*
X131503Y971749D01*
X133261D01*
X134078Y970932D01*
X137291D01*
G01X107591Y991011D02*
X114273D01*
X114769Y991507D01*
Y992179D01*
X115330Y992740D01*
X116723D01*
G01X125877Y992684D02*
X128020D01*
X128607Y992097D01*
Y991500D01*
X129113Y990994D01*
X130669D01*
X131503Y991828D01*
X133261D01*
X134078Y991011D01*
X137291D01*
G01X107591Y984318D02*
X114273D01*
X114769Y984814D01*
Y985486D01*
X115330Y986047D01*
X116723D01*
G01X125877Y985991D02*
X128020D01*
X128607Y985404D01*
Y984807D01*
X129113Y984301D01*
X130669D01*
X131503Y985135D01*
X133261D01*
X134078Y984318D01*
X137291D01*
G01X107591Y1021129D02*
X111941D01*
G01X107591Y1024475D02*
X111941D01*
G01X107591Y1044554D02*
X114273D01*
X114769Y1045050D01*
Y1045722D01*
X115330Y1046283D01*
X116723D01*
G01X125877Y1046227D02*
X128020D01*
X128607Y1045640D01*
Y1045043D01*
X129113Y1044537D01*
X130669D01*
X131503Y1045371D01*
X133261D01*
X134078Y1044554D01*
X137291D01*
G01X107591Y1037861D02*
X114273D01*
X114769Y1038357D01*
Y1039029D01*
X115330Y1039590D01*
X116723D01*
G01X125877Y1039534D02*
X128020D01*
X128607Y1038947D01*
Y1038350D01*
X129113Y1037844D01*
X130669D01*
X131503Y1038678D01*
X133261D01*
X134078Y1037861D01*
X137291D01*
G01X107591Y1031168D02*
X114273D01*
X114769Y1031664D01*
Y1032336D01*
X115330Y1032897D01*
X116723D01*
G01X125877Y1032841D02*
X128020D01*
X128607Y1032254D01*
Y1031657D01*
X129113Y1031151D01*
X130669D01*
X131503Y1031985D01*
X133261D01*
X134078Y1031168D01*
X137291D01*
G01X107591Y1051247D02*
X111941D01*
G01X107591Y1071326D02*
X112107D01*
X113780Y1069653D01*
X116222D01*
G01X126146D02*
X128369D01*
X128935Y1070219D01*
Y1071501D01*
X129594Y1072160D01*
X131281D01*
X132115Y1071326D01*
X137291D01*
G01X107591Y1064633D02*
X114273D01*
X114769Y1065129D01*
Y1065745D01*
X115330Y1066306D01*
X116206D01*
G01X126098D02*
X127817D01*
X128607Y1065516D01*
Y1064877D01*
X129397Y1064087D01*
X130624D01*
X131586Y1065049D01*
X133662D01*
X134078Y1064633D01*
X137291D01*
G01X107591Y1078018D02*
X109459D01*
X110488Y1079047D01*
X111804D01*
X113467Y1077384D01*
X114885D01*
X115924Y1076345D01*
X116206D01*
G01X126083D02*
X126433D01*
X127462Y1077374D01*
X129450D01*
X131954Y1079047D01*
X134334D01*
X135363Y1078018D01*
X137291D01*
G01X107591Y1094751D02*
X112107D01*
X113780Y1093078D01*
X116205D01*
G01X126160D02*
X128275D01*
X128935Y1093738D01*
Y1094926D01*
X129714Y1095705D01*
X131161D01*
X132115Y1094751D01*
X137291D01*
G01X107591Y1088058D02*
X114273D01*
X114769Y1088554D01*
Y1089170D01*
X115330Y1089731D01*
X116224D01*
G01X126164D02*
X128020D01*
X128607Y1089144D01*
Y1088345D01*
X129397Y1087555D01*
X130767D01*
X131717Y1088505D01*
X133631D01*
X134078Y1088058D01*
X137291D01*
G01X107591Y1081365D02*
X109448D01*
X110476Y1080337D01*
X112339D01*
X113991Y1078685D01*
X114991D01*
X115998Y1079692D01*
X116206D01*
G01X126083D02*
X126437D01*
X127465Y1078664D01*
X129058D01*
X131562Y1080337D01*
X134332D01*
X135360Y1081365D01*
X137291D01*
G01X107591Y1108137D02*
X112107D01*
X113820Y1106424D01*
X116723D01*
G01X125877Y1106464D02*
X128369D01*
X128935Y1107030D01*
Y1108312D01*
X129594Y1108971D01*
X131281D01*
X132115Y1108137D01*
X137291D01*
G01X107591Y1101444D02*
X114273D01*
X114769Y1101940D01*
Y1102612D01*
X115330Y1103173D01*
X116723D01*
G01X125877Y1103117D02*
X128020D01*
X128607Y1102530D01*
Y1101933D01*
X129113Y1101427D01*
X130669D01*
X131503Y1102261D01*
X133261D01*
X134078Y1101444D01*
X137291D01*
G01X107591Y1124869D02*
X114273D01*
X114769Y1125365D01*
Y1126037D01*
X115330Y1126598D01*
X116723D01*
G01X125877Y1126542D02*
X128020D01*
X128607Y1125955D01*
Y1125358D01*
X129113Y1124852D01*
X130669D01*
X131503Y1125686D01*
X133261D01*
X134078Y1124869D01*
X137291D01*
G01X107591Y1118176D02*
X109448D01*
X110476Y1117148D01*
X112339D01*
X114002Y1115485D01*
X114946D01*
X116002Y1116541D01*
X116723D01*
G01X125877Y1116503D02*
X126437D01*
X127465Y1115475D01*
X129058D01*
X131562Y1117148D01*
X134332D01*
X135360Y1118176D01*
X137291D01*
G01X107591Y1114829D02*
X109459D01*
X110488Y1115858D01*
X111804D01*
X113467Y1114195D01*
X114885D01*
X115946Y1113134D01*
X116723D01*
G01X125877Y1113157D02*
X126434D01*
X127462Y1114185D01*
X129450D01*
X131954Y1115858D01*
X134334D01*
X135363Y1114829D01*
X137291D01*
G01X107591Y1138255D02*
X114273D01*
X114769Y1138751D01*
Y1139423D01*
X115330Y1139984D01*
X116723D01*
G01X125877Y1139928D02*
X128020D01*
X128607Y1139341D01*
Y1138744D01*
X129113Y1138238D01*
X130669D01*
X131503Y1139072D01*
X133261D01*
X134078Y1138255D01*
X137291D01*
G01X107591Y1131562D02*
X112107D01*
X113820Y1129849D01*
X116723D01*
G01X125877Y1129889D02*
X128369D01*
X128935Y1130455D01*
Y1131737D01*
X129594Y1132396D01*
X131281D01*
X132115Y1131562D01*
X137291D01*
G01X107591Y1144948D02*
X112107D01*
X113820Y1143235D01*
X116723D01*
G01X125877Y1143275D02*
X128369D01*
X128935Y1143841D01*
Y1145123D01*
X129594Y1145782D01*
X131281D01*
X132115Y1144948D01*
X137291D01*
G01X107591Y1154987D02*
X109448D01*
X110476Y1153959D01*
X112339D01*
X114002Y1152296D01*
X114946D01*
X116002Y1153352D01*
X116723D01*
G01X125877Y1153314D02*
X126437D01*
X127465Y1152286D01*
X129058D01*
X131562Y1153959D01*
X134332D01*
X135360Y1154987D01*
X137291D01*
G01X107591Y1151641D02*
X109460D01*
X110488Y1152669D01*
X111804D01*
X113467Y1151006D01*
X114885D01*
X115946Y1149945D01*
X116723D01*
G01X125877Y1149968D02*
X126434D01*
X127462Y1150996D01*
X129450D01*
X131954Y1152669D01*
X134334D01*
X135362Y1151641D01*
X137291D01*
G01X107591Y1175066D02*
X114273D01*
X114769Y1175562D01*
Y1176234D01*
X115330Y1176795D01*
X116723D01*
G01X125877Y1176739D02*
X128020D01*
X128607Y1176152D01*
Y1175555D01*
X129113Y1175049D01*
X130669D01*
X131503Y1175883D01*
X133261D01*
X134078Y1175066D01*
X137291D01*
G01X107591Y1168373D02*
X112107D01*
X113820Y1166660D01*
X116723D01*
G01X125877Y1166700D02*
X128369D01*
X128935Y1167266D01*
Y1168548D01*
X129594Y1169207D01*
X131281D01*
X132115Y1168373D01*
X137291D01*
G01X107591Y1161680D02*
X114273D01*
X114769Y1162176D01*
Y1162848D01*
X115330Y1163409D01*
X116723D01*
G01X125877Y1163353D02*
X128020D01*
X128607Y1162766D01*
Y1162169D01*
X129113Y1161663D01*
X130669D01*
X131503Y1162497D01*
X133261D01*
X134078Y1161680D01*
X137291D01*
G01X107591Y1181759D02*
X112107D01*
X113820Y1180046D01*
X116723D01*
G01X125877Y1180086D02*
X128369D01*
X128935Y1180652D01*
Y1181934D01*
X129594Y1182593D01*
X131281D01*
X132115Y1181759D01*
X137291D01*
G01X107591Y1191798D02*
X109448D01*
X110476Y1190770D01*
X112339D01*
X114002Y1189107D01*
X114946D01*
X116002Y1190163D01*
X116723D01*
G01X125877Y1190125D02*
X126437D01*
X127465Y1189097D01*
X129058D01*
X131562Y1190770D01*
X134332D01*
X135360Y1191798D01*
X137291D01*
G01X107591Y1188452D02*
X109460D01*
X110488Y1189480D01*
X111804D01*
X113467Y1187817D01*
X114885D01*
X115946Y1186756D01*
X116723D01*
G01X125877Y1186779D02*
X126434D01*
X127462Y1187807D01*
X129450D01*
X131954Y1189480D01*
X134334D01*
X135362Y1188452D01*
X137291D01*
G01X107591Y1205184D02*
X112107D01*
X113820Y1203471D01*
X116723D01*
G01X125877Y1203511D02*
X128369D01*
X128935Y1204077D01*
Y1205359D01*
X129594Y1206018D01*
X131281D01*
X132115Y1205184D01*
X137291D01*
G01X107591Y1198491D02*
X114273D01*
X114769Y1198987D01*
Y1199659D01*
X115330Y1200220D01*
X116723D01*
G01X125877Y1200164D02*
X128020D01*
X128607Y1199577D01*
Y1198980D01*
X129113Y1198474D01*
X130669D01*
X131503Y1199308D01*
X133261D01*
X134078Y1198491D01*
X137291D01*
G01X107591Y1218570D02*
X112107D01*
X113820Y1216857D01*
X116723D01*
G01X125877Y1216897D02*
X128369D01*
X128935Y1217463D01*
Y1218745D01*
X129594Y1219404D01*
X131281D01*
X132115Y1218570D01*
X137291D01*
G01X107591Y1211877D02*
X114273D01*
X114769Y1212373D01*
Y1213045D01*
X115330Y1213606D01*
X116723D01*
G01X125877Y1213550D02*
X128020D01*
X128607Y1212963D01*
Y1212366D01*
X129113Y1211860D01*
X130669D01*
X131503Y1212694D01*
X133261D01*
X134078Y1211877D01*
X137291D01*
G01X107591Y1225263D02*
X109460D01*
X110488Y1226291D01*
X111804D01*
X113467Y1224628D01*
X114885D01*
X115946Y1223567D01*
X116723D01*
G01X125877Y1223590D02*
X126434D01*
X127462Y1224618D01*
X129450D01*
X131954Y1226291D01*
X134334D01*
X135362Y1225263D01*
X137291D01*
G01X107591Y1241995D02*
X112107D01*
X113820Y1240282D01*
X116723D01*
G01X125877Y1240322D02*
X128369D01*
X128935Y1240888D01*
Y1242170D01*
X129594Y1242829D01*
X131281D01*
X132115Y1241995D01*
X137291D01*
G01X107591Y1235302D02*
X114273D01*
X114769Y1235798D01*
Y1236470D01*
X115330Y1237031D01*
X116723D01*
G01X125877Y1236975D02*
X128020D01*
X128607Y1236388D01*
Y1235791D01*
X129113Y1235285D01*
X130669D01*
X131503Y1236119D01*
X133261D01*
X134078Y1235302D01*
X137291D01*
G01X107591Y1228609D02*
X109448D01*
X110476Y1227581D01*
X112339D01*
X114002Y1225918D01*
X114946D01*
X116002Y1226974D01*
X116723D01*
G01X125877Y1226936D02*
X126437D01*
X127465Y1225908D01*
X129058D01*
X131562Y1227581D01*
X134332D01*
X135360Y1228609D01*
X137291D01*
G01X125499Y780184D02*
X121149D01*
G01X125499Y773491D02*
X121149D01*
G01X125499Y786877D02*
X121149D01*
G01X125499Y796916D02*
X121149D01*
G01X125499Y790223D02*
X121149D01*
G01X125499Y816995D02*
X121149D01*
G01X125499Y810302D02*
X121149D01*
G01X125499Y803609D02*
X121149D01*
G01X125499Y833727D02*
X121149D01*
G01X125499Y823688D02*
X121149D01*
G01X125499Y827034D02*
X121149D01*
G01X125499Y847113D02*
X121149D01*
G01X125499Y840420D02*
X121149D01*
G01X125499Y853806D02*
X121149D01*
G01X125499Y860499D02*
X121149D01*
G01X125499Y863845D02*
X121149D01*
G01X125499Y883924D02*
X121149D01*
G01X125499Y877231D02*
X121149D01*
G01X125499Y870538D02*
X121149D01*
G01X125499Y890617D02*
X121149D01*
G01X125499Y897310D02*
X121149D01*
G01X125499Y900656D02*
X121149D01*
G01X125499Y914042D02*
X121149D01*
G01X125499Y907349D02*
X121149D01*
G01X125499Y927428D02*
X121149D01*
G01X125499Y920735D02*
X121149D01*
G01X125499Y944160D02*
X121149D01*
G01X125499Y934121D02*
X121149D01*
G01X125499Y937467D02*
X121149D01*
G01Y960892D02*
X125499D01*
G01Y950853D02*
X121149D01*
G01Y957546D02*
X125499D01*
G01Y980971D02*
X121149D01*
G01X125499Y974278D02*
X121149D01*
G01Y967585D02*
X125499D01*
G01Y994357D02*
X121149D01*
G01X125499Y987664D02*
X121149D01*
G01X125499Y1027822D02*
X121149D01*
G01X125499Y1021129D02*
X121149D01*
G01X125499Y1041207D02*
X121149D01*
G01X125499Y1034515D02*
X121149D01*
G01X125499Y1061286D02*
X121149D01*
G01X125499Y1047900D02*
X121149D01*
G01Y1054593D02*
X125499D01*
G01Y1074672D02*
X121149D01*
G01X125499Y1067979D02*
X121149D01*
G01X125499Y1091404D02*
X121149D01*
G01X125499Y1081365D02*
X121149D01*
G01X125499Y1084711D02*
X121149D01*
G01X125499Y1098097D02*
X121149D01*
G01X125499Y1111483D02*
X121149D01*
G01X125499Y1104790D02*
X121149D01*
G01X125499Y1128215D02*
X121149D01*
G01X125499Y1118176D02*
X121149D01*
G01X125499Y1121522D02*
X121149D01*
G01X125499Y1141601D02*
X121149D01*
G01X125499Y1134908D02*
X121149D01*
G01X125499Y1148294D02*
X121149D01*
G01X125499Y1154987D02*
X121149D01*
G01X125499Y1158333D02*
X121149D01*
G01X125499Y1171719D02*
X121149D01*
G01X125499Y1165026D02*
X121149D01*
G01X125499Y1185105D02*
X121149D01*
G01X125499Y1178412D02*
X121149D01*
G01X125499Y1191798D02*
X121149D01*
G01X125499Y1208530D02*
X121149D01*
G01X125499Y1201837D02*
X121149D01*
G01X125499Y1195144D02*
X121149D01*
G01X125499Y1221916D02*
X121149D01*
G01X125499Y1215223D02*
X121149D01*
G01X125499Y1238648D02*
X121149D01*
G01X125499Y1228609D02*
X121149D01*
G01X125499Y1231955D02*
X121149D01*
G01X125499Y1245341D02*
X121149D01*
G01X141641Y770144D02*
X137291D01*
G01X141641Y776837D02*
X137291D01*
G01X141641Y786877D02*
X137291D01*
G01X141641Y783530D02*
X137291D01*
G01X141641Y800263D02*
X137291D01*
G01X141641Y793570D02*
X137291D01*
G01X141641Y813648D02*
X137291D01*
G01X141641Y806955D02*
X137291D01*
G01X141641Y830381D02*
X137291D01*
G01X141641Y823688D02*
X137291D01*
G01X141641Y820341D02*
X137291D01*
G01X141641Y850459D02*
X137291D01*
G01X141641Y843766D02*
X137291D01*
G01X141641Y837074D02*
X137291D01*
G01X141641Y867192D02*
X137291D01*
G01X141641Y860499D02*
X137291D01*
G01X141641Y857152D02*
X137291D01*
G01X141641Y873885D02*
X137291D01*
G01X141641Y880577D02*
X137291D01*
G01X141641Y887270D02*
X137291D01*
G01X141641Y897310D02*
X137291D01*
G01X141641Y893963D02*
X137291D01*
G01X141641Y910696D02*
X137291D01*
G01X141641Y904003D02*
X137291D01*
G01X141641Y924081D02*
X137291D01*
G01X141641Y917389D02*
X137291D01*
G01X141641Y930774D02*
X137291D01*
G01X141641Y947507D02*
X137291D01*
G01X141641Y940814D02*
X137291D01*
G01X141641Y934121D02*
X137291D01*
G01Y964239D02*
X141641D01*
G01Y977625D02*
X137291D01*
G01X141641Y970932D02*
X137291D01*
G01X141641Y991011D02*
X137291D01*
G01X141641Y984318D02*
X137291D01*
G01Y1021129D02*
X141641D01*
G01X137291Y1024475D02*
X141641D01*
G01Y1044554D02*
X137291D01*
G01X141641Y1037861D02*
X137291D01*
G01X141641Y1031168D02*
X137291D01*
G01Y1051247D02*
X141641D01*
G01Y1071326D02*
X137291D01*
G01X141641Y1064633D02*
X137291D01*
G01X141641Y1078018D02*
X137291D01*
G01X141641Y1094751D02*
X137291D01*
G01X141641Y1088058D02*
X137291D01*
G01X141641Y1081365D02*
X137291D01*
G01X141641Y1108137D02*
X137291D01*
G01X141641Y1101444D02*
X137291D01*
G01X141641Y1124869D02*
X137291D01*
G01X141641Y1118176D02*
X137291D01*
G01X141641Y1114829D02*
X137291D01*
G01X141641Y1138255D02*
X137291D01*
G01X141641Y1131562D02*
X137291D01*
G01X141641Y1144948D02*
X137291D01*
G01X141641Y1154987D02*
X137291D01*
G01X141641Y1151641D02*
X137291D01*
G01X141641Y1175066D02*
X137291D01*
G01X141641Y1168373D02*
X137291D01*
G01X141641Y1161680D02*
X137291D01*
G01X141641Y1181759D02*
X137291D01*
G01X141641Y1191798D02*
X137291D01*
G01X141641Y1188452D02*
X137291D01*
G01X141641Y1205184D02*
X137291D01*
G01X141641Y1198491D02*
X137291D01*
G01X141641Y1218570D02*
X137291D01*
G01X141641Y1211877D02*
X137291D01*
G01X141641Y1225263D02*
X137291D01*
G01X141641Y1241995D02*
X137291D01*
G01X141641Y1235302D02*
X137291D01*
G01X141641Y1228609D02*
X137291D01*
G01X180549Y780184D02*
X175159D01*
X173486Y778511D01*
X171719D01*
G01X162565Y778479D02*
X160353D01*
X159528Y779304D01*
Y780444D01*
X158848Y781124D01*
X157042D01*
X156102Y780184D01*
X150849D01*
G01X180549Y773491D02*
X174095D01*
X172422Y771818D01*
X171719D01*
G01X162565Y771783D02*
X160168D01*
X159528Y772423D01*
Y773715D01*
X158920Y774323D01*
X156934D01*
X156102Y773491D01*
X150849D01*
G01X180549Y786877D02*
X178397D01*
X177369Y787905D01*
X175768D01*
X174094Y789579D01*
X173359D01*
X172330Y788550D01*
X171719D01*
G01X162565Y788508D02*
X161761D01*
X160690Y789579D01*
X158564D01*
X156060Y787905D01*
X154037D01*
X153009Y786877D01*
X150849D01*
G01X180549Y796916D02*
X174095D01*
X172422Y795243D01*
X171719D01*
G01X162565Y795208D02*
X160168D01*
X159528Y795848D01*
Y797140D01*
X158920Y797748D01*
X156934D01*
X156102Y796916D01*
X150849D01*
G01X180549Y790223D02*
X178389D01*
X177361Y789195D01*
X176303D01*
X174629Y790869D01*
X173346D01*
X172318Y791897D01*
X171719D01*
G01X162565Y791934D02*
X161706D01*
X160641Y790869D01*
X158172D01*
X155668Y789195D01*
X153995D01*
X152967Y790223D01*
X150849D01*
G01X180549Y816995D02*
X175159D01*
X173486Y815322D01*
X171719D01*
G01X162565Y815290D02*
X160353D01*
X159528Y816115D01*
Y817255D01*
X158848Y817935D01*
X157042D01*
X156102Y816995D01*
X150849D01*
G01X180549Y810302D02*
X174095D01*
X172422Y808629D01*
X171719D01*
G01X162565Y808594D02*
X160168D01*
X159528Y809234D01*
Y810526D01*
X158920Y811134D01*
X156934D01*
X156102Y810302D01*
X150849D01*
G01X180549Y803609D02*
X175159D01*
X173486Y801936D01*
X171719D01*
G01X162565Y801904D02*
X160353D01*
X159528Y802729D01*
Y803869D01*
X158848Y804549D01*
X157042D01*
X156102Y803609D01*
X150849D01*
G01X180549Y833727D02*
X174095D01*
X172422Y832054D01*
X171719D01*
G01X162565Y832019D02*
X160168D01*
X159528Y832659D01*
Y833951D01*
X158920Y834559D01*
X156934D01*
X156102Y833727D01*
X150849D01*
G01X180549Y823688D02*
X178397D01*
X177369Y824716D01*
X175768D01*
X174094Y826390D01*
X173359D01*
X172330Y825361D01*
X171719D01*
G01X162565Y825319D02*
X161761D01*
X160690Y826390D01*
X158564D01*
X156060Y824716D01*
X154037D01*
X153009Y823688D01*
X150849D01*
G01X180549Y827034D02*
X178389D01*
X177361Y826006D01*
X176303D01*
X174629Y827680D01*
X173346D01*
X172318Y828708D01*
X171719D01*
G01X162565Y828745D02*
X161706D01*
X160641Y827680D01*
X158172D01*
X155668Y826006D01*
X153995D01*
X152967Y827034D01*
X150849D01*
G01X180549Y847113D02*
X174095D01*
X172422Y845440D01*
X171719D01*
G01X162565Y845405D02*
X160168D01*
X159528Y846045D01*
Y847337D01*
X158920Y847945D01*
X156934D01*
X156102Y847113D01*
X150849D01*
G01X180549Y840420D02*
X175159D01*
X173486Y838747D01*
X171719D01*
G01X162565Y838715D02*
X160353D01*
X159528Y839540D01*
Y840680D01*
X158848Y841360D01*
X157042D01*
X156102Y840420D01*
X150849D01*
G01X180549Y853806D02*
X175159D01*
X173486Y852133D01*
X171719D01*
G01X162565Y852101D02*
X160353D01*
X159528Y852926D01*
Y854066D01*
X158848Y854746D01*
X157042D01*
X156102Y853806D01*
X150849D01*
G01X180549Y860499D02*
X178397D01*
X177369Y861527D01*
X175768D01*
X174094Y863201D01*
X173359D01*
X172330Y862172D01*
X171719D01*
G01X162565Y862130D02*
X161761D01*
X160690Y863201D01*
X158563D01*
X156060Y861527D01*
X154037D01*
X153009Y860499D01*
X150849D01*
G01X180549Y863845D02*
X178389D01*
X177361Y862817D01*
X176303D01*
X174629Y864491D01*
X173346D01*
X172318Y865519D01*
X171720D01*
G01X162566Y865555D02*
X162565Y865556D01*
X161706D01*
X160641Y864491D01*
X158171D01*
X155668Y862817D01*
X153995D01*
X152967Y863845D01*
X150849D01*
G01X180549Y883924D02*
X174095D01*
X172422Y882251D01*
X171719D01*
G01X162565Y882216D02*
X160168D01*
X159528Y882856D01*
Y884148D01*
X158920Y884756D01*
X156934D01*
X156102Y883924D01*
X150849D01*
G01X180549Y877231D02*
X175159D01*
X173486Y875558D01*
X171719D01*
G01X162565Y875526D02*
X160353D01*
X159528Y876351D01*
Y877491D01*
X158848Y878171D01*
X157042D01*
X156102Y877231D01*
X150849D01*
G01X180549Y870538D02*
X174095D01*
X172422Y868865D01*
X171719D01*
G01X162565Y868830D02*
X160168D01*
X159528Y869470D01*
Y870762D01*
X158920Y871370D01*
X156934D01*
X156102Y870538D01*
X150849D01*
G01X180549Y890617D02*
X175159D01*
X173486Y888944D01*
X171719D01*
G01X162565Y888912D02*
X160353D01*
X159528Y889737D01*
Y890877D01*
X158848Y891557D01*
X157042D01*
X156102Y890617D01*
X150849D01*
G01X180549Y897310D02*
X178397D01*
X177369Y898338D01*
X175768D01*
X174094Y900012D01*
X173359D01*
X172330Y898983D01*
X171719D01*
G01X162565Y898941D02*
X161761D01*
X160690Y900012D01*
X158564D01*
X156060Y898338D01*
X154037D01*
X153009Y897310D01*
X150849D01*
G01X180549Y900656D02*
X178389D01*
X177361Y899628D01*
X176303D01*
X174629Y901302D01*
X173346D01*
X172318Y902330D01*
X171719D01*
G01X162565Y902367D02*
X161706D01*
X160641Y901302D01*
X158172D01*
X155668Y899628D01*
X153995D01*
X152967Y900656D01*
X150849D01*
G01X180549Y914042D02*
X175159D01*
X173486Y912369D01*
X171719D01*
G01X162565Y912337D02*
X160353D01*
X159528Y913162D01*
Y914302D01*
X158848Y914982D01*
X157042D01*
X156102Y914042D01*
X150849D01*
G01X180549Y907349D02*
X174095D01*
X172422Y905676D01*
X171719D01*
G01X162565Y905641D02*
X160168D01*
X159528Y906281D01*
Y907573D01*
X158920Y908181D01*
X156934D01*
X156102Y907349D01*
X150849D01*
G01X180549Y927428D02*
X175159D01*
X173486Y925755D01*
X171719D01*
G01X162565Y925723D02*
X160353D01*
X159528Y926548D01*
Y927688D01*
X158848Y928368D01*
X157042D01*
X156102Y927428D01*
X150849D01*
G01X180549Y920735D02*
X174095D01*
X172422Y919062D01*
X171719D01*
G01X162565Y919027D02*
X160168D01*
X159528Y919667D01*
Y920959D01*
X158920Y921567D01*
X156934D01*
X156102Y920735D01*
X150849D01*
G01X180549Y944160D02*
X174095D01*
X172422Y942487D01*
X171719D01*
G01X162565Y942452D02*
X160168D01*
X159528Y943092D01*
Y944384D01*
X158920Y944992D01*
X156934D01*
X156102Y944160D01*
X150849D01*
G01X180549Y934121D02*
X178397D01*
X177369Y935149D01*
X175768D01*
X174094Y936823D01*
X173359D01*
X172330Y935794D01*
X171719D01*
G01X162565Y935752D02*
X161761D01*
X160690Y936823D01*
X158564D01*
X156060Y935149D01*
X154037D01*
X153009Y934121D01*
X150849D01*
G01X180549Y937467D02*
X178389D01*
X177361Y936439D01*
X176303D01*
X174629Y938113D01*
X173346D01*
X172318Y939141D01*
X171720D01*
G01X162566Y939171D02*
X161699D01*
X160641Y938113D01*
X158172D01*
X155668Y936439D01*
X153995D01*
X152967Y937467D01*
X150849D01*
G01Y960892D02*
X155199D01*
G01X180549Y950853D02*
X175159D01*
X173486Y949180D01*
X171719D01*
G01X162565Y949148D02*
X160353D01*
X159528Y949973D01*
Y951113D01*
X158848Y951793D01*
X157042D01*
X156102Y950853D01*
X150849D01*
G01Y957546D02*
X155199D01*
G01X180549Y980971D02*
X174095D01*
X172422Y979298D01*
X171719D01*
G01X162565Y979263D02*
X160168D01*
X159528Y979903D01*
Y981195D01*
X158920Y981803D01*
X156934D01*
X156102Y980971D01*
X150849D01*
G01X180549Y974278D02*
X174095D01*
X172422Y972605D01*
X171719D01*
G01X162565Y972570D02*
X160168D01*
X159528Y973210D01*
Y974502D01*
X158920Y975110D01*
X156934D01*
X156102Y974278D01*
X150849D01*
G01Y967585D02*
X155199D01*
G01X180549Y994357D02*
X174095D01*
X172422Y992684D01*
X171719D01*
G01X162565Y992649D02*
X160168D01*
X159528Y993289D01*
Y994581D01*
X158920Y995189D01*
X156934D01*
X156102Y994357D01*
X150849D01*
G01X180549Y987664D02*
X174095D01*
X172422Y985991D01*
X171719D01*
G01X162565Y985956D02*
X160168D01*
X159528Y986596D01*
Y987888D01*
X158920Y988496D01*
X156934D01*
X156102Y987664D01*
X150849D01*
G01X180549Y1027822D02*
X174095D01*
X172422Y1026149D01*
X171719D01*
G01X162565Y1026114D02*
X160168D01*
X159528Y1026754D01*
Y1028046D01*
X158920Y1028654D01*
X156934D01*
X156102Y1027822D01*
X150849D01*
G01X180549Y1021129D02*
X173831D01*
X172158Y1019456D01*
X171719D01*
G01X162565Y1019510D02*
X160081D01*
X160080Y1019509D01*
X159528Y1020061D01*
Y1021199D01*
X158657Y1022070D01*
X157043D01*
X156102Y1021129D01*
X150849D01*
G01X180549Y1041207D02*
X174095D01*
X172422Y1039534D01*
X171719D01*
G01X162565Y1039499D02*
X160168D01*
X159528Y1040139D01*
Y1041431D01*
X158920Y1042039D01*
X156934D01*
X156102Y1041207D01*
X150849D01*
G01X180549Y1034515D02*
X174095D01*
X172422Y1032842D01*
X171719D01*
G01X162565Y1032807D02*
X160168D01*
X159528Y1033447D01*
Y1034739D01*
X158920Y1035347D01*
X156934D01*
X156102Y1034515D01*
X150849D01*
G01X180549Y1061286D02*
X174095D01*
X172422Y1059613D01*
X172010D01*
G01X162038D02*
X160168D01*
X159528Y1060253D01*
Y1061510D01*
X158920Y1062118D01*
X156934D01*
X156102Y1061286D01*
X150849D01*
G01X180549Y1047900D02*
X174095D01*
X172422Y1046227D01*
X171719D01*
G01X162565Y1046192D02*
X160168D01*
X159528Y1046832D01*
Y1048124D01*
X158920Y1048732D01*
X156934D01*
X156102Y1047900D01*
X150849D01*
G01Y1054593D02*
X155199D01*
G01X180549Y1074672D02*
X175159D01*
X173486Y1072999D01*
X171719D01*
G01X162565Y1072967D02*
X160353D01*
X159528Y1073792D01*
Y1074932D01*
X158848Y1075612D01*
X157042D01*
X156102Y1074672D01*
X150849D01*
G01X180549Y1067979D02*
X174095D01*
X172422Y1066306D01*
X171719D01*
G01X162565Y1066271D02*
X160168D01*
X159528Y1066911D01*
Y1068203D01*
X158920Y1068811D01*
X156934D01*
X156102Y1067979D01*
X150849D01*
G01X180549Y1091404D02*
X174095D01*
X172422Y1089731D01*
X171719D01*
G01X162565Y1089696D02*
X160168D01*
X159528Y1090336D01*
Y1091628D01*
X158920Y1092236D01*
X156934D01*
X156102Y1091404D01*
X150849D01*
G01X180549Y1081365D02*
X178397D01*
X177369Y1082393D01*
X175768D01*
X174094Y1084067D01*
X173359D01*
X172330Y1083038D01*
X171719D01*
G01X162565Y1082996D02*
X161761D01*
X160690Y1084067D01*
X158564D01*
X156060Y1082393D01*
X154037D01*
X153009Y1081365D01*
X150849D01*
G01X180549Y1084711D02*
X178389D01*
X177361Y1083683D01*
X176303D01*
X174629Y1085357D01*
X173346D01*
X172318Y1086385D01*
X171719D01*
G01X162565Y1086422D02*
X161706D01*
X160641Y1085357D01*
X158172D01*
X155668Y1083683D01*
X153995D01*
X152967Y1084711D01*
X150849D01*
G01X180549Y1098097D02*
X175159D01*
X173486Y1096424D01*
X171719D01*
G01X162565Y1096392D02*
X160353D01*
X159528Y1097217D01*
Y1098357D01*
X158848Y1099037D01*
X157042D01*
X156102Y1098097D01*
X150849D01*
G01X180549Y1111483D02*
X175159D01*
X173486Y1109810D01*
X171719D01*
G01X162565Y1109778D02*
X160353D01*
X159528Y1110603D01*
Y1111743D01*
X158848Y1112423D01*
X157042D01*
X156102Y1111483D01*
X150849D01*
G01X180549Y1104790D02*
X174095D01*
X172422Y1103117D01*
X171719D01*
G01X162565Y1103082D02*
X160168D01*
X159528Y1103722D01*
Y1105014D01*
X158920Y1105622D01*
X156934D01*
X156102Y1104790D01*
X150849D01*
G01X180549Y1128215D02*
X174095D01*
X172422Y1126542D01*
X171719D01*
G01X162565Y1126507D02*
X160168D01*
X159528Y1127147D01*
Y1128439D01*
X158920Y1129047D01*
X156934D01*
X156102Y1128215D01*
X150849D01*
G01X180549Y1118176D02*
X178397D01*
X177369Y1119204D01*
X175768D01*
X174094Y1120878D01*
X173359D01*
X172330Y1119849D01*
X171719D01*
G01X162565Y1119807D02*
X161761D01*
X160690Y1120878D01*
X158564D01*
X156060Y1119204D01*
X154037D01*
X153009Y1118176D01*
X150849D01*
G01X180549Y1121522D02*
X178389D01*
X177361Y1120494D01*
X176303D01*
X174629Y1122168D01*
X173346D01*
X172318Y1123196D01*
X171719D01*
G01X162565Y1123233D02*
X161706D01*
X160641Y1122168D01*
X158172D01*
X155668Y1120494D01*
X153995D01*
X152967Y1121522D01*
X150849D01*
G01X180549Y1141601D02*
X174095D01*
X172422Y1139928D01*
X171719D01*
G01X162565Y1139893D02*
X160168D01*
X159528Y1140533D01*
Y1141825D01*
X158920Y1142433D01*
X156934D01*
X156102Y1141601D01*
X150849D01*
G01X180549Y1134908D02*
X175159D01*
X173486Y1133235D01*
X171719D01*
G01X162565Y1133203D02*
X160353D01*
X159528Y1134028D01*
Y1135168D01*
X158848Y1135848D01*
X157042D01*
X156102Y1134908D01*
X150849D01*
G01X180549Y1148294D02*
X175159D01*
X173486Y1146621D01*
X171719D01*
G01X162565Y1146589D02*
X160353D01*
X159528Y1147414D01*
Y1148554D01*
X158848Y1149234D01*
X157042D01*
X156102Y1148294D01*
X150849D01*
G01X180549Y1154987D02*
X178397D01*
X177369Y1156015D01*
X175768D01*
X174094Y1157689D01*
X173359D01*
X172330Y1156660D01*
X171719D01*
G01X162565Y1156618D02*
X161761D01*
X160690Y1157689D01*
X158564D01*
X156060Y1156015D01*
X154037D01*
X153009Y1154987D01*
X150849D01*
G01X180549Y1158333D02*
X178389D01*
X177361Y1157305D01*
X176303D01*
X174629Y1158979D01*
X173346D01*
X172318Y1160007D01*
X171719D01*
G01X162565Y1160044D02*
X161706D01*
X160641Y1158979D01*
X158172D01*
X155668Y1157305D01*
X153995D01*
X152967Y1158333D01*
X150849D01*
G01X180549Y1171719D02*
X175159D01*
X173486Y1170046D01*
X171719D01*
G01X162565Y1170014D02*
X160353D01*
X159528Y1170839D01*
Y1171979D01*
X158848Y1172659D01*
X157042D01*
X156102Y1171719D01*
X150849D01*
G01X180549Y1165026D02*
X174095D01*
X172422Y1163353D01*
X171719D01*
G01X162565Y1163318D02*
X160168D01*
X159528Y1163958D01*
Y1165250D01*
X158920Y1165858D01*
X156934D01*
X156102Y1165026D01*
X150849D01*
G01X180549Y1185105D02*
X175159D01*
X173486Y1183432D01*
X171719D01*
G01X162565Y1183400D02*
X160353D01*
X159528Y1184225D01*
Y1185365D01*
X158848Y1186045D01*
X157042D01*
X156102Y1185105D01*
X150849D01*
G01X180549Y1178412D02*
X174095D01*
X172422Y1176739D01*
X171719D01*
G01X162565Y1176704D02*
X160168D01*
X159528Y1177344D01*
Y1178636D01*
X158920Y1179244D01*
X156934D01*
X156102Y1178412D01*
X150849D01*
G01X180549Y1191798D02*
X178397D01*
X177369Y1192826D01*
X175768D01*
X174094Y1194500D01*
X173359D01*
X172330Y1193471D01*
X171719D01*
G01X162565Y1193429D02*
X161761D01*
X160690Y1194500D01*
X158564D01*
X156060Y1192826D01*
X154037D01*
X153009Y1191798D01*
X150849D01*
G01X180549Y1208530D02*
X175159D01*
X173486Y1206857D01*
X171719D01*
G01X162565Y1206825D02*
X160353D01*
X159528Y1207650D01*
Y1208790D01*
X158848Y1209470D01*
X157042D01*
X156102Y1208530D01*
X150849D01*
G01X180549Y1201837D02*
X174095D01*
X172422Y1200164D01*
X171719D01*
G01X162565Y1200129D02*
X160168D01*
X159528Y1200769D01*
Y1202061D01*
X158920Y1202669D01*
X156934D01*
X156102Y1201837D01*
X150849D01*
G01X180549Y1195144D02*
X178389D01*
X177361Y1194116D01*
X176303D01*
X174629Y1195790D01*
X173346D01*
X172318Y1196818D01*
X171719D01*
G01X162565Y1196855D02*
X161706D01*
X160641Y1195790D01*
X158172D01*
X155668Y1194116D01*
X153995D01*
X152967Y1195144D01*
X150849D01*
G01X180549Y1221916D02*
X175159D01*
X173486Y1220243D01*
X171719D01*
G01X162565Y1220211D02*
X160353D01*
X159528Y1221036D01*
Y1222176D01*
X158848Y1222856D01*
X157042D01*
X156102Y1221916D01*
X150849D01*
G01X180549Y1215223D02*
X174095D01*
X172422Y1213550D01*
X171719D01*
G01X162565Y1213515D02*
X160168D01*
X159528Y1214155D01*
Y1215447D01*
X158920Y1216055D01*
X156934D01*
X156102Y1215223D01*
X150849D01*
G01X180549Y1238648D02*
X174095D01*
X172422Y1236975D01*
X171719D01*
G01X162565Y1236940D02*
X160168D01*
X159528Y1237580D01*
Y1238872D01*
X158920Y1239480D01*
X156934D01*
X156102Y1238648D01*
X150849D01*
G01X180549Y1228609D02*
X178397D01*
X177369Y1229637D01*
X175768D01*
X174094Y1231311D01*
X173359D01*
X172330Y1230282D01*
X171719D01*
G01X162565Y1230240D02*
X161761D01*
X160690Y1231311D01*
X158564D01*
X156060Y1229637D01*
X154037D01*
X153009Y1228609D01*
X150849D01*
G01X180549Y1231955D02*
X178389D01*
X177361Y1230927D01*
X176303D01*
X174629Y1232601D01*
X173346D01*
X172318Y1233629D01*
X171719D01*
G01X162565Y1233666D02*
X161706D01*
X160641Y1232601D01*
X158172D01*
X155668Y1230927D01*
X153995D01*
X152967Y1231955D01*
X150849D01*
G01X180549Y1245341D02*
X175159D01*
X173486Y1243668D01*
X171719D01*
G01X162565Y1243636D02*
X160353D01*
X159528Y1244461D01*
Y1245601D01*
X158848Y1246281D01*
X157042D01*
X156102Y1245341D01*
X150849D01*
G01X196691Y770144D02*
X193478D01*
X192661Y770961D01*
X190903D01*
X190069Y770127D01*
X188513D01*
X188007Y770633D01*
Y771230D01*
X187420Y771817D01*
X185277D01*
G01X176123Y771873D02*
X174730D01*
X174169Y771312D01*
Y770640D01*
X173673Y770144D01*
X166991D01*
G01X196691Y776837D02*
X191515D01*
X190681Y777671D01*
X188994D01*
X188335Y777012D01*
Y775730D01*
X187769Y775164D01*
X185277D01*
G01X176123Y775124D02*
X173220D01*
X171507Y776837D01*
X166991D01*
G01X196691Y786877D02*
X194760D01*
X193732Y785849D01*
X190962D01*
X188458Y784176D01*
X186865D01*
X185837Y785204D01*
X185277D01*
G01X176123Y785235D02*
X175395D01*
X174346Y784186D01*
X173402D01*
X171739Y785849D01*
X169876D01*
X168848Y786877D01*
X166991D01*
G01X196691Y783530D02*
X194763D01*
X193734Y784559D01*
X191354D01*
X188850Y782886D01*
X186862D01*
X185834Y781858D01*
X185277D01*
G01X176123Y781835D02*
X175346D01*
X174285Y782896D01*
X172867D01*
X171204Y784559D01*
X169888D01*
X168859Y783530D01*
X166991D01*
G01X196691Y800263D02*
X191515D01*
X190681Y801097D01*
X188994D01*
X188335Y800438D01*
Y799156D01*
X187769Y798590D01*
X185277D01*
G01X176123Y798550D02*
X173220D01*
X171507Y800263D01*
X166991D01*
G01X196691Y793570D02*
X193478D01*
X192661Y794387D01*
X190903D01*
X190069Y793553D01*
X188513D01*
X188007Y794059D01*
Y794656D01*
X187420Y795243D01*
X185277D01*
G01X176123Y795299D02*
X174730D01*
X174169Y794738D01*
Y794066D01*
X173673Y793570D01*
X166991D01*
G01X196691Y813648D02*
X191515D01*
X190681Y814482D01*
X188994D01*
X188335Y813823D01*
Y812541D01*
X187769Y811975D01*
X185277D01*
G01X176123Y811935D02*
X173220D01*
X171507Y813648D01*
X166991D01*
G01X196691Y806955D02*
X193478D01*
X192661Y807772D01*
X190903D01*
X190069Y806938D01*
X188513D01*
X188007Y807444D01*
Y808041D01*
X187420Y808628D01*
X185277D01*
G01X176123Y808684D02*
X174730D01*
X174169Y808123D01*
Y807451D01*
X173673Y806955D01*
X166991D01*
G01X196691Y820341D02*
X194763D01*
X193734Y821370D01*
X191354D01*
X188850Y819697D01*
X186862D01*
X185834Y818669D01*
X185277D01*
G01X176123Y818646D02*
X175346D01*
X174285Y819707D01*
X172867D01*
X171204Y821370D01*
X169888D01*
X168859Y820341D01*
X166991D01*
G01X196691Y837074D02*
X191515D01*
X190681Y837908D01*
X188994D01*
X188335Y837249D01*
Y835967D01*
X187769Y835401D01*
X185277D01*
G01X176123Y835361D02*
X173220D01*
X171507Y837074D01*
X166991D01*
G01X196691Y830381D02*
X193478D01*
X192661Y831198D01*
X190903D01*
X190069Y830364D01*
X188513D01*
X188007Y830870D01*
Y831467D01*
X187420Y832054D01*
X185277D01*
G01X176123Y832110D02*
X174730D01*
X174169Y831549D01*
Y830877D01*
X173673Y830381D01*
X166991D01*
G01X196691Y823688D02*
X194760D01*
X193732Y822660D01*
X190962D01*
X188458Y820987D01*
X186865D01*
X185837Y822015D01*
X185277D01*
G01X176123Y822046D02*
X175395D01*
X174346Y820997D01*
X173402D01*
X171739Y822660D01*
X169876D01*
X168848Y823688D01*
X166991D01*
G01X196691Y850459D02*
X191515D01*
X190681Y851293D01*
X188994D01*
X188335Y850634D01*
Y849352D01*
X187769Y848786D01*
X185277D01*
G01X176123Y848746D02*
X173220D01*
X171507Y850459D01*
X166991D01*
G01X196691Y843766D02*
X193478D01*
X192661Y844583D01*
X190903D01*
X190069Y843749D01*
X188513D01*
X188007Y844255D01*
Y844852D01*
X187420Y845439D01*
X185277D01*
G01X176123Y845495D02*
X174730D01*
X174169Y844934D01*
Y844262D01*
X173673Y843766D01*
X166991D01*
G01X196691Y867192D02*
X193478D01*
X192661Y868009D01*
X190903D01*
X190069Y867175D01*
X188513D01*
X188007Y867681D01*
Y868278D01*
X187420Y868865D01*
X185277D01*
G01X176123Y868921D02*
X174730D01*
X174169Y868360D01*
Y867688D01*
X173673Y867192D01*
X166991D01*
G01X196691Y860499D02*
X194760D01*
X193732Y859471D01*
X190962D01*
X188458Y857798D01*
X186865D01*
X185837Y858826D01*
X185277D01*
G01X176123Y858857D02*
X175395D01*
X174346Y857808D01*
X173402D01*
X171739Y859471D01*
X169876D01*
X168848Y860499D01*
X166991D01*
G01X196691Y857152D02*
X194763D01*
X193734Y858181D01*
X191354D01*
X188850Y856508D01*
X186862D01*
X185834Y855480D01*
X185277D01*
G01X176123Y855457D02*
X175346D01*
X174285Y856518D01*
X172867D01*
X171204Y858181D01*
X169888D01*
X168859Y857152D01*
X166991D01*
G01X196691Y873885D02*
X191515D01*
X190681Y874719D01*
X188994D01*
X188335Y874060D01*
Y872778D01*
X187769Y872212D01*
X185277D01*
G01X176123Y872172D02*
X173220D01*
X171507Y873885D01*
X166991D01*
G01X196691Y880577D02*
X193478D01*
X192661Y881394D01*
X190903D01*
X190069Y880560D01*
X188513D01*
X188007Y881066D01*
Y881663D01*
X187420Y882250D01*
X185277D01*
G01X176123Y882306D02*
X174730D01*
X174169Y881745D01*
Y881073D01*
X173673Y880577D01*
X166991D01*
G01X196691Y887270D02*
X191515D01*
X190681Y888104D01*
X188994D01*
X188335Y887445D01*
Y886163D01*
X187769Y885597D01*
X185277D01*
G01X176123Y885557D02*
X173220D01*
X171507Y887270D01*
X166991D01*
G01X196691Y897310D02*
X194760D01*
X193732Y896282D01*
X190962D01*
X188458Y894609D01*
X186865D01*
X185837Y895637D01*
X185277D01*
G01X176123Y895668D02*
X175395D01*
X174346Y894619D01*
X173402D01*
X171739Y896282D01*
X169876D01*
X168848Y897310D01*
X166991D01*
G01X196691Y893963D02*
X194763D01*
X193734Y894992D01*
X191354D01*
X188850Y893319D01*
X186862D01*
X185834Y892291D01*
X185277D01*
G01X176123Y892268D02*
X175346D01*
X174285Y893329D01*
X172867D01*
X171204Y894992D01*
X169888D01*
X168859Y893963D01*
X166991D01*
G01X196691Y910696D02*
X191515D01*
X190681Y911530D01*
X188994D01*
X188335Y910871D01*
Y909589D01*
X187769Y909023D01*
X185277D01*
G01X176123Y908983D02*
X173220D01*
X171507Y910696D01*
X166991D01*
G01X196691Y904003D02*
X193478D01*
X192661Y904820D01*
X190903D01*
X190069Y903986D01*
X188513D01*
X188007Y904492D01*
Y905089D01*
X187420Y905676D01*
X185277D01*
G01X176123Y905732D02*
X174730D01*
X174169Y905171D01*
Y904499D01*
X173673Y904003D01*
X166991D01*
G01X196691Y924081D02*
X191515D01*
X190681Y924915D01*
X188994D01*
X188335Y924256D01*
Y922974D01*
X187769Y922408D01*
X185277D01*
G01X176123Y922368D02*
X173220D01*
X171507Y924081D01*
X166991D01*
G01X196691Y917389D02*
X193478D01*
X192661Y918206D01*
X190903D01*
X190069Y917372D01*
X188513D01*
X188007Y917878D01*
Y918475D01*
X187420Y919062D01*
X185277D01*
G01X176123Y919118D02*
X174730D01*
X174169Y918557D01*
Y917885D01*
X173673Y917389D01*
X166991D01*
G01X196691Y934121D02*
X194760D01*
X193732Y933093D01*
X190962D01*
X188458Y931420D01*
X186865D01*
X185837Y932448D01*
X185277D01*
G01X176123Y932479D02*
X175395D01*
X174346Y931430D01*
X173402D01*
X171739Y933093D01*
X169876D01*
X168848Y934121D01*
X166991D01*
G01X196691Y930774D02*
X194763D01*
X193734Y931803D01*
X191354D01*
X188850Y930130D01*
X186862D01*
X185834Y929102D01*
X185277D01*
G01X176123Y929079D02*
X175346D01*
X174285Y930140D01*
X172867D01*
X171204Y931803D01*
X169888D01*
X168859Y930774D01*
X166991D01*
G01X196691Y947507D02*
X191515D01*
X190681Y948341D01*
X188994D01*
X188335Y947682D01*
Y946400D01*
X187769Y945834D01*
X185277D01*
G01X176123Y945794D02*
X173220D01*
X171507Y947507D01*
X166991D01*
G01X196691Y940814D02*
X193478D01*
X192661Y941631D01*
X190903D01*
X190069Y940797D01*
X188513D01*
X188007Y941303D01*
Y941900D01*
X187420Y942487D01*
X185277D01*
G01X176123Y942543D02*
X174730D01*
X174169Y941982D01*
Y941310D01*
X173673Y940814D01*
X166991D01*
G01Y964239D02*
X171341D01*
G01X196691Y977625D02*
X193478D01*
X192661Y978442D01*
X190903D01*
X190069Y977608D01*
X188513D01*
X188007Y978114D01*
Y978711D01*
X187420Y979298D01*
X185277D01*
G01X176123Y979354D02*
X174730D01*
X174169Y978793D01*
Y978121D01*
X173673Y977625D01*
X166991D01*
G01X196691Y970932D02*
X193478D01*
X192661Y971749D01*
X190903D01*
X190069Y970915D01*
X188513D01*
X188007Y971421D01*
Y972018D01*
X187420Y972605D01*
X185277D01*
G01X176123Y972661D02*
X174730D01*
X174169Y972100D01*
Y971428D01*
X173673Y970932D01*
X166991D01*
G01X196691Y991011D02*
X193478D01*
X192661Y991828D01*
X190903D01*
X190069Y990994D01*
X188513D01*
X188007Y991500D01*
Y992097D01*
X187420Y992684D01*
X185277D01*
G01X176123Y992740D02*
X174730D01*
X174169Y992179D01*
Y991507D01*
X173673Y991011D01*
X166991D01*
G01X196691Y984318D02*
X193478D01*
X192661Y985135D01*
X190903D01*
X190069Y984301D01*
X188513D01*
X188007Y984807D01*
Y985404D01*
X187420Y985991D01*
X185277D01*
G01X176123Y986047D02*
X174730D01*
X174169Y985486D01*
Y984814D01*
X173673Y984318D01*
X166991D01*
G01Y1021129D02*
X171341D01*
G01X166991Y1024475D02*
X171341D01*
G01X196691Y1031168D02*
X193478D01*
X192661Y1031985D01*
X190903D01*
X190069Y1031151D01*
X188513D01*
X188007Y1031657D01*
Y1032254D01*
X187420Y1032841D01*
X185277D01*
G01X176123Y1032897D02*
X174730D01*
X174169Y1032336D01*
Y1031664D01*
X173673Y1031168D01*
X166991D01*
G01X196691Y1044554D02*
X193478D01*
X192661Y1045371D01*
X190903D01*
X190069Y1044537D01*
X188513D01*
X188007Y1045043D01*
Y1045640D01*
X187420Y1046227D01*
X185277D01*
G01X176123Y1046283D02*
X174730D01*
X174169Y1045722D01*
Y1045050D01*
X173673Y1044554D01*
X166991D01*
G01X196691Y1037861D02*
X193478D01*
X192661Y1038678D01*
X190903D01*
X190069Y1037844D01*
X188513D01*
X188007Y1038350D01*
Y1038947D01*
X187420Y1039534D01*
X185277D01*
G01X176123Y1039590D02*
X174730D01*
X174169Y1039029D01*
Y1038357D01*
X173673Y1037861D01*
X166991D01*
G01Y1051247D02*
X171341D01*
G01X196691Y1071326D02*
X191515D01*
X190681Y1072160D01*
X188994D01*
X188335Y1071501D01*
Y1070219D01*
X187769Y1069653D01*
X185277D01*
G01X176123Y1069613D02*
X173220D01*
X171507Y1071326D01*
X166991D01*
G01X196691Y1064633D02*
X193478D01*
X192661Y1065450D01*
X190903D01*
X190069Y1064616D01*
X188513D01*
X188007Y1065122D01*
Y1065719D01*
X187420Y1066306D01*
X185277D01*
G01X176123Y1066362D02*
X174730D01*
X174169Y1065801D01*
Y1065129D01*
X173673Y1064633D01*
X166991D01*
G01Y1081365D02*
X168848D01*
X169876Y1080337D01*
X171739D01*
X173402Y1078674D01*
X174346D01*
X175402Y1079730D01*
X176123D01*
G01X185277Y1079692D02*
X185837D01*
X186865Y1078664D01*
X188458D01*
X190962Y1080337D01*
X193732D01*
X194760Y1081365D01*
X196691D01*
G01Y1078018D02*
X194763D01*
X193734Y1079047D01*
X191354D01*
X188850Y1077374D01*
X186862D01*
X185834Y1076346D01*
X185277D01*
G01X176123Y1076323D02*
X175346D01*
X174285Y1077384D01*
X172867D01*
X171204Y1079047D01*
X169888D01*
X168859Y1078018D01*
X166991D01*
G01Y1094751D02*
X171507D01*
X173220Y1093038D01*
X176123D01*
G01X185277Y1093078D02*
X187769D01*
X188335Y1093644D01*
Y1094926D01*
X188994Y1095585D01*
X190681D01*
X191515Y1094751D01*
X196691D01*
G01X166991Y1088058D02*
X173673D01*
X174169Y1088554D01*
Y1089226D01*
X174730Y1089787D01*
X176123D01*
G01X185277Y1089731D02*
X187420D01*
X188007Y1089144D01*
Y1088547D01*
X188513Y1088041D01*
X190069D01*
X190903Y1088875D01*
X192661D01*
X193478Y1088058D01*
X196691D01*
G01Y1108137D02*
X191515D01*
X190681Y1108971D01*
X188994D01*
X188335Y1108312D01*
Y1107030D01*
X187769Y1106464D01*
X185277D01*
G01X176123Y1106424D02*
X173220D01*
X171507Y1108137D01*
X166991D01*
G01X196691Y1101444D02*
X193478D01*
X192661Y1102261D01*
X190903D01*
X190069Y1101427D01*
X188513D01*
X188007Y1101933D01*
Y1102530D01*
X187420Y1103117D01*
X185277D01*
G01X176123Y1103173D02*
X174730D01*
X174169Y1102612D01*
Y1101940D01*
X173673Y1101444D01*
X166991D01*
G01X196691Y1124869D02*
X193478D01*
X192661Y1125686D01*
X190903D01*
X190069Y1124852D01*
X188513D01*
X188007Y1125358D01*
Y1125955D01*
X187420Y1126542D01*
X185277D01*
G01X176123Y1126598D02*
X174730D01*
X174169Y1126037D01*
Y1125365D01*
X173673Y1124869D01*
X166991D01*
G01Y1118176D02*
X168848D01*
X169876Y1117148D01*
X171739D01*
X173402Y1115485D01*
X174346D01*
X175402Y1116541D01*
X176123D01*
G01X185277Y1116503D02*
X185837D01*
X186865Y1115475D01*
X188458D01*
X190962Y1117148D01*
X193732D01*
X194760Y1118176D01*
X196691D01*
G01X166991Y1114829D02*
X168859D01*
X169888Y1115858D01*
X171204D01*
X172867Y1114195D01*
X174285D01*
X175346Y1113134D01*
X176123D01*
G01X185277Y1113157D02*
X185834D01*
X186862Y1114185D01*
X188850D01*
X191354Y1115858D01*
X193734D01*
X194763Y1114829D01*
X196691D01*
G01Y1144948D02*
X191515D01*
X190681Y1145782D01*
X188994D01*
X188335Y1145123D01*
Y1143841D01*
X187769Y1143275D01*
X185277D01*
G01X176123Y1143235D02*
X173220D01*
X171507Y1144948D01*
X166991D01*
G01X196691Y1138255D02*
X193478D01*
X192661Y1139072D01*
X190903D01*
X190069Y1138238D01*
X188513D01*
X188007Y1138744D01*
Y1139341D01*
X187420Y1139928D01*
X185277D01*
G01X176123Y1139984D02*
X174730D01*
X174169Y1139423D01*
Y1138751D01*
X173673Y1138255D01*
X166991D01*
G01X196691Y1131562D02*
X191515D01*
X190681Y1132396D01*
X188994D01*
X188335Y1131737D01*
Y1130455D01*
X187769Y1129889D01*
X185277D01*
G01X176123Y1129849D02*
X173220D01*
X171507Y1131562D01*
X166991D01*
G01Y1154987D02*
X168848D01*
X169876Y1153959D01*
X171739D01*
X173402Y1152296D01*
X174346D01*
X175402Y1153352D01*
X176123D01*
G01X185277Y1153314D02*
X185837D01*
X186865Y1152286D01*
X188458D01*
X190962Y1153959D01*
X193732D01*
X194760Y1154987D01*
X196691D01*
G01Y1151641D02*
X194762D01*
X193734Y1152669D01*
X191354D01*
X188850Y1150996D01*
X186862D01*
X185834Y1149968D01*
X185277D01*
G01X176123Y1149945D02*
X175346D01*
X174285Y1151006D01*
X172867D01*
X171204Y1152669D01*
X169888D01*
X168860Y1151641D01*
X166991D01*
G01X196691Y1175066D02*
X193478D01*
X192661Y1175883D01*
X190903D01*
X190069Y1175049D01*
X188513D01*
X188007Y1175555D01*
Y1176152D01*
X187420Y1176739D01*
X185277D01*
G01X176123Y1176795D02*
X174730D01*
X174169Y1176234D01*
Y1175562D01*
X173673Y1175066D01*
X166991D01*
G01X196691Y1168373D02*
X191515D01*
X190681Y1169207D01*
X188994D01*
X188335Y1168548D01*
Y1167266D01*
X187769Y1166700D01*
X185277D01*
G01X176123Y1166660D02*
X173220D01*
X171507Y1168373D01*
X166991D01*
G01X196691Y1161680D02*
X193478D01*
X192661Y1162497D01*
X190903D01*
X190069Y1161663D01*
X188513D01*
X188007Y1162169D01*
Y1162766D01*
X187420Y1163353D01*
X185277D01*
G01X176123Y1163409D02*
X174730D01*
X174169Y1162848D01*
Y1162176D01*
X173673Y1161680D01*
X166991D01*
G01X196691Y1181759D02*
X191515D01*
X190681Y1182593D01*
X188994D01*
X188335Y1181934D01*
Y1180652D01*
X187769Y1180086D01*
X185277D01*
G01X176123Y1180046D02*
X173220D01*
X171507Y1181759D01*
X166991D01*
G01Y1191798D02*
X168848D01*
X169876Y1190770D01*
X171739D01*
X173402Y1189107D01*
X174346D01*
X175402Y1190163D01*
X176123D01*
G01X185277Y1190125D02*
X185837D01*
X186865Y1189097D01*
X188458D01*
X190962Y1190770D01*
X193732D01*
X194760Y1191798D01*
X196691D01*
G01Y1188452D02*
X194762D01*
X193734Y1189480D01*
X191354D01*
X188850Y1187807D01*
X186862D01*
X185834Y1186779D01*
X185277D01*
G01X176123Y1186756D02*
X175346D01*
X174285Y1187817D01*
X172867D01*
X171204Y1189480D01*
X169888D01*
X168860Y1188452D01*
X166991D01*
G01X196691Y1205184D02*
X191515D01*
X190681Y1206018D01*
X188994D01*
X188335Y1205359D01*
Y1204077D01*
X187769Y1203511D01*
X185277D01*
G01X176123Y1203471D02*
X173220D01*
X171507Y1205184D01*
X166991D01*
G01X196691Y1198491D02*
X193478D01*
X192661Y1199308D01*
X190903D01*
X190069Y1198474D01*
X188513D01*
X188007Y1198980D01*
Y1199577D01*
X187420Y1200164D01*
X185277D01*
G01X176123Y1200220D02*
X174730D01*
X174169Y1199659D01*
Y1198987D01*
X173673Y1198491D01*
X166991D01*
G01X196691Y1218570D02*
X191515D01*
X190681Y1219404D01*
X188994D01*
X188335Y1218745D01*
Y1217463D01*
X187769Y1216897D01*
X185277D01*
G01X176123Y1216857D02*
X173220D01*
X171507Y1218570D01*
X166991D01*
G01X196691Y1211877D02*
X193478D01*
X192661Y1212694D01*
X190903D01*
X190069Y1211860D01*
X188513D01*
X188007Y1212366D01*
Y1212963D01*
X187420Y1213550D01*
X185277D01*
G01X176123Y1213606D02*
X174730D01*
X174169Y1213045D01*
Y1212373D01*
X173673Y1211877D01*
X166991D01*
G01X196691Y1228609D02*
X194760D01*
X193732Y1227581D01*
X190962D01*
X188458Y1225908D01*
X186865D01*
X185837Y1226936D01*
X185277D01*
G01X176123Y1226974D02*
X175402D01*
X174346Y1225918D01*
X173402D01*
X171739Y1227581D01*
X169876D01*
X168848Y1228609D01*
X166991D01*
G01X196691Y1225263D02*
X194762D01*
X193734Y1226291D01*
X191354D01*
X188850Y1224618D01*
X186862D01*
X185834Y1223590D01*
X185277D01*
G01X176123Y1223567D02*
X175346D01*
X174285Y1224628D01*
X172867D01*
X171204Y1226291D01*
X169888D01*
X168860Y1225263D01*
X166991D01*
G01X196691Y1241995D02*
X191515D01*
X190681Y1242829D01*
X188994D01*
X188335Y1242170D01*
Y1240888D01*
X187769Y1240322D01*
X185277D01*
G01X176123Y1240282D02*
X173220D01*
X171507Y1241995D01*
X166991D01*
G01X196691Y1235302D02*
X193478D01*
X192661Y1236119D01*
X190903D01*
X190069Y1235285D01*
X188513D01*
X188007Y1235791D01*
Y1236388D01*
X187420Y1236975D01*
X185277D01*
G01X176123Y1237031D02*
X174730D01*
X174169Y1236470D01*
Y1235798D01*
X173673Y1235302D01*
X166991D01*
G01X184899Y780184D02*
X180549D01*
G01X184899Y773491D02*
X180549D01*
G01X184899Y786877D02*
X180549D01*
G01X184899Y796916D02*
X180549D01*
G01X184899Y790223D02*
X180549D01*
G01X184899Y816995D02*
X180549D01*
G01X184899Y810302D02*
X180549D01*
G01X184899Y803609D02*
X180549D01*
G01X184899Y833727D02*
X180549D01*
G01X184899Y823688D02*
X180549D01*
G01X184899Y827034D02*
X180549D01*
G01X184899Y847113D02*
X180549D01*
G01X184899Y840420D02*
X180549D01*
G01X184899Y853806D02*
X180549D01*
G01X184899Y860499D02*
X180549D01*
G01X184899Y863845D02*
X180549D01*
G01X184899Y883924D02*
X180549D01*
G01X184899Y877231D02*
X180549D01*
G01X184899Y870538D02*
X180549D01*
G01X184899Y890617D02*
X180549D01*
G01X184899Y897310D02*
X180549D01*
G01X184899Y900656D02*
X180549D01*
G01X184899Y914042D02*
X180549D01*
G01X184899Y907349D02*
X180549D01*
G01X184899Y927428D02*
X180549D01*
G01X184899Y920735D02*
X180549D01*
G01X184899Y944160D02*
X180549D01*
G01X184899Y934121D02*
X180549D01*
G01X184899Y937467D02*
X180549D01*
G01Y960892D02*
X184899D01*
G01Y950853D02*
X180549D01*
G01Y957546D02*
X184899D01*
G01Y980971D02*
X180549D01*
G01X184899Y974278D02*
X180549D01*
G01Y967585D02*
X184899D01*
G01Y994357D02*
X180549D01*
G01X184899Y987664D02*
X180549D01*
G01X184899Y1027822D02*
X180549D01*
G01X184899Y1021129D02*
X180549D01*
G01X184899Y1041207D02*
X180549D01*
G01X184899Y1034515D02*
X180549D01*
G01X184899Y1061286D02*
X180549D01*
G01X184899Y1047900D02*
X180549D01*
G01Y1054593D02*
X184899D01*
G01Y1074672D02*
X180549D01*
G01X184899Y1067979D02*
X180549D01*
G01X184899Y1091404D02*
X180549D01*
G01X184899Y1081365D02*
X180549D01*
G01X184899Y1084711D02*
X180549D01*
G01X184899Y1098097D02*
X180549D01*
G01X184899Y1111483D02*
X180549D01*
G01X184899Y1104790D02*
X180549D01*
G01X184899Y1128215D02*
X180549D01*
G01X184899Y1118176D02*
X180549D01*
G01X184899Y1121522D02*
X180549D01*
G01X184899Y1141601D02*
X180549D01*
G01X184899Y1134908D02*
X180549D01*
G01X184899Y1148294D02*
X180549D01*
G01X184899Y1154987D02*
X180549D01*
G01X184899Y1158333D02*
X180549D01*
G01X184899Y1171719D02*
X180549D01*
G01X184899Y1165026D02*
X180549D01*
G01X184899Y1185105D02*
X180549D01*
G01X184899Y1178412D02*
X180549D01*
G01X184899Y1191798D02*
X180549D01*
G01X184899Y1208530D02*
X180549D01*
G01X184899Y1201837D02*
X180549D01*
G01X184899Y1195144D02*
X180549D01*
G01X184899Y1221916D02*
X180549D01*
G01X184899Y1215223D02*
X180549D01*
G01X184899Y1238648D02*
X180549D01*
G01X184899Y1228609D02*
X180549D01*
G01X184899Y1231955D02*
X180549D01*
G01X184899Y1245341D02*
X180549D01*
G01X201041Y770144D02*
X196691D01*
G01X201041Y776837D02*
X196691D01*
G01X201041Y786877D02*
X196691D01*
G01X201041Y783530D02*
X196691D01*
G01X201041Y800263D02*
X196691D01*
G01X201041Y793570D02*
X196691D01*
G01X201041Y813648D02*
X196691D01*
G01X201041Y806955D02*
X196691D01*
G01X201041Y830381D02*
X196691D01*
G01X201041Y823688D02*
X196691D01*
G01X201041Y820341D02*
X196691D01*
G01X201041Y850459D02*
X196691D01*
G01X201041Y843766D02*
X196691D01*
G01X201041Y837074D02*
X196691D01*
G01X201041Y867192D02*
X196691D01*
G01X201041Y860499D02*
X196691D01*
G01X201041Y857152D02*
X196691D01*
G01X201041Y873885D02*
X196691D01*
G01X201041Y880577D02*
X196691D01*
G01X201041Y887270D02*
X196691D01*
G01X201041Y897310D02*
X196691D01*
G01X201041Y893963D02*
X196691D01*
G01X201041Y910696D02*
X196691D01*
G01X201041Y904003D02*
X196691D01*
G01X201041Y924081D02*
X196691D01*
G01X201041Y917389D02*
X196691D01*
G01X201041Y930774D02*
X196691D01*
G01X201041Y947507D02*
X196691D01*
G01X201041Y940814D02*
X196691D01*
G01X201041Y934121D02*
X196691D01*
G01Y964239D02*
X201041D01*
G01Y977625D02*
X196691D01*
G01X201041Y970932D02*
X196691D01*
G01X201041Y991011D02*
X196691D01*
G01X201041Y984318D02*
X196691D01*
G01Y1021129D02*
X201141D01*
G01X196691Y1024475D02*
X201141D01*
G01Y1044554D02*
X196691D01*
G01X201141Y1037861D02*
X196691D01*
G01X201141Y1031168D02*
X196691D01*
G01Y1051247D02*
X201141D01*
G01Y1071326D02*
X196691D01*
G01X201141Y1064633D02*
X196691D01*
G01X201141Y1078018D02*
X196691D01*
G01X201141Y1094752D02*
X201140Y1094751D01*
X196691D01*
G01X201141Y1088059D02*
X201140Y1088058D01*
X196691D01*
G01X201141Y1081366D02*
X201140Y1081365D01*
X196691D01*
G01X201141Y1108137D02*
X196691D01*
G01X201141Y1101444D02*
X196691D01*
G01X201041Y1124869D02*
X196691D01*
G01X201141Y1118177D02*
X201140Y1118176D01*
X196691D01*
G01X201141Y1114830D02*
X201140Y1114829D01*
X196691D01*
G01X201141Y1138255D02*
X196691D01*
G01X201041Y1131562D02*
X196691D01*
G01X201141Y1144948D02*
X196691D01*
G01X201141Y1154988D02*
X201140Y1154987D01*
X196691D01*
G01X201141Y1151641D02*
X196691D01*
G01X201141Y1175066D02*
X196691D01*
G01X201141Y1168373D02*
X196691D01*
G01X201141Y1161680D02*
X196691D01*
G01X201141Y1181759D02*
X196691D01*
G01X201141Y1191799D02*
X201140Y1191798D01*
X196691D01*
G01X201141Y1188452D02*
X196691D01*
G01X201141Y1205184D02*
X196691D01*
G01X201141Y1198491D02*
X196691D01*
G01X201141Y1218570D02*
X196691D01*
G01X201141Y1211877D02*
X196691D01*
G01X201141Y1225263D02*
X196691D01*
G01X201141Y1241995D02*
X196691D01*
G01X201141Y1235302D02*
X196691D01*
G01X201141Y1228609D02*
X196691D01*
G01X210249Y780184D02*
X215502D01*
X216495Y781177D01*
X218049D01*
X218928Y780298D01*
Y779120D01*
X219566Y778482D01*
X221965D01*
G01X231119Y778511D02*
X232016D01*
X233689Y780184D01*
X239949D01*
G01X210249Y773491D02*
X215407D01*
X216398Y774482D01*
X217934D01*
X218832Y773584D01*
Y772426D01*
X219482Y771776D01*
X221965D01*
G01X231119Y771817D02*
X231728D01*
X233402Y773491D01*
X239949D01*
G01X210249Y786877D02*
X212409D01*
X213475Y787943D01*
X214494D01*
X218510Y789607D01*
X219410D01*
X220487Y788530D01*
X221965D01*
G01X231119Y788526D02*
X232292D01*
X233370Y789604D01*
X233859D01*
X235639Y787824D01*
X236682D01*
X237629Y786877D01*
X239949D01*
G01X210249Y803609D02*
X214359D01*
X215387Y804637D01*
X218227D01*
X219084Y803780D01*
Y802690D01*
X219884Y801890D01*
X221965D01*
G01X231119Y801936D02*
X231921D01*
X233594Y803609D01*
X239949D01*
G01X210249Y796916D02*
X215407D01*
X216398Y797907D01*
X217936D01*
X218832Y797011D01*
Y795851D01*
X219475Y795208D01*
X221965D01*
G01X231119Y795243D02*
X231921D01*
X233594Y796916D01*
X239949D01*
G01X210249Y790223D02*
X212569D01*
X213559Y789233D01*
X214237D01*
X218253Y790897D01*
X219419D01*
X220444Y791922D01*
X221965D01*
X221966Y791921D01*
G01X231120Y791937D02*
X231125Y791942D01*
X232271D01*
X233319Y790894D01*
X234394D01*
X236174Y789114D01*
X236680D01*
X237789Y790223D01*
X239949D01*
G01X210249Y816995D02*
X215407D01*
X216403Y817991D01*
X217905D01*
X218832Y817064D01*
Y815930D01*
X219473Y815289D01*
X221965D01*
G01X231119Y815321D02*
X231608D01*
X233282Y816995D01*
X239949D01*
G01X210249Y810302D02*
X214359D01*
X215387Y811330D01*
X218241D01*
X219084Y810487D01*
Y809383D01*
X219884Y808583D01*
X221965D01*
G01X231119Y808629D02*
X231921D01*
X233594Y810302D01*
X239949D01*
G01X210249Y833727D02*
X214663D01*
X216170Y835234D01*
X218350D01*
X218832Y834752D01*
Y832662D01*
X219464Y832030D01*
X221965D01*
G01X231119Y832054D02*
X231657D01*
X233330Y833727D01*
X239949D01*
G01X210249Y823688D02*
X212409D01*
X213475Y824754D01*
X214494D01*
X218510Y826418D01*
X219410D01*
X220517Y825311D01*
X221965D01*
G01X231119Y825337D02*
X232292D01*
X233370Y826415D01*
X233859D01*
X235639Y824635D01*
X236682D01*
X237629Y823688D01*
X239949D01*
G01X210249Y827034D02*
X212569D01*
X213559Y826044D01*
X214237D01*
X218253Y827708D01*
X219419D01*
X220444Y828733D01*
X221965D01*
X221966Y828732D01*
G01X231120Y828748D02*
X231125Y828753D01*
X232271D01*
X233319Y827705D01*
X234394D01*
X236174Y825925D01*
X236680D01*
X237789Y827034D01*
X239949D01*
G01X210249Y853806D02*
X215270D01*
X216425Y854961D01*
X217843D01*
X218928Y853876D01*
Y852988D01*
X219829Y852087D01*
X221965D01*
G01X231119Y852133D02*
X232016D01*
X233689Y853806D01*
X239949D01*
G01X210249Y847113D02*
X214722D01*
X215710Y848101D01*
X217842D01*
X218928Y847015D01*
Y846049D01*
X219593Y845384D01*
X221965D01*
G01X231119Y845440D02*
X231669D01*
X233342Y847113D01*
X239949D01*
G01X210249Y840420D02*
X215407D01*
X216218Y841231D01*
X218090D01*
X218832Y840489D01*
Y839355D01*
X219603Y838584D01*
X221965D01*
G01X231119Y838673D02*
X231847D01*
X233594Y840420D01*
X239949D01*
G01X210249Y860499D02*
X212409D01*
X213475Y861565D01*
X214494D01*
X218510Y863229D01*
X219410D01*
X220489Y862150D01*
X221963D01*
X221965Y862152D01*
G01X231119Y862148D02*
X232292D01*
X233370Y863226D01*
X233859D01*
X235639Y861446D01*
X236682D01*
X237629Y860499D01*
X239949D01*
G01X210249Y863845D02*
X212569D01*
X213559Y862855D01*
X214237D01*
X218253Y864519D01*
X219419D01*
X220444Y865544D01*
X221965D01*
G01X231119Y865558D02*
X232277D01*
X233319Y864516D01*
X234394D01*
X236174Y862736D01*
X236680D01*
X237789Y863845D01*
X239949D01*
G01Y883924D02*
X233398D01*
X231724Y882250D01*
X231119D01*
G01X221965Y882225D02*
X219466D01*
X218832Y882859D01*
Y884125D01*
X218142Y884815D01*
X216298D01*
X215407Y883924D01*
X210249D01*
G01Y877231D02*
X214599D01*
X215294Y877926D01*
X217832D01*
X218832Y876926D01*
Y876166D01*
X219493Y875505D01*
X221965D01*
G01X231119Y875507D02*
X231503D01*
X233619Y877623D01*
X236437D01*
X236829Y877231D01*
X239949D01*
G01X210249Y870538D02*
X215407D01*
X216004Y871135D01*
X218072D01*
X218832Y870375D01*
Y869473D01*
X219479Y868826D01*
X221965D01*
G01X231119Y868865D02*
X231396D01*
X233599Y871068D01*
X236178D01*
X236708Y870538D01*
X239949D01*
G01Y890617D02*
X233594D01*
X231920Y888943D01*
X231119D01*
G01X221965Y888921D02*
X219463D01*
X218832Y889552D01*
Y890686D01*
X217910Y891608D01*
X216398D01*
X215407Y890617D01*
X210249D01*
G01X239949Y897310D02*
X237629D01*
X236682Y898257D01*
X235249D01*
X233469Y900037D01*
X232721D01*
X231667Y898983D01*
X231119D01*
G01X221965Y898963D02*
X221199D01*
X220087Y900075D01*
X219057D01*
X214956Y898376D01*
X213475D01*
X212409Y897310D01*
X210249D01*
G01X239949Y900656D02*
X237789D01*
X236680Y899547D01*
X235784D01*
X234004Y901327D01*
X232703D01*
X231700Y902330D01*
X231119D01*
G01X221965Y902385D02*
X221124D01*
X220104Y901365D01*
X218800D01*
X214699Y899666D01*
X213559D01*
X212569Y900656D01*
X210249D01*
G01X239949Y914042D02*
X233594D01*
X231857Y912305D01*
X231119D01*
G01X221965Y912206D02*
X219603D01*
X218832Y912977D01*
Y914111D01*
X217910Y915033D01*
X216398D01*
X215407Y914042D01*
X210249D01*
G01X239949Y907349D02*
X233594D01*
X231863Y905618D01*
X231119D01*
G01X221965Y905513D02*
X219603D01*
X218832Y906284D01*
Y907418D01*
X217910Y908340D01*
X216398D01*
X215407Y907349D01*
X210249D01*
G01Y927428D02*
X210438Y927239D01*
X215782D01*
X216824Y928281D01*
X218042D01*
X218832Y927491D01*
Y926544D01*
X219622Y925754D01*
X220647D01*
G01X232220D02*
X232400D01*
X234074Y927428D01*
X239949D01*
G01X210249Y920735D02*
X216379D01*
X217312Y921668D01*
X218676D01*
X219466Y920878D01*
Y919730D01*
X220134Y919062D01*
X221439D01*
G01X231371D02*
X231873D01*
X233743Y920932D01*
X236508D01*
X236705Y920735D01*
X239949D01*
G01Y950853D02*
X239736Y951066D01*
X233807D01*
X231921Y949180D01*
X231443D01*
G01X221440D02*
X219495D01*
X218832Y949843D01*
Y951244D01*
X218041Y952035D01*
X216589D01*
X215407Y950853D01*
X210249D01*
G01Y944160D02*
X215407D01*
X216595Y945348D01*
X218041D01*
X218832Y944557D01*
Y943323D01*
X219668Y942487D01*
X221235D01*
G01X231460D02*
X231774D01*
X233447Y944160D01*
X239949D01*
G01X210249Y934121D02*
X212409D01*
X213475Y935187D01*
X215598D01*
X217262Y936851D01*
X219408D01*
X220465Y935794D01*
X220599D01*
G01X232157D02*
X232316D01*
X233171Y936649D01*
X233901D01*
X234170Y936537D01*
X235639Y935068D01*
X236682D01*
X237629Y934121D01*
X239949D01*
G01X210249Y937467D02*
X212569D01*
X213559Y936477D01*
X215063D01*
X216727Y938141D01*
X219419D01*
X220419Y939141D01*
X220599D01*
G01X232157D02*
X232316D01*
X233518Y937939D01*
X234158D01*
X234901Y937631D01*
X236174Y936358D01*
X236680D01*
X237789Y937467D01*
X239949D01*
G01X210249Y960892D02*
X214599D01*
G01X210249Y967585D02*
X215326D01*
X216803Y966108D01*
Y964108D01*
X217493Y963418D01*
X219023D01*
X219713Y964108D01*
Y964450D01*
X221144Y965881D01*
X222378D01*
G01X230778Y965876D02*
X231379D01*
X231481Y965978D01*
X235878D01*
G01X244378Y965967D02*
X250757D01*
X250871Y965853D01*
X251978D01*
G01X260578Y965868D02*
X283140D01*
X287926Y967851D01*
G01X210249Y957546D02*
X214599D01*
G01X210249Y980971D02*
X213793D01*
X217348Y984526D01*
X219420D01*
X221126Y982820D01*
X221965D01*
G01X231119Y982644D02*
X232707D01*
X234380Y980971D01*
X239949D01*
G01X210249Y974278D02*
X213856D01*
X217363Y977785D01*
X219564D01*
X221346Y976003D01*
X221965D01*
G01X231119Y975951D02*
X232709D01*
X234382Y974278D01*
X239949D01*
G01X210249Y994357D02*
X215567D01*
X216702Y995492D01*
X218154D01*
X219378Y994268D01*
Y993384D01*
X220181Y992581D01*
X221965D01*
G01X231119Y992684D02*
X231515D01*
X233188Y994357D01*
X239949D01*
G01X210249Y987664D02*
X213678D01*
X217220Y991206D01*
X218607D01*
X220402Y989411D01*
X221965D01*
G01X231119Y989337D02*
X232709D01*
X234382Y987664D01*
X239949D01*
G01X210249Y1027822D02*
X215132D01*
X218678Y1031368D01*
X219878D01*
X220278Y1030968D01*
Y1030095D01*
X220812Y1029561D01*
X221965D01*
G01X231119Y1029495D02*
X231684D01*
X233357Y1027822D01*
X239949D01*
G01X210249Y1021129D02*
X214921D01*
X219875Y1026083D01*
X221965D01*
G01X231119Y1026148D02*
X231420D01*
X236439Y1021129D01*
X239949D01*
G01X210249Y1047900D02*
X215330D01*
X216607Y1049177D01*
X218169D01*
X220078Y1047268D01*
Y1046727D01*
X220753Y1046052D01*
X221965D01*
G01X231119Y1046227D02*
X235088D01*
X236761Y1047900D01*
X239949D01*
G01X210249Y1041207D02*
X215910D01*
X216878Y1042175D01*
Y1043246D01*
X217486Y1043854D01*
X219192D01*
X220103Y1042943D01*
X221965D01*
G01X231119Y1042880D02*
X232053D01*
X233727Y1041206D01*
X233728Y1041207D01*
X239949D01*
G01X210249Y1034515D02*
X216505D01*
X217341Y1035351D01*
Y1036269D01*
X218344Y1037272D01*
X220174D01*
X221155Y1036291D01*
X221965D01*
G01X231119Y1036188D02*
X232053D01*
X233727Y1034514D01*
X233728Y1034515D01*
X239949D01*
G01Y1061286D02*
X233333D01*
X231660Y1059613D01*
X231119D01*
G01X221345D02*
X219529D01*
X218832Y1060310D01*
Y1061355D01*
X217910Y1062277D01*
X213620D01*
X212629Y1061286D01*
X210249D01*
G01Y1054593D02*
X214489D01*
X217655Y1051427D01*
X218838D01*
X220206Y1052795D01*
X222078D01*
G01X230978Y1052838D02*
X231749D01*
X235148Y1056237D01*
X235523D01*
G01X244478Y1056185D02*
X245561D01*
X245928Y1055818D01*
X249513D01*
X249993Y1056298D01*
X251778D01*
G01X261468Y1056266D02*
X269218D01*
X273670Y1054419D01*
X286856Y1041233D01*
X306912Y1032925D01*
X308297Y1031540D01*
X308307Y1031536D01*
X316557Y1023286D01*
G01X210249Y1074672D02*
X213571D01*
X214045Y1075146D01*
X215243D01*
X216033Y1074356D01*
Y1072658D01*
X216980Y1071711D01*
X218098D01*
X219386Y1072999D01*
X220647D01*
G01X232172D02*
X233191D01*
X234376Y1074184D01*
X236101D01*
X236589Y1074672D01*
X239949D01*
G01X210249Y1067979D02*
X213467D01*
X213939Y1068451D01*
X216030D01*
X216740Y1067741D01*
Y1066534D01*
X217479Y1065795D01*
X218642D01*
X219153Y1066306D01*
X221484D01*
G01X231329D02*
X231816D01*
X233489Y1067979D01*
X239949D01*
G01X210249Y1098097D02*
X213591D01*
X214015Y1098521D01*
X215997D01*
X216659Y1097859D01*
Y1096899D01*
X217811Y1095747D01*
X219498D01*
X220175Y1096424D01*
X221582D01*
G01X231268D02*
X232667D01*
X234340Y1098097D01*
X239949D01*
G01X210249Y1091404D02*
X213639D01*
X214108Y1091873D01*
X216032D01*
X217041Y1090864D01*
Y1089288D01*
X217878Y1088451D01*
X219026D01*
X220200Y1089625D01*
X221965D01*
G01X231332Y1089731D02*
X231649D01*
X233322Y1091404D01*
X239949D01*
G01X210249Y1081365D02*
X212409D01*
X213437Y1082393D01*
X214878D01*
X217382Y1084067D01*
X219226D01*
X220255Y1083038D01*
X220616D01*
G01X231278D02*
X231730D01*
X232759Y1084067D01*
X233094D01*
X233778Y1083783D01*
X235168Y1082393D01*
X236769D01*
X237797Y1081365D01*
X239949D01*
G01X210249Y1084711D02*
X212367D01*
X213395Y1083683D01*
X214486D01*
X216990Y1085357D01*
X219301D01*
X220329Y1086385D01*
X220616D01*
G01X231278D02*
X231718D01*
X232746Y1085357D01*
X233351D01*
X234509Y1084877D01*
X235703Y1083683D01*
X236761D01*
X237789Y1084711D01*
X239949D01*
G01X210249Y1111483D02*
X213577D01*
X214395Y1112301D01*
X215559D01*
X216371Y1111489D01*
Y1110150D01*
X216780Y1109741D01*
X221965D01*
G01X231119Y1109810D02*
X233069D01*
X234742Y1111483D01*
X239949D01*
G01X210249Y1104790D02*
X213393D01*
X214239Y1105636D01*
X216007D01*
X216666Y1104977D01*
Y1103681D01*
X217305Y1103042D01*
X221965D01*
G01X231119Y1103117D02*
X231540D01*
X233213Y1104790D01*
X239949D01*
G01X210249Y1128215D02*
X212705D01*
X212706Y1128214D01*
X213698Y1129206D01*
X215210D01*
X216132Y1128284D01*
Y1127150D01*
X216796Y1126486D01*
X221965D01*
G01X231119Y1126542D02*
X231557D01*
X233230Y1128215D01*
X239949D01*
G01X210249Y1118176D02*
X212409D01*
X213437Y1119204D01*
X215613D01*
X218117Y1120878D01*
X219332D01*
X220403Y1119807D01*
X221965D01*
G01X231119Y1119849D02*
X231862D01*
X232891Y1120878D01*
X233922D01*
X235596Y1119204D01*
X236769D01*
X237797Y1118176D01*
X239949D01*
G01X210249Y1121522D02*
X212367D01*
X213395Y1120494D01*
X215221D01*
X217725Y1122168D01*
X219285D01*
X220350Y1123233D01*
X221965D01*
G01X231119Y1123196D02*
X231886D01*
X232914Y1122168D01*
X234457D01*
X236131Y1120494D01*
X236761D01*
X237789Y1121522D01*
X239949D01*
G01X210249Y1141601D02*
X212705D01*
X212706Y1141600D01*
X213698Y1142592D01*
X215210D01*
X216132Y1141670D01*
Y1140536D01*
X216808Y1139860D01*
X221965D01*
G01X231119Y1139928D02*
X231690D01*
X233363Y1141601D01*
X239949D01*
G01X210249Y1134908D02*
X212705D01*
X212706Y1134907D01*
X213698Y1135899D01*
X215210D01*
X216132Y1134977D01*
Y1133843D01*
X216801Y1133174D01*
X221965D01*
G01X231119Y1133177D02*
X232612D01*
X234343Y1134908D01*
X239949D01*
G01X210249Y1148294D02*
X215502D01*
X216494Y1149286D01*
X218006D01*
X218928Y1148364D01*
Y1147230D01*
X219637Y1146521D01*
X221965D01*
G01X231119Y1146579D02*
X232549D01*
X233684Y1147714D01*
X235977D01*
X236557Y1148294D01*
X239949D01*
G01X210249Y1154987D02*
X212409D01*
X213437Y1156015D01*
X215613D01*
X218117Y1157689D01*
X219332D01*
X220403Y1156618D01*
X221965D01*
G01X231119Y1156623D02*
X232429D01*
X233495Y1157689D01*
X233922D01*
X235596Y1156015D01*
X236769D01*
X237797Y1154987D01*
X239949D01*
G01X210249Y1158333D02*
X212367D01*
X213395Y1157305D01*
X215221D01*
X217725Y1158979D01*
X219285D01*
X220350Y1160044D01*
X221965D01*
G01X231119Y1160036D02*
X232417D01*
X233474Y1158979D01*
X234457D01*
X236131Y1157305D01*
X236761D01*
X237789Y1158333D01*
X239949D01*
G01Y1178412D02*
X233361D01*
X231688Y1176739D01*
X231119D01*
G01X221965Y1176657D02*
X216822D01*
X216132Y1177347D01*
Y1178481D01*
X215210Y1179403D01*
X213698D01*
X212706Y1178411D01*
X212705Y1178412D01*
X210249D01*
G01Y1171719D02*
X212705D01*
X212706Y1171718D01*
X213698Y1172710D01*
X215210D01*
X216132Y1171788D01*
Y1170654D01*
X216772Y1170014D01*
X221965D01*
G01X231119Y1170046D02*
X232483D01*
X234156Y1171719D01*
X239949D01*
G01X210249Y1165026D02*
X212705D01*
X212706Y1165025D01*
X213698Y1166017D01*
X215210D01*
X216132Y1165095D01*
Y1164062D01*
X216921Y1163273D01*
X221965D01*
G01X231119Y1163353D02*
X231680D01*
X233353Y1165026D01*
X239949D01*
G01Y1185105D02*
X236385D01*
X235632Y1184352D01*
X232824D01*
X231904Y1183432D01*
X231119D01*
G01X221965Y1183350D02*
X216822D01*
X216132Y1184040D01*
Y1185174D01*
X215210Y1186096D01*
X213698D01*
X212706Y1185104D01*
X212705Y1185105D01*
X210249D01*
G01X239949Y1191798D02*
X237797D01*
X236769Y1192826D01*
X235168D01*
X233494Y1194500D01*
X232759D01*
X231730Y1193471D01*
X231119D01*
G01X221965Y1193429D02*
X221161D01*
X220090Y1194500D01*
X217964D01*
X215460Y1192826D01*
X213437D01*
X212409Y1191798D01*
X210249D01*
G01X239949Y1208530D02*
X235253D01*
X233580Y1206857D01*
X231119D01*
G01X221965Y1206811D02*
X216887D01*
X216132Y1207566D01*
Y1208599D01*
X215210Y1209521D01*
X213698D01*
X212706Y1208529D01*
X212705Y1208530D01*
X210249D01*
G01X239949Y1201837D02*
X233253D01*
X231580Y1200164D01*
X231119D01*
G01X221965Y1200132D02*
X216874D01*
X216132Y1200874D01*
Y1201906D01*
X215210Y1202828D01*
X213698D01*
X212706Y1201836D01*
X212705Y1201837D01*
X210249D01*
G01X239949Y1195144D02*
X237789D01*
X236761Y1194116D01*
X235703D01*
X234029Y1195790D01*
X232746D01*
X231718Y1196818D01*
X231119D01*
G01X221965Y1196855D02*
X221106D01*
X220041Y1195790D01*
X217572D01*
X215068Y1194116D01*
X213395D01*
X212367Y1195144D01*
X210249D01*
G01Y1221916D02*
X212705D01*
X212706Y1221915D01*
X213698Y1222907D01*
X215210D01*
X216132Y1221985D01*
Y1220952D01*
X216995Y1220089D01*
X221965D01*
G01X231119Y1220243D02*
X232353D01*
X233133Y1221023D01*
X235346D01*
X236239Y1221916D01*
X239949D01*
G01X210249Y1215223D02*
X212705D01*
X212706Y1215222D01*
X213698Y1216214D01*
X215210D01*
X216132Y1215292D01*
Y1214259D01*
X216871Y1213520D01*
X221965D01*
G01X231119Y1213550D02*
X231728D01*
X233401Y1215223D01*
X239949D01*
G01X210249Y1238648D02*
X212705D01*
X212706Y1238647D01*
X213698Y1239639D01*
X215210D01*
X216132Y1238717D01*
Y1237583D01*
X216805Y1236910D01*
X221965D01*
G01X231119Y1236951D02*
X232325D01*
X234022Y1238648D01*
X239949D01*
G01X210249Y1228609D02*
X212409D01*
X213437Y1229637D01*
X215634D01*
X218138Y1231311D01*
X219332D01*
X220403Y1230240D01*
X221965D01*
G01X231119Y1230245D02*
X232429D01*
X233495Y1231311D01*
X233922D01*
X235596Y1229637D01*
X236769D01*
X237797Y1228609D01*
X239949D01*
G01X210249Y1231955D02*
X212367D01*
X213395Y1230927D01*
X215242D01*
X217746Y1232601D01*
X219285D01*
X220350Y1233666D01*
X221965D01*
G01X231119Y1233658D02*
X232417D01*
X233474Y1232601D01*
X234457D01*
X236131Y1230927D01*
X236761D01*
X237789Y1231955D01*
X239949D01*
G01Y1245341D02*
X234240D01*
X232567Y1243668D01*
X231119D01*
G01X221965Y1243587D02*
X216922D01*
X216132Y1244377D01*
Y1245410D01*
X215210Y1246332D01*
X213698D01*
X212707Y1245341D01*
X210249D01*
G01X226391Y770144D02*
X226392Y770143D01*
X232647D01*
X234374Y771870D01*
X235523D01*
G01X244677Y771817D02*
X246425D01*
X246778Y771464D01*
Y769925D01*
X247278Y769425D01*
X251865D01*
X252584Y770144D01*
X256091D01*
G01X336093Y842652D02*
Y825694D01*
X334588Y822061D01*
X295422Y782895D01*
X287202Y779490D01*
X262469D01*
X261489Y778510D01*
X260778D01*
G01X251578Y778475D02*
X249060D01*
X247351Y780184D01*
X239949D01*
G01X341131Y842652D02*
Y824693D01*
X338859Y819209D01*
X298274Y778624D01*
X286712Y773835D01*
X263686D01*
X261668Y771817D01*
X260778D01*
G01X251678Y771792D02*
X250446D01*
X248747Y773491D01*
X239949D01*
G01X226391Y776837D02*
X232648D01*
X234398Y778587D01*
X235523D01*
G01X244677Y778535D02*
X246400D01*
X246778Y778157D01*
Y776618D01*
X247278Y776118D01*
X251887D01*
X252606Y776837D01*
X256091D01*
G01X329764Y842652D02*
Y828036D01*
X329437Y827246D01*
X327762Y825571D01*
Y824878D01*
X326085Y823201D01*
X325392D01*
X323715Y821524D01*
Y820831D01*
X322039Y819155D01*
X321346D01*
X319671Y817480D01*
Y816787D01*
X317994Y815110D01*
X317301D01*
X315626Y813435D01*
Y812742D01*
X313949Y811065D01*
X313256D01*
X311581Y809390D01*
Y808697D01*
X309904Y807020D01*
X309211D01*
X291845Y789654D01*
X262354D01*
X261250Y788550D01*
X260778D01*
G01X251878Y788483D02*
X250346D01*
X250012Y788817D01*
Y789545D01*
X249763Y789794D01*
X248731D01*
X244072Y787864D01*
X242878D01*
X241890Y786876D01*
X241889Y786877D01*
X239949D01*
G01X226391D02*
X228304D01*
X229332Y785849D01*
X231139D01*
X232819Y784169D01*
X233727D01*
X234790Y785232D01*
X235523D01*
G01X244677Y785204D02*
X245329D01*
X246317Y784216D01*
X247787D01*
X250231Y785849D01*
X253080D01*
X254108Y786877D01*
X256091D01*
G01X226391Y783530D02*
X228259D01*
X229288Y784559D01*
X230604D01*
X232284Y782879D01*
X233712D01*
X234759Y781832D01*
X235523D01*
G01X244677Y781858D02*
X245162D01*
X246230Y782926D01*
X248179D01*
X250623Y784559D01*
X253174D01*
X254203Y783530D01*
X256091D01*
G01X323433Y842652D02*
Y830191D01*
X307574Y814332D01*
X306456D01*
X305130Y815658D01*
X304012D01*
X303150Y814796D01*
Y813678D01*
X304476Y812352D01*
Y811234D01*
X303614Y810372D01*
X302496D01*
X301255Y811613D01*
X300137D01*
X299275Y810751D01*
Y809633D01*
X300516Y808392D01*
Y807274D01*
X299654Y806412D01*
X298536D01*
X296859Y808089D01*
X295741D01*
X283722Y796070D01*
X264262D01*
X263516Y796816D01*
X263035D01*
X261185Y798666D01*
X260678D01*
G01X251878Y798658D02*
X251152D01*
X249221Y798004D01*
X244231Y796916D01*
X239949D01*
G01X226391Y800263D02*
X232987D01*
X234734Y802010D01*
X235509D01*
X235523Y801996D01*
G01X244677Y801936D02*
X246112D01*
X246641Y801407D01*
Y800030D01*
X247143Y799528D01*
X248610D01*
X249345Y800263D01*
X256091D01*
G01X226391Y793570D02*
X233016D01*
X234752Y795306D01*
X235523D01*
G01X244677Y795379D02*
X245602D01*
X247726Y793255D01*
X249396D01*
X251057Y794916D01*
X252481D01*
X253828Y793569D01*
X253829Y793570D01*
X256091D01*
G01X328474Y842652D02*
Y828293D01*
X328343Y827977D01*
X291310Y790944D01*
X262242D01*
X261264Y791922D01*
X260678D01*
G01X251978Y791953D02*
X250826D01*
X249952Y791079D01*
X249947Y791084D01*
X248474D01*
X243815Y789154D01*
X242964D01*
X241895Y790223D01*
X239949D01*
G01X309285Y844376D02*
X283913Y819004D01*
X265754D01*
X261924Y815174D01*
X260778D01*
G01X251578Y815157D02*
X249945D01*
X248107Y816995D01*
X239949D01*
G01X312003Y839971D02*
X284442Y812410D01*
X266520D01*
X262638Y808528D01*
X260678D01*
G01X251578Y808569D02*
X249059D01*
X248733Y808895D01*
Y809986D01*
X248176Y810543D01*
X244081D01*
X243840Y810302D01*
X239949D01*
G01X226391Y813648D02*
X232303D01*
X234043Y815388D01*
X235523D01*
G01X244677Y815351D02*
X246294D01*
X247080Y814565D01*
Y813428D01*
X247825Y812683D01*
X251180D01*
X252145Y813648D01*
X256091D01*
G01X226391Y806955D02*
X232987D01*
X234734Y808702D01*
X235509D01*
X235523Y808688D01*
G01X244677Y808628D02*
X246112D01*
X246641Y808099D01*
Y806825D01*
X247367Y806099D01*
X248489D01*
X249345Y806955D01*
X256091D01*
G01X318397Y842653D02*
Y837868D01*
X283978Y803449D01*
X282851D01*
X281314Y804986D01*
X280094D01*
X279304Y804196D01*
Y802002D01*
X278514Y801212D01*
X277294D01*
X276504Y802002D01*
Y804196D01*
X275714Y804986D01*
X274494D01*
X273704Y804196D01*
Y802002D01*
X272914Y801212D01*
X271694D01*
X270904Y802002D01*
Y804196D01*
X270114Y804986D01*
X268894D01*
X268104Y804196D01*
Y802002D01*
X267314Y801212D01*
X266341D01*
X265040Y802513D01*
X262276D01*
X262090Y802435D01*
X260783Y801889D01*
X260478D01*
G01X251778Y801875D02*
X249060D01*
X247326Y803609D01*
X239949D01*
G01X226391Y820341D02*
X228259D01*
X229288Y821370D01*
X230194D01*
X231874Y819690D01*
X233004D01*
X234088Y818606D01*
X235523D01*
G01X244677Y818627D02*
X246044D01*
X247123Y819706D01*
X248952D01*
X251442Y821370D01*
X253174D01*
X254203Y820341D01*
X256091D01*
G01X239949Y833727D02*
X241894D01*
X241895Y833726D01*
X243163Y834994D01*
X245960D01*
X247228Y833726D01*
X249156D01*
X250872Y832010D01*
X252078D01*
G01X260478Y832028D02*
X261269D01*
X262856Y833615D01*
X271881D01*
X278495Y840229D01*
X280549D01*
X282588Y838190D01*
X283706D01*
X284568Y839052D01*
Y840170D01*
X283490Y841248D01*
Y842366D01*
X284352Y843228D01*
X285470D01*
X286422Y842276D01*
X287836D01*
X303768Y858208D01*
G01X226391Y830381D02*
X232436D01*
X234170Y832115D01*
X235523D01*
G01X244677Y832054D02*
X245772D01*
X246226Y831600D01*
Y830271D01*
X246940Y829557D01*
X248005D01*
X248829Y830381D01*
X256091D01*
G01X305774Y851200D02*
X304100Y849526D01*
Y848833D01*
X302423Y847156D01*
X301730D01*
X300055Y845481D01*
Y844788D01*
X298378Y843111D01*
X297685D01*
X296010Y841436D01*
Y840743D01*
X294333Y839066D01*
X293640D01*
X291965Y837391D01*
Y836698D01*
X290288Y835021D01*
X289595D01*
X287920Y833346D01*
Y832653D01*
X286243Y830976D01*
X285550D01*
X283875Y829301D01*
Y828608D01*
X282198Y826931D01*
X281505D01*
X280902Y826328D01*
X278532D01*
X278042Y825838D01*
X275672D01*
X275182Y826328D01*
X272812D01*
X272322Y825838D01*
X269952D01*
X269462Y826328D01*
X263183D01*
X262185Y825330D01*
X260678D01*
G01X251878Y825324D02*
X250188D01*
X249086Y826426D01*
X247744D01*
X243765Y824778D01*
X242981D01*
X241890Y823687D01*
X241889Y823688D01*
X239949D01*
G01X226391D02*
X228304D01*
X229332Y822660D01*
X230729D01*
X232409Y820980D01*
X232953D01*
X234046Y822073D01*
X235523D01*
G01X244677D02*
X246077D01*
X247154Y820996D01*
X248560D01*
X251050Y822660D01*
X253080D01*
X254108Y823688D01*
X256091D01*
G01X304861Y852112D02*
X280367Y827618D01*
X263211D01*
X262044Y828785D01*
X260578D01*
G01X251878Y828743D02*
X250118D01*
X249091Y827716D01*
X247487D01*
X243508Y826068D01*
X242861D01*
X241895Y827034D01*
X239949D01*
G01X300945Y891198D02*
Y891195D01*
X297139Y887389D01*
X292290D01*
X290141Y885240D01*
Y870479D01*
X265067Y845405D01*
X260578D01*
G01X251878Y845395D02*
X249069D01*
X247351Y847113D01*
X239949D01*
G01X226391Y850459D02*
X232648D01*
X234361Y852172D01*
X235523D01*
G01X244677Y852132D02*
X246249D01*
X246653Y851728D01*
Y850365D01*
X247354Y849664D01*
X248595D01*
X249390Y850459D01*
X256091D01*
G01X226391Y843766D02*
X232689D01*
X234420Y845497D01*
X235523D01*
G01X244677Y845439D02*
X246254D01*
X246732Y844961D01*
Y843546D01*
X247232Y843046D01*
X251705D01*
X252425Y843766D01*
X256091D01*
G01X297521Y864121D02*
X294664D01*
X294109Y863566D01*
Y862448D01*
X296894Y859663D01*
Y858545D01*
X296032Y857683D01*
X294914D01*
X292129Y860468D01*
X291011D01*
X269817Y839274D01*
X261748D01*
X261179Y838705D01*
X260578D01*
G01X251878Y838693D02*
X249078D01*
X247351Y840420D01*
X239949D01*
G01X226391Y837074D02*
X232823D01*
X234551Y838802D01*
X235523D01*
G01X244677Y838768D02*
X246228D01*
X246732Y838264D01*
Y836854D01*
X247232Y836354D01*
X251819D01*
X252539Y837074D01*
X256091D01*
G01X226391Y867192D02*
X232017D01*
X234026Y869201D01*
X235523D01*
G01X244677Y868965D02*
X246278D01*
X246877Y868366D01*
Y867600D01*
X247656Y866821D01*
X248974D01*
X249891Y867738D01*
X251722D01*
X252268Y867192D01*
X256091D01*
G01X300523Y897018D02*
X289161D01*
X284850Y892707D01*
Y872527D01*
X268636Y856313D01*
X267378D01*
X265586Y854521D01*
Y853263D01*
X264419Y852096D01*
X260578D01*
G01X251878Y852095D02*
X249062D01*
X247351Y853806D01*
X239949D01*
G01X300123Y904400D02*
X297753D01*
X297263Y903910D01*
X294893D01*
X294403Y904400D01*
X292033D01*
X291543Y903910D01*
X289173D01*
X288683Y904400D01*
X286109D01*
X284434Y902725D01*
Y902032D01*
X282757Y900355D01*
X282064D01*
X280389Y898680D01*
Y897987D01*
X278712Y896310D01*
X278019D01*
X277341Y895632D01*
Y893262D01*
X277831Y892772D01*
Y890402D01*
X277341Y889912D01*
Y887542D01*
X277831Y887052D01*
Y884682D01*
X277341Y884192D01*
Y881822D01*
X277831Y881332D01*
Y878962D01*
X277341Y878472D01*
Y875590D01*
X275666Y873915D01*
Y873222D01*
X273989Y871545D01*
X273296D01*
X271621Y869870D01*
Y869177D01*
X269944Y867500D01*
X269251D01*
X264952Y863201D01*
X263108D01*
X262045Y862138D01*
X260778D01*
G01X251578Y862146D02*
X250079D01*
X248986Y863239D01*
X247991D01*
X243952Y861566D01*
X242958D01*
X241890Y860498D01*
X241889Y860499D01*
X239949D01*
G01X226391D02*
X228304D01*
X229332Y859471D01*
X230719D01*
X232399Y857791D01*
X232971D01*
X234034Y858854D01*
X235523D01*
G01X244677Y858859D02*
X245954D01*
X246960Y857853D01*
X248156D01*
X250688Y859545D01*
X253154D01*
X254108Y860499D01*
X256091D01*
G01X300137Y905690D02*
X285574D01*
X276051Y896167D01*
Y876125D01*
X264417Y864491D01*
X263042D01*
X261985Y865548D01*
X260819D01*
G01X251678Y865543D02*
X249995D01*
X248981Y864529D01*
X247734D01*
X243695Y862856D01*
X242884D01*
X241895Y863845D01*
X239949D01*
G01X226391Y857152D02*
X228259D01*
X229288Y858181D01*
X230184D01*
X231864Y856501D01*
X232942D01*
X233985Y855458D01*
X235523D01*
G01X244677Y855450D02*
X245854D01*
X246967Y856563D01*
X248548D01*
X251080Y858255D01*
X253100D01*
X254203Y857152D01*
X256091D01*
G01X226391Y873885D02*
X232607D01*
X234624Y875902D01*
X235523D01*
G01X244677Y875628D02*
X245739D01*
X246418Y874949D01*
Y873979D01*
X247232Y873165D01*
X248353D01*
X249073Y873885D01*
X256091D01*
G01X244299Y883924D02*
X239949D01*
G01X256091Y880577D02*
X250809D01*
X249865Y879633D01*
X247772D01*
X246732Y880673D01*
Y881749D01*
X246228Y882253D01*
X244677D01*
G01X235523Y882319D02*
X234289D01*
X232547Y880577D01*
X226391D01*
G01X306324Y917756D02*
X276064D01*
X262630Y904322D01*
Y877006D01*
X261107Y875483D01*
X260578D01*
G01X251878Y875526D02*
X250919D01*
X250527Y875918D01*
X248298D01*
X246985Y877231D01*
X239949D01*
G01Y870538D02*
X244231D01*
X248145Y871391D01*
X250696Y872256D01*
X251878D01*
G01X260815Y872215D02*
X261215D01*
X262125Y871305D01*
X264087D01*
X267784Y875002D01*
Y895778D01*
X269299Y897293D01*
Y898411D01*
X268134Y899576D01*
Y900694D01*
X268996Y901556D01*
X270114D01*
X271279Y900391D01*
X272397D01*
X283400Y911394D01*
X288488D01*
X289686Y912592D01*
X291288D01*
X292486Y911394D01*
X294088D01*
X295286Y912592D01*
X296888D01*
X298086Y911394D01*
X300523D01*
G01X244299Y890617D02*
X239949D01*
G01X256091Y887270D02*
X250201D01*
X249328Y886397D01*
X247385D01*
X246732Y887050D01*
Y888442D01*
X246230Y888944D01*
X244677D01*
G01X235523Y889011D02*
X234430D01*
X232687Y887268D01*
X232685Y887270D01*
X226391D01*
G01X244299Y897310D02*
X239949D01*
G01X256091D02*
X254108D01*
X253080Y896282D01*
X250745D01*
X248387Y894707D01*
X246259D01*
X245329Y895637D01*
X244677D01*
G01X235523Y895727D02*
X234824D01*
X233729Y894632D01*
X232789D01*
X231139Y896282D01*
X229332D01*
X228304Y897310D01*
X226391D01*
G01X244299Y900656D02*
X239949D01*
G01X256091Y893963D02*
X254203D01*
X253174Y894992D01*
X251137D01*
X248779Y893417D01*
X246288D01*
X245162Y892291D01*
X244677D01*
G01X235523Y892245D02*
X234779D01*
X233682Y893342D01*
X232254D01*
X230604Y894992D01*
X229288D01*
X228259Y893963D01*
X226391D01*
G01Y917389D02*
X229835D01*
X230075Y917149D01*
X232708D01*
X234621Y919062D01*
X235033D01*
G01X244909D02*
X246231D01*
X246732Y918561D01*
Y917687D01*
X247903Y916516D01*
X249756D01*
X250629Y917389D01*
X256091D01*
G01X244299Y914042D02*
X239949D01*
G01X244299Y907349D02*
X239949D01*
G01X256091Y910696D02*
X250201D01*
X249328Y909823D01*
X247385D01*
X246732Y910476D01*
Y911868D01*
X246231Y912369D01*
X244677D01*
G01X235523Y912404D02*
X234646D01*
X232938Y910696D01*
X226391D01*
G01X256091Y904003D02*
X250201D01*
X249328Y903130D01*
X247385D01*
X246732Y903783D01*
Y905175D01*
X246231Y905676D01*
X244677D01*
G01X235523Y905756D02*
X234477D01*
X232724Y904003D01*
X226391D01*
G01X317146Y937992D02*
X304757D01*
X298279Y931514D01*
X270651D01*
X268845Y929708D01*
X264907D01*
X263144Y927945D01*
Y926178D01*
X262720Y925754D01*
X261944D01*
G01X250308D02*
X249025D01*
X247351Y927428D01*
X239949D01*
G01X316486Y932782D02*
X307087D01*
X298105Y923800D01*
X268185D01*
X263447Y919062D01*
X261103D01*
G01X251084D02*
X249024D01*
X247351Y920735D01*
X239949D01*
G01X226391Y924081D02*
X233002D01*
X234675Y925754D01*
X234978D01*
G01X244934D02*
X246231D01*
X246732Y925253D01*
Y923861D01*
X247385Y923208D01*
X249328D01*
X250201Y924081D01*
X256091D01*
G01X226391Y934121D02*
X228304D01*
X229332Y933093D01*
X231139D01*
X232633Y931599D01*
X233082Y931413D01*
X233727D01*
X234762Y932448D01*
X235035D01*
G01X245688D02*
X246135D01*
X247154Y931429D01*
X248560D01*
X251050Y933093D01*
X253080D01*
X254108Y934121D01*
X256091D01*
G01X226391Y930774D02*
X228259D01*
X229288Y931803D01*
X230604D01*
X231902Y930505D01*
X232825Y930123D01*
X233712D01*
X234734Y929101D01*
X235035D01*
G01X245688D02*
X246085D01*
X247123Y930139D01*
X248952D01*
X251442Y931803D01*
X253174D01*
X254203Y930774D01*
X256091D01*
G01X321624Y953659D02*
X294268D01*
X291782Y951173D01*
X279600Y946126D01*
X265330D01*
X262962Y943758D01*
Y943310D01*
X262139Y942487D01*
X261056D01*
G01X251211D02*
X250132D01*
X247665Y944954D01*
X245907D01*
X245113Y944160D01*
X239949D01*
G01X226391Y947507D02*
X233190D01*
X234866Y949183D01*
X235011D01*
G01X244935Y949180D02*
X246378D01*
X246732Y948826D01*
Y947287D01*
X247232Y946787D01*
X249041D01*
X249761Y947507D01*
X256091D01*
G01X226391Y940814D02*
X232414D01*
X234087Y942487D01*
X234312D01*
G01X245775D02*
X246268D01*
X246978Y941777D01*
Y940384D01*
X247387Y939975D01*
X248506D01*
X249345Y940814D01*
X256091D01*
G01X318824Y945325D02*
X316454D01*
X315964Y944835D01*
X313594D01*
X313104Y945325D01*
X310734D01*
X310244Y944835D01*
X307874D01*
X307384Y945325D01*
X305014D01*
X304524Y944835D01*
X302154D01*
X301664Y945325D01*
X295791D01*
X293062Y944195D01*
X292799Y943561D01*
X290608Y942653D01*
X289968Y942918D01*
X287779Y942012D01*
X287514Y941372D01*
X285323Y940464D01*
X284683Y940730D01*
X281981Y939611D01*
X280097D01*
X279607Y939121D01*
X277237D01*
X276747Y939611D01*
X274377D01*
X273887Y939121D01*
X271517D01*
X271027Y939611D01*
X268657D01*
X266896Y937850D01*
X263914D01*
X262983Y936919D01*
Y936550D01*
X262227Y935794D01*
X261880D01*
G01X250324D02*
X250117D01*
X249050Y936861D01*
X247138D01*
X245465Y935188D01*
X242958D01*
X241890Y934120D01*
X241889Y934121D01*
X239949D01*
G01Y937467D02*
X241895D01*
X242884Y936478D01*
X244930D01*
X246603Y938151D01*
X249170D01*
X250159Y939140D01*
X250324D01*
G01X261880D02*
X266361D01*
X268122Y940901D01*
X281724D01*
X292073Y945188D01*
X292079Y945185D01*
X295534Y946615D01*
X318824D01*
G01X239949Y960892D02*
X244299D01*
G01X321624Y960847D02*
X293397D01*
X287802Y955252D01*
X280048Y952039D01*
X264067D01*
X261208Y949180D01*
X261040D01*
G01X251164D02*
X249024D01*
X247351Y950853D01*
X239949D01*
G01X288733Y962553D02*
X280684Y959219D01*
X260778D01*
G01X251228D02*
X247759D01*
X247070Y959908D01*
Y960971D01*
X245476Y962565D01*
X244617D01*
G01X235878Y962506D02*
X233691D01*
X231958Y964239D01*
X226391D01*
G01X239949Y957546D02*
X244299D01*
G01X291921Y977647D02*
X284725Y984843D01*
X264127D01*
X262008Y982724D01*
X260578D01*
G01X251878Y982681D02*
X249583D01*
X247872Y980970D01*
X247871Y980971D01*
X239949D01*
G01X226391Y977625D02*
X232999D01*
X233000Y977624D01*
X234740Y979364D01*
X235523D01*
G01X244677Y979298D02*
X246058D01*
X246538Y978818D01*
Y977938D01*
X247118Y977358D01*
X248238D01*
X249338Y978458D01*
X252001D01*
X252834Y977625D01*
X256091D01*
G01X287337Y974962D02*
X285721Y976578D01*
X266499D01*
X265936Y976015D01*
X260578D01*
G01X251878Y975982D02*
X250983D01*
X249279Y974278D01*
X239949D01*
G01X287406Y970464D02*
X283177Y968711D01*
X262610D01*
X262020Y969301D01*
X260578D01*
G01X251878Y969349D02*
X246338D01*
X244573Y967584D01*
X244572Y967585D01*
X239949D01*
G01X226391Y970932D02*
X230078D01*
X231011Y969999D01*
X232658D01*
X233478Y970819D01*
Y972019D01*
X234097Y972638D01*
X235523D01*
G01X244677Y972605D02*
X250536D01*
X252209Y970932D01*
X256091D01*
G01X301508Y982736D02*
X285804Y998440D01*
X261700D01*
X260084Y996824D01*
X246828D01*
X244361Y994357D01*
X239949D01*
G01X226391Y991011D02*
X233021D01*
X234771Y992761D01*
X235523D01*
G01X244677Y992684D02*
X245878D01*
X246588Y991974D01*
Y991375D01*
X247298Y990665D01*
X248595D01*
X249908Y991978D01*
X251864D01*
X252831Y991011D01*
X256091D01*
G01X296838Y980066D02*
X285106Y991798D01*
X263839D01*
X261378Y989337D01*
X260778D01*
G01X251578Y989422D02*
X249768D01*
X248010Y987664D01*
X239949D01*
G01X226391Y984318D02*
X231228D01*
X231808Y984898D01*
Y985582D01*
X232294Y986068D01*
X235523D01*
G01X244677Y985991D02*
X245806D01*
X247207Y984590D01*
X249339D01*
X250639Y985890D01*
X252226D01*
X253798Y984318D01*
X256091D01*
G01X330625Y984495D02*
X327483D01*
X321215Y990762D01*
X319525Y993291D01*
X311643Y1001174D01*
X286652D01*
X265849Y1006025D01*
X265261Y1005659D01*
X262952Y1006197D01*
X262586Y1006786D01*
X260278Y1007324D01*
X259690Y1006958D01*
X257381Y1007496D01*
X257015Y1008085D01*
X254707Y1008623D01*
X254119Y1008257D01*
X251810Y1008795D01*
X251444Y1009384D01*
X249136Y1009922D01*
X248548Y1009557D01*
X246238Y1010095D01*
X245873Y1010684D01*
X243565Y1011222D01*
X242976Y1010856D01*
X240667Y1011395D01*
X240301Y1011984D01*
X235635Y1013072D01*
X233368Y1015337D01*
X232871Y1016540D01*
X232501Y1017434D01*
Y1020247D01*
X230541Y1022207D01*
X229587D01*
X228509Y1021129D01*
X226391D01*
G01X330625Y985785D02*
X328018D01*
X322218Y991585D01*
X320528Y994114D01*
X312178Y1002464D01*
X286801D01*
X236287Y1014245D01*
X234463Y1016068D01*
X234268Y1016540D01*
X233791Y1017691D01*
Y1020782D01*
X231076Y1023497D01*
X229519D01*
X228541Y1024475D01*
X226391D01*
G01Y1031168D02*
X230338D01*
X231355Y1032185D01*
X232861D01*
X233438Y1031608D01*
Y1030518D01*
X234491Y1029465D01*
X235523D01*
G01X244677Y1029495D02*
X247805D01*
X249478Y1031168D01*
X256091D01*
G01X290925Y1011753D02*
X272188Y1019514D01*
X265072Y1026630D01*
X263658Y1027216D01*
X261319Y1029555D01*
X260678D01*
G01X251878Y1029539D02*
X251051D01*
X249334Y1027822D01*
X239949D01*
G01X292125Y1008809D02*
X291115D01*
X270994Y1017144D01*
X263692Y1024446D01*
X262266Y1025037D01*
X260578Y1025736D01*
G01X251878Y1026083D02*
X251162D01*
X246208Y1021129D01*
X239949D01*
G01X226391Y1044554D02*
X232794D01*
X234540Y1042808D01*
X235523D01*
G01X244677Y1042880D02*
X245140D01*
X246359Y1044099D01*
X247645D01*
X249333Y1042411D01*
X250351D01*
X252494Y1044554D01*
X256091D01*
G01X239949Y1041207D02*
X244149D01*
X245877Y1039479D01*
X251878D01*
G01X260678D02*
X261689D01*
X262250Y1040040D01*
X266429D01*
X278009Y1028460D01*
X279033Y1028036D01*
X279035Y1028034D01*
X297801Y1020260D01*
X302267Y1015794D01*
G01X226391Y1037861D02*
X232794D01*
X234523Y1036132D01*
X235523D01*
G01X244677Y1036188D02*
X246145D01*
X247088Y1035245D01*
X249685D01*
X250188Y1035748D01*
Y1036788D01*
X251261Y1037861D01*
X256091D01*
G01X295879Y1014059D02*
X293904Y1016034D01*
X274933Y1023891D01*
X266217Y1032607D01*
X265062Y1033085D01*
X263535Y1033718D01*
X262055D01*
X261107Y1032770D01*
X260578D01*
G01X251878Y1032781D02*
X245305D01*
X243571Y1034515D01*
X239949D01*
G01X244299Y1061286D02*
X239949D01*
G01Y1047900D02*
X244670D01*
X246413Y1046157D01*
X251878D01*
G01X260678Y1046125D02*
X261406D01*
X261942Y1045589D01*
X267191D01*
X268575Y1045016D01*
X280860Y1032731D01*
X281886Y1032306D01*
X281888Y1032304D01*
X299873Y1024855D01*
X299874Y1024853D01*
X301323Y1024253D01*
X307374Y1018202D01*
G01X309461Y1019689D02*
X302771Y1026379D01*
X301803Y1026780D01*
X301801Y1026783D01*
X282286Y1034866D01*
X269999Y1047153D01*
X267670Y1048118D01*
X262665D01*
X261145Y1049638D01*
X260578D01*
G01X251978Y1049657D02*
X251258D01*
X251174Y1049573D01*
X244677D01*
G01X235523Y1049406D02*
X234615D01*
X233433Y1048224D01*
X232723D01*
X232278Y1048669D01*
Y1050050D01*
X231969Y1050359D01*
X230778D01*
X229890Y1051247D01*
X226391D01*
G01X314223Y1022052D02*
X305629Y1030646D01*
X305145Y1030847D01*
X305142Y1030852D01*
X285566Y1038960D01*
X272243Y1052284D01*
X268937Y1053655D01*
X262157D01*
X261401Y1052899D01*
X260478D01*
G01X251878Y1052892D02*
X246068D01*
X244367Y1054593D01*
X239949D01*
G01Y1074672D02*
X243644D01*
X244773Y1074424D01*
X246274D01*
X247258Y1075408D01*
X248688D01*
X249138Y1074958D01*
Y1073918D01*
X250057Y1072999D01*
X250324D01*
G01X261865D02*
X262274D01*
X263064Y1073789D01*
Y1076062D01*
X263987Y1076985D01*
X268252D01*
X292398Y1052839D01*
X294307Y1052049D01*
X295596D01*
G01X295894Y1046785D02*
X295573Y1046464D01*
X294316D01*
X289614Y1048412D01*
X271432Y1066594D01*
X266735D01*
X265948Y1065807D01*
X263871D01*
X263080Y1066598D01*
Y1068666D01*
X262094Y1069652D01*
X261858D01*
G01X250317D02*
X249026D01*
X247353Y1067979D01*
X239949D01*
G01X226391Y1071326D02*
X232285D01*
X232688Y1070923D01*
Y1070204D01*
X233305Y1069587D01*
X234994D01*
G01X244918Y1069652D02*
X245576D01*
X246130Y1070206D01*
Y1071150D01*
X246811Y1071831D01*
X247841D01*
X248347Y1071325D01*
X248348Y1071326D01*
X256091D01*
G01X226391Y1064633D02*
X233026D01*
X233027Y1064632D01*
X233523Y1065128D01*
Y1065687D01*
X234142Y1066306D01*
X235025D01*
G01X244949D02*
X246038D01*
X246375Y1065969D01*
Y1064288D01*
X247406Y1063257D01*
X249434D01*
X250322Y1064145D01*
X252345D01*
X252833Y1064633D01*
X256091D01*
G01X226391Y1081365D02*
X228248D01*
X229276Y1080337D01*
X230703D01*
X232366Y1078674D01*
X232992D01*
X234010Y1079692D01*
X234217D01*
G01X245695D02*
X246223D01*
X247251Y1078664D01*
X248826D01*
X251330Y1080337D01*
X253132D01*
X254160Y1081365D01*
X256091D01*
G01X226391Y1078018D02*
X228259D01*
X229288Y1079047D01*
X230168D01*
X231831Y1077384D01*
X232965D01*
X234003Y1076346D01*
X234217D01*
G01X245695Y1076345D02*
X245909D01*
X246938Y1077374D01*
X249218D01*
X251722Y1079047D01*
X253134D01*
X254163Y1078018D01*
X256091D01*
G01X239949Y1091404D02*
X247351D01*
X249024Y1093077D01*
X251195D01*
G01X260865D02*
X261528D01*
X262176Y1092429D01*
X274181D01*
X287296Y1079314D01*
X288607Y1076150D01*
X299586Y1065171D01*
G01X226391Y1094751D02*
X232285D01*
X232688Y1094348D01*
Y1093574D01*
X233185Y1093077D01*
X235089D01*
G01X244759D02*
X245797D01*
X246130Y1093410D01*
Y1094575D01*
X246717Y1095162D01*
X247935D01*
X248347Y1094750D01*
X248348Y1094751D01*
X256091D01*
G01X226391Y1088058D02*
X232302D01*
X232303Y1088057D01*
X233977Y1089731D01*
X234288D01*
G01X245702D02*
X246338D01*
X246781Y1089288D01*
Y1088520D01*
X247566Y1087735D01*
X249173D01*
X250554Y1089116D01*
X251673D01*
X252731Y1088058D01*
X256091D01*
G01X297272Y1058499D02*
X295597Y1060174D01*
X294904D01*
X293227Y1061851D01*
Y1062544D01*
X291552Y1064219D01*
X290859D01*
X289182Y1065896D01*
Y1066589D01*
X287507Y1068264D01*
X286814D01*
X285137Y1069941D01*
Y1070634D01*
X283462Y1072309D01*
X282769D01*
X281092Y1073986D01*
Y1074679D01*
X279417Y1076354D01*
X278724D01*
X277047Y1078031D01*
Y1078724D01*
X275458Y1080313D01*
X271173Y1083176D01*
X267886Y1084538D01*
X262459D01*
X262070Y1084149D01*
Y1083443D01*
X261665Y1083038D01*
X261056D01*
G01X251243D02*
X250850D01*
X249797Y1084091D01*
X247728D01*
X243723Y1082432D01*
X242964D01*
X241896Y1081364D01*
X241895Y1081365D01*
X239949D01*
G01X298185Y1059412D02*
X276281Y1081316D01*
X271785Y1084320D01*
X268143Y1085828D01*
X262077D01*
X261521Y1086384D01*
X261056D01*
G01X251243D02*
X250667D01*
X249664Y1085381D01*
X247471D01*
X243466Y1083722D01*
X242878D01*
X241889Y1084711D01*
X239949D01*
G01X297678Y1074237D02*
X294572Y1077343D01*
X291531Y1084683D01*
X278494Y1097720D01*
X262778D01*
X261400Y1096342D01*
X261066D01*
G01X251194D02*
X249070D01*
X248571Y1096841D01*
X243431Y1097963D01*
X243107Y1098097D01*
X239949D01*
G01Y1111483D02*
X241910D01*
X243410Y1109983D01*
X245101D01*
X245987Y1110665D01*
X246189Y1111427D01*
X247500Y1112187D01*
X248590Y1111897D01*
X249766Y1109869D01*
X250090Y1109783D01*
X251778D01*
G01X260478Y1109772D02*
X261601D01*
X262284Y1110055D01*
X262716Y1110487D01*
X262776Y1110633D01*
X263354Y1112035D01*
X265064Y1113745D01*
X268160D01*
X269364Y1112541D01*
X270482D01*
X271586Y1113645D01*
X273838D01*
X274971Y1112512D01*
X276090D01*
X276627Y1113049D01*
X280805D01*
X290679Y1103175D01*
G01X287115Y1099610D02*
X281153Y1105572D01*
X262265D01*
X261329Y1106508D01*
X260678D01*
G01X251878Y1106544D02*
X250512D01*
X249825Y1105857D01*
Y1103068D01*
X249367Y1102610D01*
X248363D01*
X246183Y1104790D01*
X239949D01*
G01X226391Y1108137D02*
X232128D01*
X232688Y1107577D01*
Y1106833D01*
X233118Y1106403D01*
X235523D01*
G01X244677Y1106459D02*
X245571D01*
X246130Y1107018D01*
Y1107961D01*
X246811Y1108642D01*
X247841D01*
X248346Y1108137D01*
X256091D01*
G01X226391Y1101444D02*
X233026D01*
X233027Y1101443D01*
X233523Y1101939D01*
Y1102779D01*
X233925Y1103181D01*
X235523D01*
G01X244677Y1103139D02*
X245257D01*
X248116Y1100280D01*
X251166D01*
X252330Y1101444D01*
X256091D01*
G01X239949Y1128215D02*
X248585D01*
X250316Y1129946D01*
X251665D01*
G01X260819Y1129888D02*
X261078D01*
X261605Y1129670D01*
X263121Y1128154D01*
X285158D01*
X297443Y1115869D01*
G01X226391Y1124869D02*
X232179D01*
X233915Y1126605D01*
X235523D01*
G01X244677Y1126615D02*
X246246D01*
X246890Y1125971D01*
Y1124979D01*
X247463Y1124406D01*
X248529D01*
X249886Y1125763D01*
X252861D01*
X253756Y1124868D01*
X253757Y1124869D01*
X256091D01*
G01X294328Y1109954D02*
X292653Y1111629D01*
X291960D01*
X290283Y1113306D01*
Y1113999D01*
X288608Y1115674D01*
X287915D01*
X286238Y1117351D01*
Y1118044D01*
X284271Y1120011D01*
X281683Y1120525D01*
X281107Y1120140D01*
X278782Y1120603D01*
X278397Y1121180D01*
X275635Y1121729D01*
X274279D01*
X273789Y1121239D01*
X271419D01*
X270929Y1121729D01*
X268559D01*
X268069Y1121239D01*
X265699D01*
X265209Y1121729D01*
X263677D01*
X262945Y1120997D01*
Y1120185D01*
X262540Y1119780D01*
X260778D01*
G01X251778Y1119783D02*
X250156D01*
X249037Y1120902D01*
X248313D01*
X244308Y1119243D01*
X242964D01*
X241896Y1118175D01*
X241895Y1118176D01*
X239949D01*
G01X226391D02*
X228248D01*
X229379Y1117045D01*
X230754D01*
X232314Y1115485D01*
X233628D01*
X234684Y1116541D01*
X235523D01*
G01X244677D02*
X245847D01*
X246913Y1115475D01*
X248826D01*
X251330Y1117148D01*
X253132D01*
X254160Y1118176D01*
X256091D01*
G01X295241Y1110867D02*
X284907Y1121201D01*
X275763Y1123019D01*
X262257D01*
X262053Y1123223D01*
X260578D01*
G01X251578Y1123266D02*
X250022D01*
X248948Y1122192D01*
X248056D01*
X244051Y1120533D01*
X242878D01*
X241889Y1121522D01*
X239949D01*
G01X226391Y1114829D02*
X228259D01*
X229185Y1115755D01*
X230219D01*
X231779Y1114195D01*
X233617D01*
X234697Y1113115D01*
X235523D01*
G01X244677Y1113114D02*
X245887D01*
X246958Y1114185D01*
X249218D01*
X251722Y1115858D01*
X253134D01*
X254163Y1114829D01*
X256091D01*
G01X306027Y1129353D02*
X306024D01*
X305083Y1130294D01*
Y1131107D01*
X303288Y1132902D01*
Y1134020D01*
X303856Y1134588D01*
Y1135706D01*
X302994Y1136568D01*
X301876D01*
X301308Y1136000D01*
X300190D01*
X299328Y1136862D01*
Y1137980D01*
X299896Y1138548D01*
Y1139666D01*
X299034Y1140528D01*
X297916D01*
X297348Y1139960D01*
X296230D01*
X294359Y1141831D01*
X282980D01*
X282190Y1141041D01*
Y1140494D01*
X281400Y1139704D01*
X280180D01*
X279390Y1140494D01*
Y1141041D01*
X278600Y1141831D01*
X277380D01*
X276590Y1141041D01*
Y1140494D01*
X275800Y1139704D01*
X274580D01*
X273790Y1140494D01*
Y1141041D01*
X273000Y1141831D01*
X271780D01*
X270990Y1141041D01*
Y1140494D01*
X270200Y1139704D01*
X268980D01*
X268190Y1140494D01*
Y1141041D01*
X267400Y1141831D01*
X262612D01*
X261148Y1143295D01*
X260578D01*
G01X251878Y1143327D02*
X250354D01*
X249964Y1142937D01*
Y1141192D01*
X249181Y1140409D01*
X247807D01*
X246615Y1141601D01*
X239949D01*
G01X226391Y1144948D02*
X232285D01*
X232688Y1144545D01*
Y1143728D01*
X233223Y1143193D01*
X235523D01*
G01X244677Y1143274D02*
X245575D01*
X246130Y1143829D01*
Y1144772D01*
X246811Y1145453D01*
X247841D01*
X248347Y1144947D01*
X248348Y1144948D01*
X256091D01*
G01X226391Y1138255D02*
X233026D01*
X233027Y1138254D01*
X233523Y1138750D01*
Y1139380D01*
X234122Y1139979D01*
X235523D01*
G01X244677Y1139928D02*
X245791D01*
X246375Y1139344D01*
Y1138396D01*
X247146Y1137625D01*
X249022D01*
X249652Y1138255D01*
X256091D01*
G01X301027Y1119453D02*
X287083Y1133397D01*
X265833D01*
X265125Y1134105D01*
X262140D01*
X261270Y1133235D01*
X260778D01*
G01X251778Y1133155D02*
X250793D01*
X248145Y1134053D01*
X244231Y1134908D01*
X239949D01*
G01X226391Y1131562D02*
X231371D01*
X231838Y1131095D01*
Y1130413D01*
X232393Y1129858D01*
X235523D01*
G01X244677Y1129831D02*
X246383D01*
X246940Y1130388D01*
Y1131514D01*
X247519Y1132093D01*
X248800D01*
X249332Y1131561D01*
X249333Y1131562D01*
X256091D01*
G01X239949Y1148294D02*
X246113D01*
X250474Y1150102D01*
X251778D01*
G01X259878Y1150011D02*
X261358D01*
X261921Y1150574D01*
X264540D01*
X265330Y1149784D01*
Y1147834D01*
X266120Y1147044D01*
X267340D01*
X268130Y1147834D01*
Y1149784D01*
X268920Y1150574D01*
X270140D01*
X270930Y1149784D01*
Y1147834D01*
X271720Y1147044D01*
X272940D01*
X273730Y1147834D01*
Y1149784D01*
X274520Y1150574D01*
X293764D01*
X298667Y1148543D01*
X308627Y1138583D01*
G01X311764Y1145789D02*
X310089Y1147464D01*
X309396D01*
X307719Y1149141D01*
Y1149834D01*
X306044Y1151509D01*
X305351D01*
X303674Y1153186D01*
Y1153880D01*
X302643Y1154911D01*
X299189Y1156341D01*
X298549Y1156076D01*
X296358Y1156984D01*
X296093Y1157624D01*
X293456Y1158716D01*
X291327D01*
X290837Y1158226D01*
X288467D01*
X287977Y1158716D01*
X285607D01*
X285117Y1158226D01*
X282747D01*
X282257Y1158716D01*
X279720D01*
X279230Y1158226D01*
X276860D01*
X276370Y1158716D01*
X274000D01*
X273510Y1158226D01*
X271140D01*
X270650Y1158716D01*
X268280D01*
X267790Y1158226D01*
X265420D01*
X264930Y1158716D01*
X262560D01*
X262186Y1158342D01*
Y1157590D01*
X261256Y1156660D01*
X260778D01*
G01X251778Y1156523D02*
X250460D01*
X250178Y1156805D01*
Y1157622D01*
X249859Y1157941D01*
X248618D01*
X243869Y1155974D01*
X242884D01*
X241896Y1154986D01*
X241895Y1154987D01*
X239949D01*
G01X226391D02*
X228248D01*
X229276Y1153959D01*
X230703D01*
X232366Y1152296D01*
X232992D01*
X234048Y1153352D01*
X235523D01*
G01X244677D02*
X245171D01*
X246237Y1152286D01*
X247575D01*
X250079Y1153959D01*
X253132D01*
X254160Y1154987D01*
X256091D01*
G01X312677Y1146702D02*
X303374Y1156005D01*
X293713Y1160006D01*
X260778D01*
G01X251578Y1160152D02*
X250917D01*
X249996Y1159231D01*
X248361D01*
X243612Y1157264D01*
X242958D01*
X241889Y1158333D01*
X239949D01*
G01X226391Y1151641D02*
X228260D01*
X229288Y1152669D01*
X230168D01*
X231831Y1151006D01*
X232965D01*
X234026Y1149945D01*
X235523D01*
G01X244677Y1149925D02*
X245207D01*
X246278Y1150996D01*
X247967D01*
X250471Y1152669D01*
X253134D01*
X254162Y1151641D01*
X256091D01*
G01Y1175066D02*
X252731D01*
X252085Y1175712D01*
X250087D01*
X249261Y1174886D01*
X248029D01*
X247361Y1175554D01*
Y1176227D01*
X246849Y1176739D01*
X244677D01*
G01X235523Y1176817D02*
X234149D01*
X233523Y1176191D01*
Y1175563D01*
X233026Y1175066D01*
X226391D01*
G01X317304Y1156629D02*
X303823Y1170110D01*
X294071Y1174149D01*
X265577D01*
X261406Y1169978D01*
X260478D01*
G01X251778Y1169983D02*
X250937D01*
X248690Y1170745D01*
X244231Y1171719D01*
X239949D01*
G01X315387Y1151412D02*
X306431Y1160368D01*
X289409Y1167419D01*
X267543D01*
X265775Y1165651D01*
X262224D01*
X261163Y1166712D01*
X261008D01*
X260992Y1166728D01*
X260578D01*
G01X251878Y1166775D02*
X249954D01*
X245732Y1165026D01*
X239949D01*
G01X226391Y1168373D02*
X232285D01*
X232688Y1167970D01*
Y1167407D01*
X233452Y1166643D01*
X235523D01*
G01X244677Y1166699D02*
X245575D01*
X246130Y1167254D01*
Y1168197D01*
X247101Y1169168D01*
X248299D01*
X249289Y1168758D01*
X249674Y1168373D01*
X256091D01*
G01X226391Y1161680D02*
X232932D01*
X233523Y1162271D01*
Y1162805D01*
X234132Y1163414D01*
X235523D01*
G01X244677Y1163353D02*
X245705D01*
X247082Y1161976D01*
X248697D01*
X250074Y1163353D01*
X251158D01*
X252831Y1161680D01*
X256091D01*
G01X244299Y1185105D02*
X239949D01*
G01X244299Y1178412D02*
X239949D01*
G01X256091Y1181759D02*
X250306D01*
X249604Y1182461D01*
X248527D01*
X247689Y1181623D01*
Y1180775D01*
X246999Y1180085D01*
X244677D01*
G01X235523Y1180021D02*
X233206D01*
X232688Y1180539D01*
Y1181259D01*
X232188Y1181759D01*
X226391D01*
G01X244299Y1191798D02*
X239949D01*
G01X256091D02*
X254160D01*
X253132Y1190770D01*
X250362D01*
X247858Y1189097D01*
X246265D01*
X245237Y1190125D01*
X244677D01*
G01X235523Y1190163D02*
X234802D01*
X233746Y1189107D01*
X232802D01*
X231139Y1190770D01*
X229276D01*
X228248Y1191798D01*
X226391D01*
G01X256091Y1188452D02*
X254162D01*
X253134Y1189480D01*
X250754D01*
X248250Y1187807D01*
X246262D01*
X245234Y1186779D01*
X244677D01*
G01X235523Y1186756D02*
X234746D01*
X233685Y1187817D01*
X232267D01*
X230604Y1189480D01*
X229288D01*
X228260Y1188452D01*
X226391D01*
G01X256091Y1205184D02*
X250308D01*
X250307Y1205183D01*
X249604Y1205886D01*
X248437D01*
X247689Y1205138D01*
Y1204200D01*
X246999Y1203510D01*
X244677D01*
G01X235523Y1203430D02*
X233222D01*
X232688Y1203964D01*
Y1204626D01*
X232130Y1205184D01*
X226391D01*
G01X256091Y1198491D02*
X252731D01*
X252043Y1199179D01*
X250129D01*
X249261Y1198311D01*
X248029D01*
X247361Y1198979D01*
Y1199652D01*
X246849Y1200164D01*
X244677D01*
G01X235523Y1200234D02*
X234141D01*
X233523Y1199616D01*
Y1198986D01*
X233027Y1198490D01*
X233026Y1198491D01*
X226391D01*
G01X244299Y1208530D02*
X239949D01*
G01X244299Y1201837D02*
X239949D01*
G01X244299Y1195144D02*
X239949D01*
G01Y1221916D02*
X243209D01*
X247726Y1220929D01*
X249914Y1220186D01*
X251878D01*
G01X260578Y1220181D02*
X262427D01*
X263397Y1221151D01*
X264616D01*
X288406Y1197361D01*
X290401Y1196028D01*
X290619Y1194934D01*
X289586Y1193389D01*
X289804Y1192294D01*
X290820Y1191615D01*
X291914Y1191833D01*
X292947Y1193378D01*
X294041Y1193596D01*
X295057Y1192917D01*
X295275Y1191822D01*
X294242Y1190277D01*
X294460Y1189182D01*
X295476Y1188503D01*
X296570Y1188721D01*
X297603Y1190266D01*
X298697Y1190484D01*
X299838Y1189721D01*
X321366Y1168193D01*
G01X319753Y1162679D02*
X299349Y1183083D01*
X287937D01*
X270924Y1200096D01*
Y1201214D01*
X272708Y1202998D01*
Y1204116D01*
X271846Y1204978D01*
X270728D01*
X268944Y1203194D01*
X267826D01*
X267187Y1203833D01*
Y1209723D01*
X262423Y1214487D01*
Y1216154D01*
X262417Y1216188D01*
X262410Y1216227D01*
X261346Y1216938D01*
X260678D01*
G01X251878Y1216960D02*
X248840D01*
X247103Y1215223D01*
X239949D01*
G01X226391Y1218570D02*
X232285D01*
X232688Y1218167D01*
Y1217350D01*
X233188Y1216850D01*
X235523D01*
G01X244677Y1216896D02*
X245575D01*
X246130Y1217451D01*
Y1218394D01*
X246811Y1219075D01*
X247841D01*
X248347Y1218569D01*
X248348Y1218570D01*
X256091D01*
G01X226391Y1211877D02*
X233026D01*
X233027Y1211876D01*
X233523Y1212372D01*
Y1213002D01*
X234099Y1213578D01*
X235523D01*
G01X244677Y1213550D02*
X245737D01*
X247411Y1211876D01*
X248707D01*
X250010Y1213179D01*
X251529D01*
X252831Y1211877D01*
X256091D01*
G01X226391Y1228609D02*
X228248D01*
X229276Y1227581D01*
X230703D01*
X232366Y1225918D01*
X232992D01*
X234048Y1226974D01*
X235523D01*
G01X244677D02*
X245847D01*
X246913Y1225908D01*
X248826D01*
X251330Y1227581D01*
X253132D01*
X254160Y1228609D01*
X256091D01*
G01X226391Y1225263D02*
X228260D01*
X229288Y1226291D01*
X230168D01*
X231831Y1224628D01*
X232965D01*
X234026Y1223567D01*
X235523D01*
G01X244677Y1223547D02*
X245887D01*
X246958Y1224618D01*
X249218D01*
X251722Y1226291D01*
X253134D01*
X254162Y1225263D01*
X256091D01*
G01X329331Y1178155D02*
X275050Y1232436D01*
X270068Y1235765D01*
X264164Y1238211D01*
X262561D01*
X262141Y1238631D01*
Y1239572D01*
X261348Y1240365D01*
X260478D01*
G01X251978Y1240361D02*
X249651D01*
X249021Y1239731D01*
Y1238677D01*
X248402Y1238058D01*
X247368D01*
X246778Y1238648D01*
X239949D01*
G01X256091Y1241995D02*
X254821D01*
X254820Y1241996D01*
X249327D01*
X248486Y1242837D01*
X246844D01*
X246130Y1242123D01*
Y1240923D01*
X245531Y1240324D01*
X244613D01*
G01X235459Y1240271D02*
X233281D01*
X231557Y1241995D01*
X226391D01*
G01Y1235302D02*
X233011D01*
X234684Y1236975D01*
X235523D01*
G01X244677Y1237006D02*
X245957D01*
X247920Y1235043D01*
X249119D01*
X250889Y1236813D01*
X252290D01*
X253801Y1235302D01*
X256091D01*
G01X324852Y1173676D02*
X301091Y1197437D01*
X284371Y1211160D01*
X277822Y1217709D01*
X277129D01*
X275452Y1219386D01*
Y1220079D01*
X273777Y1221754D01*
X273084D01*
X271407Y1223431D01*
Y1224124D01*
X269732Y1225799D01*
X269039D01*
X267363Y1227475D01*
Y1228168D01*
X264546Y1230985D01*
X263952Y1231231D01*
X263337D01*
X262355Y1230249D01*
X260578D01*
G01X251978Y1230259D02*
X250133D01*
X249043Y1231349D01*
X248064D01*
X244025Y1229676D01*
X242964D01*
X241896Y1228608D01*
X241895Y1228609D01*
X239949D01*
G01Y1231955D02*
X241889D01*
X242878Y1230966D01*
X243768D01*
X247807Y1232639D01*
X249034D01*
X249828Y1233433D01*
X250438Y1233686D01*
X251978D01*
G01X260478Y1233650D02*
X262165D01*
X263294Y1232521D01*
X264209D01*
X265277Y1232079D01*
X285239Y1212118D01*
X301959Y1198395D01*
X325765Y1174589D01*
G01X332901Y1181725D02*
X277926Y1236700D01*
X272853Y1240089D01*
X269762Y1241368D01*
X269335Y1242399D01*
X269737Y1243370D01*
X269310Y1244401D01*
X268181Y1244869D01*
X267150Y1244442D01*
X266748Y1243471D01*
X265717Y1243044D01*
X263609Y1243918D01*
X262235D01*
X261933Y1243616D01*
X260578D01*
G01X251978Y1243604D02*
X251341D01*
X247776Y1244813D01*
X245358Y1245341D01*
X239949D01*
G01X343651Y842652D02*
Y824195D01*
X340996Y817785D01*
X299700Y776489D01*
X286967Y771215D01*
X266324D01*
X265087Y769978D01*
X256257D01*
X256091Y770144D01*
G01X338611Y842652D02*
Y825192D01*
X336723Y820634D01*
X296848Y780759D01*
X286333Y776404D01*
X256524D01*
X256091Y776837D01*
G01X332285Y842652D02*
Y826455D01*
X331849Y825402D01*
X292276Y785829D01*
X259446D01*
X258398Y786877D01*
X256091D01*
G01Y783530D02*
X258371D01*
X258372Y783529D01*
X259382Y784539D01*
X280783D01*
X281273Y784049D01*
X283643D01*
X284133Y784539D01*
X286503D01*
X286993Y784049D01*
X289363D01*
X289853Y784539D01*
X292811D01*
X299377Y791105D01*
X300070D01*
X301747Y792782D01*
Y793475D01*
X303422Y795150D01*
X304115D01*
X305792Y796827D01*
Y797520D01*
X307467Y799195D01*
X308160D01*
X309837Y800872D01*
Y801565D01*
X311512Y803240D01*
X312205D01*
X313882Y804917D01*
Y805610D01*
X315557Y807285D01*
X316250D01*
X317927Y808962D01*
Y809655D01*
X319602Y811330D01*
X320295D01*
X321972Y813007D01*
Y813700D01*
X323647Y815375D01*
X324340D01*
X326017Y817052D01*
Y817745D01*
X327692Y819420D01*
X328385D01*
X330061Y821096D01*
Y821789D01*
X332943Y824671D01*
X333575Y826198D01*
Y842652D01*
G01X320915Y842653D02*
Y836824D01*
X319264Y835173D01*
Y834055D01*
X320915Y832404D01*
Y831286D01*
X320053Y830424D01*
X318935D01*
X317284Y832075D01*
X316166D01*
X315304Y831213D01*
Y830095D01*
X316981Y828418D01*
Y827300D01*
X316119Y826438D01*
X315001D01*
X313324Y828115D01*
X312206D01*
X311344Y827253D01*
Y826135D01*
X313021Y824458D01*
Y823340D01*
X312159Y822478D01*
X311041D01*
X309364Y824155D01*
X308246D01*
X307384Y823293D01*
Y822175D01*
X309061Y820498D01*
Y819380D01*
X308199Y818518D01*
X307081D01*
X305404Y820195D01*
X304286D01*
X282720Y798629D01*
X265330D01*
X264227Y799732D01*
X263398Y799897D01*
X261556Y800263D01*
X256091D01*
G01X325952Y842652D02*
Y829149D01*
X299437Y802634D01*
X298321D01*
X296641Y804312D01*
X295526D01*
X294662Y803448D01*
Y802331D01*
X296341Y800654D01*
Y799538D01*
X295477Y798674D01*
X294361D01*
X292681Y800352D01*
X291565D01*
X290701Y799488D01*
Y798372D01*
X292381Y796694D01*
Y795578D01*
X290291Y793488D01*
X263262D01*
X262387Y794363D01*
X258860D01*
X258066Y793569D01*
X258065Y793570D01*
X256091D01*
G01X310223Y841752D02*
X283399Y814928D01*
X281524D01*
X279966Y816486D01*
X278724D01*
X277166Y814928D01*
X275924D01*
X274366Y816486D01*
X273124D01*
X271566Y814928D01*
X270324D01*
X268766Y816486D01*
X266936D01*
X262925Y812475D01*
X261221D01*
X260048Y813648D01*
X256091D01*
G01X313784Y838191D02*
X283993Y808400D01*
X282183D01*
X280691Y809892D01*
X279383D01*
X277891Y808400D01*
X276583D01*
X275091Y809892D01*
X273783D01*
X272291Y808400D01*
X270983D01*
X269491Y809892D01*
X267816D01*
X263934Y806010D01*
X259083D01*
X258138Y806955D01*
X256091D01*
G01X303079Y853897D02*
X283593Y834411D01*
X282475D01*
X279948Y836938D01*
X278830D01*
X277968Y836076D01*
Y834958D01*
X280495Y832431D01*
Y831313D01*
X279563Y830381D01*
X256091D01*
G01X307902Y849072D02*
X282132Y823302D01*
X259721D01*
X259710Y823313D01*
X259622D01*
X259247Y823688D01*
X256091D01*
G01Y820341D02*
X258206D01*
X259877Y822012D01*
X265507D01*
X265997Y821522D01*
X268367D01*
X268857Y822012D01*
X271227D01*
X271717Y821522D01*
X274087D01*
X274577Y822012D01*
X276947D01*
X277437Y821522D01*
X279807D01*
X280297Y822012D01*
X282667D01*
X284545Y823890D01*
X285238D01*
X286915Y825567D01*
Y826260D01*
X288590Y827935D01*
X289283D01*
X290960Y829612D01*
Y830305D01*
X292635Y831980D01*
X293328D01*
X295005Y833657D01*
Y834350D01*
X296680Y836025D01*
X297373D01*
X299050Y837702D01*
Y838395D01*
X300725Y840070D01*
X301418D01*
X303095Y841747D01*
Y842440D01*
X304770Y844115D01*
X305463D01*
X307140Y845792D01*
Y846485D01*
X308815Y848160D01*
G01X300523Y894357D02*
X299638Y893472D01*
X297518D01*
X296598Y892552D01*
Y890782D01*
X295835Y890019D01*
X293838D01*
X293048Y890809D01*
Y893667D01*
X292258Y894457D01*
X291038D01*
X290248Y893667D01*
Y890809D01*
X289458Y890019D01*
X288484D01*
X287453Y888988D01*
Y871418D01*
X264093Y848058D01*
X262077D01*
X259676Y850459D01*
X256091D01*
G01X301853Y888540D02*
X298132Y884819D01*
X293527D01*
X292659Y883951D01*
Y881273D01*
X293449Y880483D01*
X295325D01*
X296115Y879693D01*
Y878473D01*
X295325Y877683D01*
X293449D01*
X292659Y876893D01*
Y875673D01*
X293449Y874883D01*
X295325D01*
X296115Y874093D01*
Y872873D01*
X295325Y872083D01*
X293449D01*
X292659Y871293D01*
Y869413D01*
X266015Y842769D01*
X259120D01*
X258123Y843766D01*
X256091D01*
G01X301423Y859512D02*
X295654Y853743D01*
X294536D01*
X291751Y856528D01*
X290633D01*
X289771Y855666D01*
Y854548D01*
X292556Y851763D01*
Y850645D01*
X291694Y849783D01*
X290576D01*
X287791Y852568D01*
X286673D01*
X285811Y851706D01*
Y850588D01*
X288596Y847803D01*
Y846597D01*
X287745Y845746D01*
X280217D01*
X270884Y836413D01*
X260140D01*
X259479Y837074D01*
X256091D01*
G01X300523Y908784D02*
X284542D01*
X273416Y897658D01*
Y895695D01*
X272626Y894905D01*
X271262D01*
X270472Y894115D01*
Y892895D01*
X271262Y892105D01*
X272626D01*
X273416Y891315D01*
Y890095D01*
X272626Y889305D01*
X271262D01*
X270472Y888515D01*
Y887295D01*
X271262Y886505D01*
X272626D01*
X273416Y885715D01*
Y884495D01*
X272626Y883705D01*
X271262D01*
X270472Y882915D01*
Y881695D01*
X271262Y880905D01*
X272626D01*
X273416Y880115D01*
Y877071D01*
X264523Y868178D01*
X260250D01*
X259264Y867192D01*
X256091D01*
G01X300123Y901387D02*
X287396D01*
X280400Y894391D01*
Y874391D01*
X266514Y860505D01*
X265139Y859935D01*
X262346D01*
X261008Y860486D01*
X258971D01*
X258958Y860499D01*
X256091D01*
G01Y857152D02*
X259218D01*
X259974Y857908D01*
Y858714D01*
X260456Y859196D01*
X260752D01*
X262090Y858645D01*
X265396D01*
X267245Y859411D01*
X269555Y861721D01*
X270248D01*
X271925Y863398D01*
Y864091D01*
X273600Y865766D01*
X274293D01*
X275970Y867443D01*
Y868136D01*
X277645Y869811D01*
X278338D01*
X280015Y871488D01*
Y872181D01*
X281690Y873856D01*
Y877251D01*
X282180Y877741D01*
Y880111D01*
X281690Y880601D01*
Y882971D01*
X282180Y883461D01*
Y885831D01*
X281690Y886321D01*
Y888691D01*
X282180Y889181D01*
Y891551D01*
X281690Y892041D01*
Y893856D01*
X283886Y896052D01*
X284579D01*
X286256Y897729D01*
Y898422D01*
X287931Y900097D01*
X288683D01*
X289173Y899607D01*
X291543D01*
X292033Y900097D01*
X294403D01*
X294893Y899607D01*
X297263D01*
X297753Y900097D01*
X300123D01*
G01X304126Y913910D02*
X303566D01*
X302282Y915194D01*
X277256D01*
X275762Y913700D01*
Y912582D01*
X277567Y910777D01*
Y909659D01*
X276705Y908797D01*
X275587D01*
X273782Y910602D01*
X272664D01*
X271802Y909740D01*
Y908622D01*
X273607Y906817D01*
Y905699D01*
X272745Y904837D01*
X271627D01*
X269822Y906642D01*
X268704D01*
X265195Y903133D01*
Y875976D01*
X263104Y873885D01*
X256091D01*
G01X260441Y880577D02*
X256091D01*
G01X260441Y887270D02*
X256091D01*
G01X260441Y897310D02*
X256091D01*
G01X260441Y893963D02*
X256091D01*
G01X260441Y910696D02*
X256091D01*
G01X260441Y904003D02*
X256091D01*
G01X317146Y935302D02*
X306046D01*
X297671Y926927D01*
X294638D01*
X293848Y927717D01*
Y928099D01*
X293058Y928889D01*
X291838D01*
X291048Y928099D01*
Y927717D01*
X290258Y926927D01*
X289038D01*
X288248Y927717D01*
Y928099D01*
X287458Y928889D01*
X286238D01*
X285448Y928099D01*
Y927717D01*
X284658Y926927D01*
X283438D01*
X282648Y927717D01*
Y928099D01*
X281858Y928889D01*
X280638D01*
X279848Y928099D01*
Y927717D01*
X279058Y926927D01*
X277838D01*
X277048Y927717D01*
Y928099D01*
X276258Y928889D01*
X275038D01*
X274248Y928099D01*
Y927717D01*
X273458Y926927D01*
X267663D01*
X263780Y923044D01*
X262492D01*
X261455Y924081D01*
X256091D01*
G01Y917389D02*
X261147D01*
X262255Y916281D01*
X264675D01*
X269649Y921255D01*
X299856D01*
X304209Y925608D01*
X305325D01*
X306649Y924285D01*
X307765D01*
X308629Y925149D01*
Y926265D01*
X307305Y927588D01*
Y928704D01*
X308864Y930263D01*
X310621D01*
X311411Y929473D01*
Y928826D01*
X312201Y928036D01*
X313421D01*
X314211Y928826D01*
Y929473D01*
X315001Y930263D01*
X316486D01*
G01X256091Y930774D02*
X259305D01*
X260062Y931531D01*
Y932265D01*
X260513Y932716D01*
X262883D01*
X263373Y932226D01*
X265743D01*
X266233Y932716D01*
X268291D01*
X270097Y934522D01*
X272467D01*
X272957Y934032D01*
X275327D01*
X275817Y934522D01*
X278187D01*
X278677Y934032D01*
X281047D01*
X281537Y934522D01*
X282720D01*
X284909Y935428D01*
X285549Y935163D01*
X287740Y936071D01*
X288005Y936711D01*
X290849Y937889D01*
X292216D01*
X292636Y937469D01*
Y935877D01*
X294182Y934331D01*
X296497D01*
X298043Y935877D01*
Y940484D01*
X298559Y941000D01*
X301664D01*
X302154Y940510D01*
X304524D01*
X305014Y941000D01*
X307384D01*
X307874Y940510D01*
X310244D01*
X310734Y941000D01*
X313104D01*
X313594Y940510D01*
X315964D01*
X316454Y941000D01*
X318824D01*
G01X321624Y957227D02*
X320522Y958329D01*
X318103D01*
X317313Y957539D01*
Y957029D01*
X316523Y956239D01*
X315303D01*
X314513Y957029D01*
Y957539D01*
X313723Y958329D01*
X312503D01*
X311713Y957539D01*
Y957029D01*
X310923Y956239D01*
X309703D01*
X308913Y957029D01*
Y957539D01*
X308123Y958329D01*
X306903D01*
X306113Y957539D01*
Y957029D01*
X305323Y956239D01*
X304103D01*
X303313Y957029D01*
Y957539D01*
X302523Y958329D01*
X301303D01*
X300513Y957539D01*
Y957029D01*
X299723Y956239D01*
X298503D01*
X297713Y957029D01*
Y957539D01*
X296923Y958329D01*
X294844D01*
X289818Y953303D01*
X280136Y949293D01*
X264923D01*
X262509Y946879D01*
X261390D01*
X260762Y947507D01*
X256091D01*
G01X321724Y951002D02*
X320093D01*
X319303Y950212D01*
Y949923D01*
X318513Y949133D01*
X317293D01*
X316503Y949923D01*
Y950351D01*
X315713Y951141D01*
X314493D01*
X313703Y950351D01*
Y949923D01*
X312913Y949133D01*
X311693D01*
X310903Y949923D01*
Y950212D01*
X310113Y951002D01*
X308893D01*
X308103Y950212D01*
Y949923D01*
X307313Y949133D01*
X306093D01*
X305303Y949923D01*
Y950351D01*
X304513Y951141D01*
X303293D01*
X302503Y950351D01*
Y949923D01*
X301713Y949133D01*
X300493D01*
X298624Y951002D01*
X296648D01*
X294772Y949126D01*
X281441Y943605D01*
X266396D01*
X263605Y940814D01*
X256091D01*
G01X318824Y942290D02*
X298024D01*
X296753Y941019D01*
Y936412D01*
X295962Y935621D01*
X294717D01*
X293926Y936412D01*
Y938004D01*
X292751Y939179D01*
X290592D01*
X282463Y935812D01*
X269562D01*
X267756Y934006D01*
X259743D01*
X259629Y934120D01*
X257159D01*
X257158Y934121D01*
X256091D01*
G01X288022Y965008D02*
X282482Y962709D01*
X264929D01*
X264928Y962708D01*
X259997D01*
X258466Y964239D01*
X256091D01*
G01X289602Y976400D02*
X284555Y981447D01*
X265715D01*
X263073Y978805D01*
X261438D01*
X260258Y977625D01*
X256091D01*
G01X286025Y972651D02*
X283337D01*
X282579Y971893D01*
X260311D01*
X259350Y970932D01*
X256091D01*
G01X299471Y981199D02*
X286149Y994521D01*
X262939D01*
X259429Y991011D01*
X256091D01*
G01X294088Y979216D02*
X284424Y988880D01*
X266825D01*
X264302Y987835D01*
X262942Y987271D01*
X259989Y984318D01*
X256091D01*
G01Y1021129D02*
X258099D01*
X259258Y1022288D01*
X260177D01*
X270186Y1012279D01*
X287783Y1004989D01*
X313740D01*
X323457Y995271D01*
X326165Y991219D01*
X328830Y988554D01*
X330625D01*
G01Y989844D02*
X329365D01*
X327168Y992042D01*
X324460Y996094D01*
X314275Y1006279D01*
X288040D01*
X286498Y1006918D01*
X286233Y1007558D01*
X284042Y1008466D01*
X283402Y1008201D01*
X281213Y1009108D01*
X280948Y1009748D01*
X278757Y1010656D01*
X278117Y1010391D01*
X275928Y1011297D01*
X275663Y1011938D01*
X273472Y1012846D01*
X272832Y1012580D01*
X270917Y1013373D01*
X260712Y1023578D01*
X259178D01*
X258281Y1024475D01*
X256091D01*
G01X304539Y1017466D02*
X299881Y1022124D01*
X280462Y1030169D01*
X280460Y1030171D01*
X279434Y1030596D01*
X267472Y1042558D01*
X261582D01*
X260272Y1043868D01*
X258998D01*
X258312Y1044554D01*
X256091D01*
G01X298235Y1015427D02*
X294944Y1018718D01*
X276585Y1026323D01*
X265386Y1037522D01*
X263081D01*
X261827Y1036268D01*
X259967D01*
X258374Y1037861D01*
X256091D01*
G01X293540Y1012770D02*
X292364Y1013946D01*
X273507Y1021756D01*
X265088Y1030175D01*
X265062Y1030186D01*
X262689Y1031168D01*
X256091D01*
G01X311841Y1020870D02*
X304197Y1028514D01*
X303474Y1028814D01*
X303472Y1028817D01*
X284138Y1036825D01*
X271855Y1049110D01*
X267901Y1050748D01*
X263587D01*
X263088Y1051247D01*
X256091D01*
G01X295596Y1049511D02*
X293710D01*
X290960Y1050650D01*
X271264Y1070346D01*
X270146D01*
X268918Y1069118D01*
X267800D01*
X267010Y1069908D01*
Y1071026D01*
X268166Y1072182D01*
Y1073444D01*
X267186Y1074424D01*
X265523D01*
X264733Y1073634D01*
Y1073003D01*
X263055Y1071325D01*
X262446D01*
X262443Y1071326D01*
X256091D01*
G01X297688Y1044991D02*
X296566Y1043869D01*
X292938D01*
X288931Y1045529D01*
X274186Y1060274D01*
X273068D01*
X272630Y1059836D01*
X271512D01*
X270650Y1060698D01*
Y1061816D01*
X271088Y1062254D01*
Y1063372D01*
X270405Y1064055D01*
X267831D01*
X267041Y1063265D01*
Y1061261D01*
X266251Y1060471D01*
X265031D01*
X264241Y1061261D01*
Y1062497D01*
X263451Y1063287D01*
X262491D01*
X261146Y1064632D01*
X257990D01*
X257989Y1064633D01*
X256091D01*
G01Y1078018D02*
X257196D01*
X257197Y1078017D01*
X259298D01*
X260015Y1078734D01*
Y1079687D01*
X260332Y1080004D01*
X262811D01*
X263301Y1079514D01*
X265671D01*
X266161Y1080004D01*
X268531D01*
X272942Y1076734D01*
X273999Y1075677D01*
Y1074983D01*
X275676Y1073306D01*
X276369D01*
X278044Y1071631D01*
Y1070939D01*
X279721Y1069262D01*
X280414D01*
X282089Y1067587D01*
Y1066894D01*
X283766Y1065217D01*
X284459D01*
X286134Y1063542D01*
Y1062849D01*
X287811Y1061172D01*
X288504D01*
X290179Y1059497D01*
Y1058804D01*
X291856Y1057127D01*
X292549D01*
X294224Y1055452D01*
G01X299586Y1068743D02*
X292377Y1075952D01*
X291652Y1077704D01*
X290530Y1078169D01*
X289768Y1080009D01*
X290233Y1081131D01*
X289352Y1083255D01*
X288946Y1083661D01*
X286680D01*
X285890Y1084451D01*
Y1086717D01*
X284986Y1087621D01*
X282720D01*
X281930Y1088411D01*
Y1090677D01*
X281026Y1091581D01*
X278760D01*
X277970Y1092371D01*
Y1094637D01*
X277438Y1095169D01*
X264841D01*
X264840Y1095168D01*
X262579D01*
X262162Y1094751D01*
X256091D01*
G01X299586Y1061601D02*
X285170Y1076017D01*
Y1077815D01*
X284089Y1078896D01*
X282291D01*
X281210Y1079977D01*
Y1081775D01*
X280129Y1082856D01*
X278331D01*
X277250Y1083937D01*
Y1085735D01*
X276169Y1086816D01*
X273311D01*
X270300Y1089827D01*
X268059D01*
X266588Y1088356D01*
X264255D01*
X263353Y1089258D01*
X262234D01*
X261034Y1088058D01*
X256091D01*
G01X295137Y1056364D02*
X273787Y1077714D01*
X268957Y1081294D01*
X256162D01*
X256091Y1081365D01*
G01X288899Y1101394D02*
X282183Y1108110D01*
X280502D01*
X279712Y1108900D01*
Y1109686D01*
X278922Y1110476D01*
X277702D01*
X276912Y1109686D01*
Y1108900D01*
X276122Y1108110D01*
X274902D01*
X274112Y1108900D01*
Y1109707D01*
X273322Y1110497D01*
X272102D01*
X271312Y1109707D01*
Y1108900D01*
X270522Y1108110D01*
X269302D01*
X268512Y1108900D01*
Y1109728D01*
X267722Y1110518D01*
X266502D01*
X265712Y1109728D01*
Y1108900D01*
X264902Y1108090D01*
X261850D01*
X261803Y1108137D01*
X256091D01*
G01X285327Y1097822D02*
X281065Y1102084D01*
X279307D01*
X278873Y1101650D01*
Y1101649D01*
X278439Y1101215D01*
X276607D01*
X276173Y1101649D01*
Y1102519D01*
X275739Y1102953D01*
X273907D01*
X273473Y1102519D01*
Y1101649D01*
X273039Y1101215D01*
X271207D01*
X270773Y1101649D01*
Y1102519D01*
X270339Y1102953D01*
X268507D01*
X268073Y1102519D01*
Y1101649D01*
X267639Y1101215D01*
X265807D01*
X265373Y1101649D01*
Y1102519D01*
X264939Y1102953D01*
X262396D01*
X261527Y1102084D01*
X260185D01*
X259545Y1101444D01*
X256091D01*
G01X297312Y1112438D02*
X284114Y1125636D01*
X283134D01*
X282055Y1124557D01*
X280967D01*
X279888Y1125636D01*
X262205D01*
X261433Y1124864D01*
X260802D01*
X259643Y1126023D01*
X259060D01*
X257905Y1124868D01*
X257904Y1124869D01*
X256091D01*
G01X293281Y1106706D02*
X284128Y1115859D01*
X279071Y1117953D01*
X277949Y1118176D01*
X256091D01*
G01X292368Y1105794D02*
X290693Y1107469D01*
X290000D01*
X288323Y1109146D01*
Y1109839D01*
X286648Y1111514D01*
X285955D01*
X284278Y1113191D01*
Y1113884D01*
X283397Y1114765D01*
X278695Y1116712D01*
X277822Y1116886D01*
X276687D01*
X276197Y1116396D01*
X273827D01*
X273337Y1116886D01*
X270967D01*
X270477Y1116396D01*
X268107D01*
X267617Y1116886D01*
X265247D01*
X264757Y1116396D01*
X262387D01*
X261897Y1116886D01*
X260446D01*
X259993Y1116433D01*
Y1115523D01*
X259298Y1114828D01*
X257197D01*
X257196Y1114829D01*
X256091D01*
G01X305030Y1125356D02*
X304081Y1126305D01*
X303055D01*
X301564Y1124814D01*
X300616D01*
X299601Y1125829D01*
Y1126947D01*
X302065Y1129411D01*
Y1130529D01*
X301203Y1131391D01*
X300085D01*
X297621Y1128927D01*
X296503D01*
X295641Y1129789D01*
Y1130907D01*
X298105Y1133371D01*
Y1134489D01*
X297243Y1135351D01*
X296125D01*
X293661Y1132887D01*
X292543D01*
X291681Y1133749D01*
Y1134867D01*
X294145Y1137331D01*
Y1138449D01*
X293283Y1139311D01*
X292165D01*
X289751Y1136897D01*
X267313D01*
X266042Y1138168D01*
X262957D01*
X261232Y1139893D01*
X260001D01*
X258362Y1138254D01*
X258361Y1138255D01*
X256091D01*
G01X299245Y1117671D02*
X286079Y1130837D01*
X264313D01*
X263588Y1131562D01*
X256091D01*
G01X307090Y1134512D02*
Y1136227D01*
X298967Y1144350D01*
X292920D01*
X292130Y1145140D01*
Y1147065D01*
X291340Y1147855D01*
X290120D01*
X289330Y1147065D01*
Y1145140D01*
X288540Y1144350D01*
X287320D01*
X286530Y1145140D01*
Y1147065D01*
X285740Y1147855D01*
X284520D01*
X283730Y1147065D01*
Y1145140D01*
X282940Y1144350D01*
X281720D01*
X280930Y1145140D01*
Y1147065D01*
X280140Y1147855D01*
X278920D01*
X278130Y1147065D01*
Y1145140D01*
X277340Y1144350D01*
X263864D01*
X262876Y1145338D01*
X260001D01*
X259611Y1144948D01*
X256091D01*
G01X309636Y1143661D02*
X300953Y1152344D01*
X294849Y1154872D01*
X256206D01*
X256091Y1154987D01*
G01Y1151641D02*
X259654D01*
X259655Y1151640D01*
X260084Y1152069D01*
Y1152889D01*
X260777Y1153582D01*
X262895D01*
X263385Y1153092D01*
X265755D01*
X266245Y1153582D01*
X268615D01*
X269105Y1153092D01*
X271475D01*
X271965Y1153582D01*
X274335D01*
X274825Y1153092D01*
X277195D01*
X277685Y1153582D01*
X280055D01*
X280545Y1153092D01*
X282915D01*
X283405Y1153582D01*
X285775D01*
X286265Y1153092D01*
X288635D01*
X289125Y1153582D01*
X294592D01*
X300222Y1151250D01*
X300633Y1150839D01*
Y1150146D01*
X302310Y1148469D01*
X303003D01*
X304678Y1146794D01*
Y1146101D01*
X306355Y1144424D01*
X307048D01*
X308723Y1142749D01*
G01X260441Y1175066D02*
X256091D01*
G01X316818Y1153543D02*
X307822Y1162539D01*
X302960Y1164551D01*
X302533Y1165582D01*
X303003Y1166717D01*
X302576Y1167749D01*
X301447Y1168217D01*
X300416Y1167790D01*
X299946Y1166654D01*
X298915Y1166227D01*
X297786Y1166695D01*
X297359Y1167726D01*
X297829Y1168861D01*
X297402Y1169893D01*
X296273Y1170361D01*
X295242Y1169934D01*
X294772Y1168798D01*
X293741Y1168371D01*
X289961Y1169937D01*
X284686D01*
X283896Y1170727D01*
Y1170841D01*
X283106Y1171631D01*
X281886D01*
X281096Y1170841D01*
Y1170727D01*
X280306Y1169937D01*
X279086D01*
X278296Y1170727D01*
Y1170841D01*
X277506Y1171631D01*
X276286D01*
X275496Y1170841D01*
Y1170727D01*
X274706Y1169937D01*
X273486D01*
X272696Y1170727D01*
Y1170841D01*
X271906Y1171631D01*
X270686D01*
X269896Y1170841D01*
Y1170727D01*
X269106Y1169937D01*
X265955D01*
X264391Y1168373D01*
X256091D01*
G01X313595Y1149619D02*
X304978Y1158236D01*
X294405Y1162616D01*
X289442D01*
X288652Y1163406D01*
Y1164106D01*
X287862Y1164896D01*
X286642D01*
X285852Y1164106D01*
Y1163406D01*
X285062Y1162616D01*
X283842D01*
X283052Y1163406D01*
Y1164106D01*
X282262Y1164896D01*
X281042D01*
X280252Y1164106D01*
Y1163406D01*
X279462Y1162616D01*
X278242D01*
X277452Y1163406D01*
Y1164106D01*
X276662Y1164896D01*
X275442D01*
X274652Y1164106D01*
Y1163406D01*
X273862Y1162616D01*
X272642D01*
X271852Y1163406D01*
Y1164106D01*
X271062Y1164896D01*
X269842D01*
X269052Y1164106D01*
Y1163406D01*
X268262Y1162616D01*
X261363D01*
X260427Y1161680D01*
X256091D01*
G01X260441Y1181759D02*
X256091D01*
G01X260441Y1191798D02*
X256091D01*
G01X260441Y1188452D02*
X256091D01*
G01X260441Y1205184D02*
X256091D01*
G01X260441Y1198491D02*
X256091D01*
G01X319835Y1166160D02*
X300041Y1185954D01*
X292277D01*
X286812Y1191419D01*
Y1195391D01*
X285275Y1196928D01*
X284157D01*
X281475Y1194246D01*
X280357D01*
X279495Y1195108D01*
Y1196226D01*
X282177Y1198908D01*
Y1200026D01*
X281315Y1200888D01*
X280197D01*
X277515Y1198206D01*
X276397D01*
X275535Y1199068D01*
Y1200186D01*
X278217Y1202868D01*
Y1203986D01*
X263633Y1218570D01*
X256091D01*
G01X317973Y1160898D02*
X298872Y1179999D01*
X287436D01*
X284659Y1182776D01*
X283541D01*
X282078Y1181313D01*
X280960D01*
X280098Y1182175D01*
Y1183293D01*
X281561Y1184756D01*
Y1185874D01*
X280699Y1186736D01*
X279581D01*
X278118Y1185273D01*
X277000D01*
X276138Y1186135D01*
Y1187253D01*
X277601Y1188716D01*
Y1189834D01*
X276739Y1190696D01*
X275621D01*
X274158Y1189233D01*
X273040D01*
X272178Y1190095D01*
Y1191213D01*
X273641Y1192676D01*
Y1193794D01*
X272779Y1194656D01*
X271661D01*
X270198Y1193193D01*
X269080D01*
X268218Y1194055D01*
Y1195173D01*
X269681Y1196636D01*
Y1197754D01*
X264576Y1202859D01*
Y1208617D01*
X261316Y1211877D01*
X256091D01*
G01X322153Y1170978D02*
X298897Y1194234D01*
X297066Y1195737D01*
X296376Y1195669D01*
X294543Y1197174D01*
X294475Y1197864D01*
X292644Y1199367D01*
X291954Y1199299D01*
X290121Y1200804D01*
X290053Y1201493D01*
X288222Y1202996D01*
X287532Y1202928D01*
X285699Y1204433D01*
X285631Y1205123D01*
X283800Y1206626D01*
X283110Y1206558D01*
X281277Y1208063D01*
X281209Y1208752D01*
X278346Y1211102D01*
X264899Y1224550D01*
X263691Y1225049D01*
X262872Y1225387D01*
X262870Y1225388D01*
X260712Y1226283D01*
X259255D01*
X258234Y1225262D01*
X258233Y1225263D01*
X256091D01*
G01X330875Y1180174D02*
X276525Y1234524D01*
X271380Y1237962D01*
X263691Y1241148D01*
X261646Y1241995D01*
X256091D01*
G01Y1235302D02*
X257763D01*
X258634Y1236173D01*
X262451D01*
X263691Y1235659D01*
X268219Y1233784D01*
X269374Y1233013D01*
X269715Y1231292D01*
X271012Y1230425D01*
X272733Y1230767D01*
X274014Y1229911D01*
X274616Y1229309D01*
Y1228191D01*
X274231Y1227806D01*
Y1226688D01*
X275093Y1225826D01*
X276211D01*
X276596Y1226211D01*
X277714D01*
X278576Y1225349D01*
Y1224231D01*
X278191Y1223846D01*
Y1222728D01*
X279053Y1221866D01*
X280171D01*
X280556Y1222251D01*
X281674D01*
X282536Y1221389D01*
Y1220271D01*
X282151Y1219886D01*
Y1218768D01*
X283013Y1217906D01*
X284131D01*
X284516Y1218291D01*
X285634D01*
X286496Y1217429D01*
Y1216311D01*
X286115Y1215930D01*
Y1214812D01*
X286977Y1213950D01*
X288095D01*
X288476Y1214331D01*
X289594D01*
X290456Y1213469D01*
Y1212351D01*
X290462Y1212345D01*
Y1211233D01*
X291253Y1210442D01*
X293483D01*
X294416Y1209509D01*
Y1208391D01*
X296396Y1206411D01*
X297514D01*
X327550Y1176375D01*
G01X256091Y1228609D02*
X258321D01*
X259357Y1227573D01*
X260969D01*
X263691Y1226447D01*
X265630Y1225645D01*
X279214Y1212060D01*
X299765Y1195192D01*
X323066Y1171891D01*
G01X337779Y882329D02*
Y880219D01*
G01X335928Y885533D02*
Y883423D01*
G01X337779Y895146D02*
Y893036D01*
G01X335928Y891942D02*
Y889832D01*
G01X334079Y888737D02*
Y886627D01*
G01X337779Y888737D02*
Y886627D01*
G01X341479Y882329D02*
Y880219D01*
G01X343328Y885533D02*
Y883424D01*
X343329Y883423D01*
G01X348879Y901555D02*
Y899446D01*
X348878Y899445D01*
G01X348879Y895146D02*
Y893037D01*
X348878Y893036D01*
G01X350728Y891942D02*
X350729Y891941D01*
Y889832D01*
G01X354428Y891942D02*
X354429Y891941D01*
Y889832D01*
G01X341479Y895146D02*
Y893037D01*
X341478Y893036D01*
G01X343328Y891942D02*
Y889832D01*
G01X347029Y898350D02*
Y896240D01*
G01X354428Y898350D02*
X354429Y898349D01*
Y896240D01*
G01X341479Y888737D02*
Y886627D01*
G01X350728Y898350D02*
X350729Y898349D01*
Y896240D01*
G01X345179Y888737D02*
Y886627D01*
G01X348879Y914372D02*
X348878Y914371D01*
Y912262D01*
G01X350728Y911167D02*
X350729Y911166D01*
Y909057D01*
G01X354428Y911167D02*
X354429Y911166D01*
Y909057D01*
G01X350728Y904759D02*
X350729Y904758D01*
Y902649D01*
G01X354428Y904759D02*
X354429Y904758D01*
Y902649D01*
G01X347029Y917576D02*
Y915466D01*
G01X354428Y917576D02*
X354429Y917575D01*
Y915466D01*
G01X350728Y917576D02*
Y915467D01*
X350729Y915466D01*
G01X348879Y933598D02*
Y931488D01*
G01X350728Y930393D02*
X350729Y930392D01*
Y928283D01*
G01X354428Y930393D02*
X354429Y930392D01*
Y928283D01*
G01X354428Y923985D02*
X354429Y923984D01*
Y921875D01*
G01X350728Y923985D02*
Y921876D01*
X350729Y921875D01*
G01X348879Y920780D02*
X348878Y920779D01*
Y918670D01*
G01X350728Y943210D02*
X350729Y943209D01*
Y941100D01*
G01X348879Y940006D02*
X348878Y940005D01*
Y937896D01*
G01X354428Y943210D02*
X354429Y941100D01*
G01X347029Y936801D02*
Y934691D01*
G01X354428Y936801D02*
Y934692D01*
X354429Y934691D01*
G01X350728Y936801D02*
Y934692D01*
X350729Y934691D01*
G01X350728Y949619D02*
X350729Y949618D01*
Y947509D01*
G01X354428Y949619D02*
X354429Y949618D01*
Y947509D01*
G01X348879Y952823D02*
X348878Y952822D01*
Y950713D01*
G01X350728Y962436D02*
X350729Y962435D01*
Y960326D01*
G01X348879Y959232D02*
X348878Y959231D01*
Y957122D01*
G01X354428Y962436D02*
X354429Y962435D01*
Y960326D01*
G01X350728Y956027D02*
X350729Y956026D01*
Y953917D01*
G01X354428Y956027D02*
Y953918D01*
X354429Y953917D01*
G01X347029Y956027D02*
Y953918D01*
X347030Y953917D01*
G01X350728Y981662D02*
X350729Y981661D01*
Y979552D01*
G01X354428Y981662D02*
X354429Y981661D01*
Y979552D01*
G01X348879Y978457D02*
X348878Y978456D01*
Y976347D01*
G01X347029Y975253D02*
Y973143D01*
G01X348879Y972049D02*
X348878Y972048D01*
Y969939D01*
G01X350728Y968845D02*
X350729Y968844D01*
Y966735D01*
G01X354428Y968845D02*
X354429Y968844D01*
Y966735D01*
G01X351161Y997574D02*
Y999684D01*
G01X347461Y1003983D02*
Y1006093D01*
G01X349312Y1000778D02*
Y1002887D01*
X349311Y1002888D01*
G01X351161Y1012501D02*
Y1010391D01*
G01X349312Y1007187D02*
Y1009296D01*
X349311Y1009297D01*
G01X351161Y1029617D02*
X351162Y1029618D01*
Y1031727D01*
G01X349312Y1026413D02*
Y1028521D01*
X349311Y1028522D01*
Y1028523D01*
G01X349312Y1020004D02*
X349311Y1020005D01*
Y1022114D01*
G01X351161Y1016800D02*
Y1018910D01*
G01X347461Y1023208D02*
Y1025318D01*
G01X351162D02*
X351120D01*
G03X351119Y1023208I771732J-1421D01*
G01X351161D01*
G01X349311Y1047749D02*
Y1045639D01*
X349312D01*
G01Y1039230D02*
Y1041339D01*
X349311Y1041340D01*
G01X351161Y1036026D02*
Y1038136D01*
G01X347461Y1042434D02*
Y1044544D01*
G01X351161Y1042434D02*
Y1044544D01*
G01X349312Y1058455D02*
X349311Y1058456D01*
Y1060565D01*
G01X351161Y1055251D02*
Y1057361D01*
G01X347461Y1061660D02*
Y1063770D01*
G01X351161Y1061660D02*
Y1063770D01*
G01Y1048842D02*
Y1050952D01*
G01Y1068068D02*
Y1070177D01*
X351162Y1070178D01*
G01X349312Y1064864D02*
Y1066973D01*
X349311Y1066974D01*
G01X349312Y1077681D02*
Y1079790D01*
X349311Y1079791D01*
G01X351161Y1074477D02*
Y1076587D01*
G01Y1087294D02*
Y1089404D01*
G01X349312Y1084090D02*
Y1086198D01*
G03X349311Y1086200I-3J0D01*
G01X347461Y1080885D02*
Y1082995D01*
G01X351161Y1080885D02*
Y1082995D01*
G01X356279Y901555D02*
Y899446D01*
X356278Y899445D01*
G01X356279Y895146D02*
X356278Y895145D01*
Y893036D01*
G01X358128Y898350D02*
Y896241D01*
X358129Y896240D01*
G01X363679Y901555D02*
X363678Y901554D01*
Y899445D01*
G01X367379Y901555D02*
X367378Y901554D01*
Y899445D01*
G01X356279Y914372D02*
X356278Y914371D01*
Y912262D01*
G01X358128Y917576D02*
X358129Y917575D01*
Y915466D01*
G01X363679Y914372D02*
X363678Y914371D01*
Y912262D01*
G01X361828Y911167D02*
X361829Y911166D01*
Y909057D01*
G01X367379Y914372D02*
X367378Y914371D01*
Y912262D01*
G01X369228Y911167D02*
X369229Y911166D01*
Y909057D01*
G01X361828Y904759D02*
X361829Y904758D01*
Y902649D01*
G01X369228Y904759D02*
X369229Y904758D01*
Y902649D01*
G01X359979Y907963D02*
X359978Y907962D01*
Y905853D01*
G01X367379Y907963D02*
Y905854D01*
X367378Y905853D01*
G01X363679Y907963D02*
Y905854D01*
X363678Y905853D01*
G01X356279Y933598D02*
X356278Y933597D01*
Y931488D01*
G01X363679Y933598D02*
X363678Y933597D01*
Y931488D01*
G01X356279Y920780D02*
X356278Y920779D01*
Y918670D01*
G01X361828Y930393D02*
X361829Y930392D01*
Y928283D01*
G01X367379Y933598D02*
X367378Y933597D01*
Y931488D01*
G01X369228Y930393D02*
X369229Y930392D01*
Y928283D01*
G01X361828Y923985D02*
X361829Y923984D01*
Y921875D01*
G01X363679Y920780D02*
X363678Y920779D01*
Y918670D01*
G01X369228Y923985D02*
X369229Y923984D01*
Y921875D01*
G01X367379Y920780D02*
X367378Y920779D01*
Y918670D01*
G01X359979Y927189D02*
X359978Y927188D01*
Y925079D01*
G01X367379Y927189D02*
X367378Y927188D01*
Y925079D01*
G01X363679Y927189D02*
Y925080D01*
X363678Y925079D01*
G01X356279Y940006D02*
X356278Y937896D01*
G01X358128Y936801D02*
X358129Y936800D01*
Y934691D01*
G01X361828Y943210D02*
X361829Y943209D01*
Y941100D01*
G01X363679Y940006D02*
X363678Y940005D01*
Y937896D01*
G01X369228Y943210D02*
X369229Y943209D01*
Y941100D01*
G01X367379Y940006D02*
X367378Y940005D01*
Y937896D01*
G01X361828Y949619D02*
X361829Y949618D01*
Y947509D01*
G01X369228Y949619D02*
X369229Y949618D01*
Y947509D01*
G01X367379Y946414D02*
Y944305D01*
X367378Y944304D01*
G01X359979Y946414D02*
Y944305D01*
X359978Y944304D01*
G01X363679Y946414D02*
Y944305D01*
X363678Y944304D01*
G01X356279Y952823D02*
X356278Y952822D01*
Y950713D01*
G01X356279Y959232D02*
X356278Y959231D01*
Y957122D01*
G01X358128Y956027D02*
Y953918D01*
X358129Y953917D01*
G01X359979Y965640D02*
X359978Y965639D01*
Y963530D01*
G01X363679Y952823D02*
X363678Y952822D01*
Y950713D01*
G01X367379Y952823D02*
X367378Y952822D01*
Y950713D01*
G01X361828Y962436D02*
X361829Y962435D01*
Y960326D01*
G01X363679Y959232D02*
X363678Y959231D01*
Y957122D01*
G01X369228Y962436D02*
X369229Y962435D01*
Y960326D01*
G01X367379Y959232D02*
X367378Y959231D01*
Y957122D01*
G01X369228Y981662D02*
X369229Y981661D01*
Y979552D01*
G01X367379Y978457D02*
X367378Y978456D01*
Y976347D01*
G01X361828Y981662D02*
X361829Y981661D01*
Y979552D01*
G01X363679Y978457D02*
X363678Y978456D01*
Y976347D01*
G01X356279Y978457D02*
X356278Y978456D01*
Y976347D01*
G01X356279Y972049D02*
X356278Y972048D01*
Y969939D01*
G01X358128Y975253D02*
Y973144D01*
X358129Y973143D01*
G01X363679Y972049D02*
X363678Y972048D01*
Y969939D01*
G01X367379Y972049D02*
X367378Y972048D01*
Y969939D01*
G01X361828Y968845D02*
X361829Y968844D01*
Y966735D01*
G01X369228Y968845D02*
X369229Y968844D01*
Y966735D01*
G01X359979Y984866D02*
X359978Y984865D01*
Y982756D01*
G01X367379Y984866D02*
Y982757D01*
X367378Y982756D01*
G01X363679Y984866D02*
Y982757D01*
X363678Y982756D01*
G01X354861Y997574D02*
Y999684D01*
G01X362261Y997574D02*
X362262Y997575D01*
Y999684D01*
G01X369661Y997574D02*
Y999683D01*
X369662Y999684D01*
G01X358561Y1003983D02*
Y1006092D01*
X358562Y1006093D01*
G01X356712Y1000778D02*
Y1002887D01*
X356711Y1002888D01*
G01X354861Y1012501D02*
Y1010391D01*
G01X356712Y1007187D02*
Y1009296D01*
X356711Y1009297D01*
G01X360412Y1013595D02*
Y1015704D01*
X360411Y1015705D01*
G01X362261Y1010391D02*
Y1012500D01*
X362262Y1012501D01*
G01X369661Y1010391D02*
Y1012500D01*
X369662Y1012501D01*
G01X364112Y1007187D02*
Y1009296D01*
X364111Y1009297D01*
G01X367812Y1007187D02*
Y1009296D01*
X367811Y1009297D01*
G01X364112Y1000778D02*
Y1002887D01*
X364111Y1002888D01*
G01X367812Y1000778D02*
X371511Y1002888D01*
G01X354861Y1029617D02*
Y1031727D01*
G01X356712Y1026413D02*
X356711Y1026414D01*
Y1028523D01*
G01X356712Y1020004D02*
X356711Y1020005D01*
Y1022114D01*
G01X354861Y1016800D02*
Y1018910D01*
G01X362261Y1029617D02*
Y1031726D01*
X362262Y1031727D01*
G01X364112Y1026413D02*
Y1028522D01*
X364111Y1028523D01*
G01X369661Y1029617D02*
Y1031726D01*
X369662Y1031727D01*
G01X367812Y1026413D02*
Y1028522D01*
X367811Y1028523D01*
G01X354861Y1023208D02*
Y1025317D01*
X354862Y1025318D01*
G01X358561Y1023208D02*
X358562Y1023209D01*
Y1025318D01*
G01X364112Y1020004D02*
Y1022113D01*
X364111Y1022114D01*
G01X362261Y1016800D02*
X362262Y1016801D01*
Y1018910D01*
G01X367812Y1020004D02*
Y1022113D01*
X367811Y1022114D01*
G01X369661Y1016800D02*
Y1018909D01*
X369662Y1018910D01*
G01X356711Y1047749D02*
Y1045639D01*
X356712D01*
G01Y1039230D02*
X356711Y1039231D01*
Y1041340D01*
G01X354861Y1036026D02*
Y1038136D01*
G01X364112Y1039230D02*
X364111Y1039231D01*
Y1041340D01*
G01X362261Y1036026D02*
Y1038135D01*
X362262Y1038136D01*
G01X367812Y1039230D02*
X367811Y1039231D01*
Y1041340D01*
G01X369661Y1036026D02*
Y1038135D01*
X369662Y1038136D01*
G01X360412Y1032821D02*
Y1034930D01*
X360411Y1034931D01*
G01X354861Y1042434D02*
Y1044544D01*
G01X364112Y1032821D02*
Y1034930D01*
X364111Y1034931D01*
G01X358561Y1042434D02*
Y1044543D01*
X358562Y1044544D01*
G01X367812Y1032821D02*
Y1034930D01*
X367811Y1034931D01*
G01X364111Y1047749D02*
Y1045639D01*
X364112D01*
G01X367811Y1047749D02*
Y1045639D01*
X367812D01*
G01X356712Y1058455D02*
X356711Y1058456D01*
Y1060565D01*
G01X354861Y1055251D02*
Y1057361D01*
G01X358561Y1061660D02*
Y1063769D01*
X358562Y1063770D01*
G01X354861Y1061660D02*
Y1063770D01*
G01Y1048842D02*
Y1050952D01*
G01X364112Y1058455D02*
X364111Y1058456D01*
Y1060565D01*
G01X362261Y1055251D02*
X362262Y1055252D01*
Y1057361D01*
G01X367812Y1058455D02*
X367811Y1058456D01*
Y1060565D01*
G01X369661Y1055251D02*
X369662Y1055252D01*
Y1057361D01*
G01X362261Y1048842D02*
X362262Y1048843D01*
Y1050952D01*
G01X369661Y1048842D02*
X369662Y1048843D01*
Y1050952D01*
G01X360412Y1052047D02*
X360411Y1054157D01*
G01X364112Y1052047D02*
X364111Y1054157D01*
G01X367812Y1052047D02*
X367811Y1054157D01*
G01X354861Y1068068D02*
Y1070178D01*
G01X356712Y1064864D02*
Y1066973D01*
X356711Y1066974D01*
G01X367812Y1077681D02*
Y1079790D01*
X367811Y1079791D01*
G01X369661Y1074477D02*
G02X369662Y1076587I2226050J0D01*
G01X362261Y1068068D02*
X362262Y1068069D01*
Y1070178D01*
G01X364112Y1064864D02*
Y1066973D01*
X364111Y1066974D01*
G01X369661Y1068068D02*
X369662Y1068069D01*
Y1070178D01*
G01X367812Y1064864D02*
Y1066973D01*
X367811Y1066974D01*
G01X356712Y1077681D02*
Y1079790D01*
X356711Y1079791D01*
G01X354861Y1074477D02*
Y1076587D01*
G01X364112Y1077681D02*
Y1079790D01*
X364111Y1079791D01*
G01X362261Y1074477D02*
G02X362262Y1076587I2226050J0D01*
G01X360412Y1071273D02*
Y1073382D01*
X360411Y1073383D01*
G01X364112Y1071273D02*
Y1073382D01*
X364111Y1073383D01*
G01X367812Y1071273D02*
Y1073382D01*
X367811Y1073383D01*
G01X354861Y1087294D02*
Y1089404D01*
G01X356712Y1084090D02*
Y1086198D01*
G03X356711Y1086200I-3J0D01*
G01X354861Y1080885D02*
Y1082995D01*
G01X358562D02*
X358547D01*
G03X358546Y1080885I2226050J-2110D01*
G01X358561D01*
G01X362261Y1093703D02*
Y1095812D01*
X362262Y1095813D01*
G01X369661Y1093703D02*
Y1095812D01*
X369662Y1095813D01*
G01X362261Y1087294D02*
Y1089403D01*
X362262Y1089404D01*
G01X364112Y1084090D02*
G03X364111Y1086200I-2226050J0D01*
G01X369661Y1087294D02*
Y1089403D01*
X369662Y1089404D01*
G01X367812Y1084090D02*
G03X367811Y1086200I-2226050J0D01*
G01X360412Y1090498D02*
Y1092607D01*
X360411Y1092608D01*
G01X367812Y1090498D02*
X367811Y1090499D01*
Y1092608D01*
G01X364112Y1090498D02*
Y1092607D01*
X364111Y1092608D01*
G01X364112Y1096907D02*
X364111Y1099017D01*
G01X367812Y1096907D02*
X367811Y1099017D01*
G01X374779Y901555D02*
X374778Y901554D01*
Y899445D01*
G01X382179Y901555D02*
X382178Y901554D01*
Y899445D01*
G01X371079Y895146D02*
X371078Y895145D01*
Y893036D01*
G01X382179Y895146D02*
X382178Y895145D01*
Y893036D01*
G01X374779Y895146D02*
X374778Y895145D01*
Y893036D01*
G01X385879Y895146D02*
X385878Y895145D01*
Y893036D01*
G01X372928Y898350D02*
X372929Y898349D01*
Y896240D01*
G01X380328Y898350D02*
Y896241D01*
X380329Y896240D01*
G01X376628Y898350D02*
X376629Y898349D01*
Y896240D01*
G01X384028Y898350D02*
Y896241D01*
X384029Y896240D01*
G01X376628Y904759D02*
X376629Y904758D01*
Y902649D01*
G01X380328Y904759D02*
X380329Y904758D01*
Y902649D01*
G01X371079Y907963D02*
X371078Y907962D01*
Y905853D01*
G01X374779Y914372D02*
X374778Y914371D01*
Y912262D01*
G01X376628Y911167D02*
X376629Y911166D01*
Y909057D01*
G01X382179Y914372D02*
X382178Y914371D01*
Y912262D01*
G01X380328Y911167D02*
X380329Y911166D01*
Y909057D01*
G01X372928Y917576D02*
X372929Y917575D01*
Y915466D01*
G01X385879Y907963D02*
X385878Y907962D01*
Y905853D01*
G01X380328Y917576D02*
X380329Y917575D01*
Y915466D01*
G01X376628Y917576D02*
X376629Y917575D01*
Y915466D01*
G01X384028Y917576D02*
X384029Y917575D01*
Y915466D01*
G01X371079Y927189D02*
Y925080D01*
X371078Y925079D01*
G01X374779Y933598D02*
X374778Y933597D01*
Y931488D01*
G01X376628Y930393D02*
X376629Y930392D01*
Y928283D01*
G01X382179Y933598D02*
X382178Y933597D01*
Y931488D01*
G01X380328Y930393D02*
X380329Y930392D01*
Y928283D01*
G01X376628Y923985D02*
X376629Y923984D01*
Y921875D01*
G01X374779Y920780D02*
X374778Y920779D01*
Y918670D01*
G01X380328Y923985D02*
X380329Y923984D01*
Y921875D01*
G01X382179Y920780D02*
X382178Y920779D01*
Y918670D01*
G01X385879Y927189D02*
Y925080D01*
X385878Y925079D01*
G01X380328Y943210D02*
X380329Y943209D01*
Y941100D01*
G01X382179Y940006D02*
X382178Y940005D01*
Y937896D01*
G01X376628Y949619D02*
X376629Y949618D01*
Y947509D01*
G01X380328Y949619D02*
X380329Y949618D01*
Y947509D01*
G01X376628Y943210D02*
X376629Y943209D01*
Y941100D01*
G01X374779Y940006D02*
X374778Y940005D01*
Y937896D01*
G01X372928Y936801D02*
X372929Y936800D01*
Y934691D01*
G01X380328Y936801D02*
X380329Y936800D01*
Y934691D01*
G01X376628Y936801D02*
X376629Y936800D01*
Y934691D01*
G01X371079Y946414D02*
Y944305D01*
X371078Y944304D01*
G01X384028Y936801D02*
X384029Y936800D01*
Y934691D01*
G01X385879Y946414D02*
X385878Y946413D01*
Y944304D01*
G01X376628Y962436D02*
Y960327D01*
X376629Y960326D01*
G01X374779Y959232D02*
X374778Y959231D01*
Y957122D01*
G01X380328Y962436D02*
X380329Y962435D01*
Y960326D01*
G01X382179Y959232D02*
X382178Y959231D01*
Y957122D01*
G01X374779Y952823D02*
X374778Y952822D01*
Y950713D01*
G01X382179Y952823D02*
X382178Y952822D01*
Y950713D01*
G01X372928Y956027D02*
X372929Y953917D01*
G01X380328Y956027D02*
X380329Y953917D01*
G01X376628Y956027D02*
X376629Y953917D01*
G01X384028Y956027D02*
X384029Y953917D01*
G01X371079Y965640D02*
X371078Y965639D01*
Y963530D01*
G01X385879Y965640D02*
X385878Y965639D01*
Y963530D01*
G01X376628Y981662D02*
X376629Y981661D01*
Y979552D01*
G01X380328Y981662D02*
X380329Y981661D01*
Y979552D01*
G01X374779Y978457D02*
X374778Y978456D01*
Y976347D01*
G01X382179Y978457D02*
X382178Y978456D01*
Y976347D01*
G01X372928Y975253D02*
Y973144D01*
X372929Y973143D01*
G01X374779Y972049D02*
X374778Y972048D01*
Y969939D01*
G01X382179Y972049D02*
X382178Y972048D01*
Y969939D01*
G01X380328Y968845D02*
X380329Y968844D01*
Y966735D01*
G01X376628Y968845D02*
X376629Y968844D01*
Y966735D01*
G01X384028Y975253D02*
Y973144D01*
X384029Y973143D01*
G01X371079Y984866D02*
X371078Y984865D01*
Y982756D01*
G01X377061Y997574D02*
Y999683D01*
X377062Y999684D01*
G01X380761Y997574D02*
Y999683D01*
X380762Y999684D01*
G01X385879Y984866D02*
Y982757D01*
X385878Y982756D01*
G01X373361Y1003983D02*
Y1006092D01*
X373362Y1006093D01*
G01X380761Y1003983D02*
Y1006092D01*
X380762Y1006093D01*
G01X377061Y1003983D02*
Y1006092D01*
X377062Y1006093D01*
G01X384461Y1003983D02*
Y1006092D01*
X384462Y1006093D01*
G01X371512Y1013595D02*
Y1015704D01*
X371511Y1015705D01*
G01X375212Y1000778D02*
Y1002887D01*
X375211Y1002888D01*
G01X382612Y1000778D02*
Y1002887D01*
X382611Y1002888D01*
G01X386312Y1013595D02*
Y1015704D01*
X386311Y1015705D01*
G01X377061Y1010391D02*
Y1012500D01*
X377062Y1012501D01*
G01X375212Y1007187D02*
Y1009296D01*
X375211Y1009297D01*
G01X380761Y1010391D02*
Y1012500D01*
X380762Y1012501D01*
G01X382612Y1007187D02*
Y1009296D01*
X382611Y1009297D01*
G01X377061Y1029617D02*
Y1031726D01*
X377062Y1031727D01*
G01X375212Y1026413D02*
Y1028522D01*
X375211Y1028523D01*
G01X380761Y1029617D02*
Y1031726D01*
X380762Y1031727D01*
G01X382612Y1026413D02*
Y1028522D01*
X382611Y1028523D01*
G01X375212Y1020004D02*
Y1022113D01*
X375211Y1022114D01*
G01X377061Y1016800D02*
Y1018909D01*
X377062Y1018910D01*
G01X382612Y1020004D02*
Y1022113D01*
X382611Y1022114D01*
G01X380761Y1016800D02*
Y1018909D01*
X380762Y1018910D01*
G01X377061Y1023208D02*
X377062Y1025318D01*
G01X384461Y1023208D02*
X384462Y1025318D01*
G01X373361Y1023208D02*
Y1025317D01*
X373360Y1025318D01*
G01X380761Y1023208D02*
Y1025317D01*
X380760Y1025318D01*
G01X371512Y1032821D02*
Y1034930D01*
X371511Y1034931D01*
G01X375211Y1047749D02*
Y1045639D01*
X375212D01*
G01X382611Y1047749D02*
Y1045639D01*
X382612D01*
G01X375212Y1039230D02*
X375211Y1039231D01*
Y1041340D01*
G01X377061Y1036026D02*
Y1038135D01*
X377062Y1038136D01*
G01X382612Y1039230D02*
X382611Y1039231D01*
Y1041340D01*
G01X380761Y1036026D02*
Y1038135D01*
X380762Y1038136D01*
G01X373361Y1042434D02*
X373362Y1044544D01*
G01X380761Y1042434D02*
X380762Y1044544D01*
G01X377061Y1042434D02*
X377062Y1044544D01*
G01X384461Y1042434D02*
X384462Y1044544D01*
G01X386312Y1032821D02*
Y1034930D01*
X386311Y1034931D01*
G01X375212Y1058455D02*
X375211Y1058456D01*
Y1060565D01*
G01X377061Y1055251D02*
X377062Y1055252D01*
Y1057361D01*
G01X382612Y1058455D02*
X382611Y1058456D01*
Y1060565D01*
G01X380761Y1055251D02*
X380762Y1055252D01*
Y1057361D01*
G01X377061Y1048842D02*
X377062Y1048843D01*
Y1050952D01*
G01X380761Y1048842D02*
X380762Y1048843D01*
Y1050952D01*
G01X373361Y1061660D02*
X373362Y1063770D01*
G01X384461Y1061660D02*
X384462Y1063770D01*
G01X371512Y1052047D02*
X371511Y1054157D01*
G01X377061Y1061660D02*
X377062Y1063770D01*
G01X380761Y1061660D02*
X380762Y1063770D01*
G01X386312Y1052047D02*
X386311Y1052048D01*
Y1054157D01*
G01X371512Y1071273D02*
Y1073382D01*
X371511Y1073383D01*
G01X380761Y1068068D02*
Y1070177D01*
X380762Y1070178D01*
G01X382612Y1064864D02*
G03X382611Y1066974I-2226050J0D01*
G01X377061Y1068068D02*
X377062Y1068069D01*
Y1070178D01*
G01X375212Y1064864D02*
G03X375211Y1066974I-2226050J0D01*
G01X375212Y1077681D02*
Y1079790D01*
X375211Y1079791D01*
G01X377061Y1074477D02*
G02X377062Y1076587I2226050J0D01*
G01X382612Y1077681D02*
Y1079790D01*
X382611Y1079791D01*
G01X380761Y1074477D02*
G02X380762Y1076587I2226050J0D01*
G01X386312Y1071273D02*
G03X386311Y1073383I-2226050J0D01*
G01X371512Y1090498D02*
X371511Y1090499D01*
Y1092608D01*
G01X377061Y1087294D02*
Y1089403D01*
X377062Y1089404D01*
G01X375212Y1084090D02*
G03X375211Y1086200I-2226050J0D01*
G01X380761Y1087294D02*
Y1089403D01*
X380762Y1089404D01*
G01X382612Y1084090D02*
G03X382611Y1086200I-2226050J0D01*
G01X373361Y1080885D02*
G02X373362Y1082995I2226050J0D01*
G01X386312Y1090498D02*
G03X386311Y1092608I-2226050J0D01*
G01X384461Y1080885D02*
G02X384462Y1082995I2226050J0D01*
G01X377061Y1080885D02*
G02X377062Y1082995I2226050J0D01*
G01X380761Y1080885D02*
G02X380762Y1082995I2226050J0D01*
G01X389579Y901555D02*
X389578Y901554D01*
Y899445D01*
G01X393279Y901555D02*
X393278Y901554D01*
Y899445D01*
G01X389579Y914372D02*
X389578Y914371D01*
Y912262D01*
G01X387728Y911167D02*
X387729Y911166D01*
Y909057D01*
G01X393279Y914372D02*
X393278Y914371D01*
Y912262D01*
G01X395128Y911167D02*
X395129Y911166D01*
Y909057D01*
G01X387728Y904759D02*
X387729Y904758D01*
Y902649D01*
G01X395128Y904759D02*
X395129Y904758D01*
Y902649D01*
G01X393279Y907963D02*
X393278Y907962D01*
Y905853D01*
G01X389579Y907963D02*
X389578Y907962D01*
Y905853D01*
G01X396979Y907963D02*
X396978Y907962D01*
Y905853D01*
G01X393279Y933598D02*
X393278Y933597D01*
Y931488D01*
G01X395128Y930393D02*
X395129Y930392D01*
Y928283D01*
G01X387728Y923985D02*
X387729Y923984D01*
Y921875D01*
G01X389579Y920780D02*
X389578Y920779D01*
Y918670D01*
G01X395128Y923985D02*
X395129Y923984D01*
Y921875D01*
G01X393279Y920780D02*
X393278Y920779D01*
Y918670D01*
G01X389579Y933598D02*
X389578Y933597D01*
Y931488D01*
G01X387728Y930393D02*
X387729Y930392D01*
Y928283D01*
G01X393279Y927189D02*
Y925080D01*
X393278Y925079D01*
G01X389579Y927189D02*
X389578Y927188D01*
Y925079D01*
G01X396979Y927189D02*
Y925080D01*
X396978Y925079D01*
G01X387728Y949619D02*
X387729Y949618D01*
Y947509D01*
G01X395128Y949619D02*
X395129Y949618D01*
Y947509D01*
G01X387728Y943210D02*
X387729Y943209D01*
Y941100D01*
G01X389579Y940006D02*
X389578Y940005D01*
Y937896D01*
G01X395128Y943210D02*
X395129Y943209D01*
Y941100D01*
G01X393279Y940006D02*
X393278Y940005D01*
Y937896D01*
G01X393279Y946414D02*
X393278Y946413D01*
Y944304D01*
G01X389579Y946414D02*
X389578Y946413D01*
Y944304D01*
G01X396979Y946414D02*
X396978Y946413D01*
Y944304D01*
G01X387728Y962436D02*
X387729Y962435D01*
Y960326D01*
G01X389579Y959232D02*
X389578Y959231D01*
Y957122D01*
G01X395128Y962436D02*
X395129Y962435D01*
Y960326D01*
G01X393279Y959232D02*
X393278Y959231D01*
Y957122D01*
G01X389579Y952823D02*
X389578Y952822D01*
Y950713D01*
G01X393279Y952823D02*
X393278Y952822D01*
Y950713D01*
G01X396979Y965640D02*
X396978Y965639D01*
Y963530D01*
G01X393279Y965640D02*
X393278Y965639D01*
Y963530D01*
G01X389579Y965640D02*
X389578Y965639D01*
Y963530D01*
G01X398828Y975253D02*
X398824Y975249D01*
Y973148D01*
X398829Y973143D01*
G01X400679Y978457D02*
Y976348D01*
X400678Y976347D01*
G01X402528Y981662D02*
X402529Y981661D01*
Y979552D01*
G01X402528Y975253D02*
X402524Y975249D01*
Y973148D01*
X402529Y973143D01*
G01X393279Y978457D02*
X393278Y978456D01*
Y976347D01*
G01X395128Y981662D02*
X395129Y981661D01*
Y979552D01*
G01X387728Y981662D02*
X387729Y981661D01*
Y979552D01*
G01X389579Y976347D02*
Y978457D01*
G01Y972049D02*
X389578Y972048D01*
Y969939D01*
G01X387728Y968845D02*
X387729Y968844D01*
Y966735D01*
G01X393279Y972049D02*
X393278Y972048D01*
Y969939D01*
G01X395128Y968845D02*
X395129Y968844D01*
Y966735D01*
G01X388161Y997574D02*
Y999683D01*
X388162Y999684D01*
G01X395561Y997574D02*
Y999683D01*
X395562Y999684D01*
G01X399261Y997574D02*
Y999683D01*
X399262Y999684D01*
G01X402961Y997574D02*
Y999683D01*
X402962Y999684D01*
G01X393279Y984866D02*
X393278Y984865D01*
Y982756D01*
G01X389579Y984866D02*
Y982757D01*
X389578Y982756D01*
G01X396979Y984866D02*
X396978Y984865D01*
Y982756D01*
G01X399261Y1003983D02*
Y1006092D01*
X399262Y1006093D01*
G01X402961Y1003983D02*
X402962Y1003984D01*
Y1006093D01*
G01X390012Y1000778D02*
Y1002887D01*
X390011Y1002888D01*
G01X393712Y1000778D02*
Y1002887D01*
X393711Y1002888D01*
G01X397412Y1013595D02*
Y1015704D01*
X397411Y1015705D01*
G01X388161Y1010391D02*
Y1012500D01*
X388162Y1012501D01*
G01X395561Y1010391D02*
Y1012500D01*
X395562Y1012501D01*
G01X390012Y1007187D02*
Y1009296D01*
X390011Y1009297D01*
G01X393712Y1007187D02*
Y1009296D01*
X393711Y1009297D01*
G01X388161Y1029617D02*
Y1031726D01*
X388162Y1031727D01*
G01X390012Y1026413D02*
Y1028522D01*
X390011Y1028523D01*
G01X395561Y1029617D02*
Y1031726D01*
X395562Y1031727D01*
G01X393712Y1026413D02*
Y1028522D01*
X393711Y1028523D01*
G01X390012Y1020004D02*
Y1022113D01*
X390011Y1022114D01*
G01X388161Y1016800D02*
Y1018909D01*
X388162Y1018910D01*
G01X393712Y1020004D02*
Y1022113D01*
X393711Y1022114D01*
G01X395561Y1016800D02*
Y1018909D01*
X395562Y1018910D01*
G01X390012Y1039230D02*
X390011Y1039231D01*
Y1041340D01*
G01X388161Y1036026D02*
Y1038135D01*
X388162Y1038136D01*
G01X393712Y1039230D02*
X393711Y1039231D01*
Y1041340D01*
G01X395561Y1036026D02*
Y1038135D01*
X395562Y1038136D01*
G01X390011Y1047749D02*
Y1045639D01*
X390012D01*
G01X393711Y1047749D02*
Y1045639D01*
X393712D01*
G01Y1032821D02*
Y1034930D01*
X393711Y1034931D01*
G01X390012Y1032821D02*
Y1034930D01*
X390011Y1034931D01*
G01X397412Y1032821D02*
Y1034930D01*
X397411Y1034931D01*
G01X390012Y1058455D02*
X390011Y1058456D01*
Y1060565D01*
G01X388161Y1055251D02*
X388162Y1055252D01*
Y1057361D01*
G01X393712Y1058455D02*
X393711Y1058456D01*
Y1060565D01*
G01X395561Y1055251D02*
X395562Y1055252D01*
Y1057361D01*
G01X388161Y1048842D02*
G02X388162Y1050952I2226050J0D01*
G01X395561Y1048842D02*
G02X395562Y1050952I2226050J0D01*
G01X393712Y1052047D02*
X393711Y1052048D01*
Y1054157D01*
G01X390012Y1052047D02*
X390011Y1052048D01*
Y1054157D01*
G01X397412Y1052047D02*
X397411Y1052048D01*
Y1054157D01*
G01X390012Y1077681D02*
Y1079790D01*
X390011Y1079791D01*
G01X388161Y1074477D02*
G02X388162Y1076587I2226050J0D01*
G01X393712Y1077681D02*
X393711Y1077682D01*
Y1079791D01*
G01X395561Y1074477D02*
G02X395562Y1076587I2226050J0D01*
G01X388161Y1068068D02*
X388162Y1068069D01*
Y1070178D01*
G01X390012Y1064864D02*
G03X390011Y1066974I-2226050J0D01*
G01X395561Y1068068D02*
X395562Y1068069D01*
Y1070178D01*
G01X393712Y1064864D02*
G03X393711Y1066974I-2226050J0D01*
G01X393712Y1071273D02*
G03X393711Y1073383I-2226050J0D01*
G01X390012Y1071273D02*
G03X390011Y1073383I-2226050J0D01*
G01X397412Y1071273D02*
G03X397411Y1073383I-2226050J0D01*
G01X395561Y1093703D02*
Y1095812D01*
X395562Y1095813D01*
G01X388161Y1087294D02*
Y1089403D01*
X388162Y1089404D01*
G01X390012Y1084090D02*
G03X390011Y1086200I-2226050J0D01*
G01X395561Y1087294D02*
Y1089403D01*
X395562Y1089404D01*
G01X393712Y1084090D02*
G03X393711Y1086200I-2226050J0D01*
G01X388161Y1093703D02*
Y1095812D01*
X388162Y1095813D01*
G01X393712Y1090498D02*
G03X393711Y1092608I-2226050J0D01*
G01X390012Y1090498D02*
G03X390011Y1092608I-2226050J0D01*
G01X397412Y1090498D02*
G03X397411Y1092608I-2226050J0D01*
G01X393712Y1096907D02*
Y1099016D01*
X393711Y1099017D01*
G01X390012Y1096907D02*
Y1099016D01*
X390011Y1099017D01*
G01X482079Y895146D02*
X482078Y895145D01*
Y893036D01*
G01X483928Y898350D02*
X483929Y898349D01*
Y896240D01*
G01X483928Y917576D02*
Y915467D01*
X483929Y915466D01*
G01X483928Y936801D02*
Y934692D01*
X483929Y934691D01*
G01X483928Y956027D02*
X483929Y956026D01*
Y953917D01*
G01X483928Y975253D02*
X483929Y975252D01*
Y973143D01*
G01X480661Y997574D02*
Y999683D01*
X480662Y999684D01*
G01X478812Y1000778D02*
Y1002887D01*
X478811Y1002888D01*
G01X478812Y1007187D02*
Y1009295D01*
G03X478811Y1009297I-3J0D01*
G01X480661Y1010391D02*
Y1012500D01*
X480662Y1012501D01*
G01X484361Y1003983D02*
Y1006092D01*
X484362Y1006093D01*
G01X484361Y1023208D02*
Y1025317D01*
X484362Y1025318D01*
G01X484361Y1042434D02*
Y1044543D01*
X484362Y1044544D01*
G01X484361Y1061660D02*
X484362Y1063653D01*
Y1063770D01*
G01X484361Y1080885D02*
X484362Y1080886D01*
Y1082995D01*
G01X500579Y901555D02*
X500578Y901554D01*
Y899445D01*
G01X485779Y901555D02*
Y899446D01*
X485778Y899445D01*
G01X493179Y901555D02*
X493178Y901554D01*
Y899445D01*
G01X493179Y895146D02*
X493178Y895145D01*
Y893036D01*
G01X496879Y895146D02*
X496878Y895145D01*
Y893036D01*
G01X485779Y895146D02*
X485778Y895145D01*
Y893036D01*
G01X491328Y898350D02*
X491329Y898349D01*
Y896240D01*
G01X487628Y898350D02*
X487629Y898349D01*
Y896240D01*
G01X495028Y898350D02*
X495029Y898349D01*
Y896240D01*
G01X485779Y914372D02*
X485778Y914371D01*
Y912262D01*
G01X487628Y911167D02*
Y909058D01*
X487629Y909057D01*
G01X493179Y914372D02*
X493178Y914371D01*
Y912262D01*
G01X491328Y911167D02*
Y909058D01*
X491329Y909057D01*
G01X500579Y914372D02*
X500578Y914371D01*
Y912262D01*
G01X498728Y911167D02*
Y909058D01*
X498729Y909057D01*
G01X498728Y904759D02*
X498729Y904758D01*
Y902649D01*
G01X487628Y904759D02*
Y902650D01*
X487629Y902649D01*
G01X491328Y904759D02*
X491329Y904758D01*
Y902649D01*
G01X487628Y917576D02*
Y915467D01*
X487629Y915466D01*
G01X500579Y907963D02*
X500578Y907962D01*
Y905853D01*
G01X495028Y917576D02*
Y915467D01*
X495029Y915466D01*
G01X496879Y907963D02*
X496878Y907962D01*
Y905853D01*
G01X491328Y917576D02*
Y915467D01*
X491329Y915466D01*
G01X500579Y933598D02*
X500578Y933597D01*
Y931488D01*
G01X498728Y923985D02*
X498729Y923984D01*
Y921875D01*
G01X500579Y920780D02*
X500578Y920779D01*
Y918670D01*
G01X498728Y930393D02*
X498729Y930392D01*
Y928283D01*
G01X496879Y927189D02*
X496878Y927188D01*
Y925079D01*
G01X500579Y927189D02*
X500578Y927188D01*
Y925079D01*
G01X491328Y923985D02*
X491329Y923984D01*
Y921875D01*
G01X493179Y920780D02*
X493178Y920779D01*
Y918670D01*
G01X485779Y933598D02*
X485778Y933597D01*
Y931488D01*
G01X491328Y930393D02*
X491329Y930392D01*
Y928283D01*
G01X493179Y933598D02*
X493178Y933597D01*
Y931488D01*
G01X487628Y930393D02*
X487629Y930392D01*
Y928283D01*
G01X487628Y923985D02*
X487629Y923984D01*
Y921875D01*
G01X485779Y920780D02*
X485778Y920779D01*
Y918670D01*
G01X498728Y949619D02*
X498729Y949618D01*
Y947509D01*
G01X498728Y943210D02*
X498729Y943209D01*
Y941100D01*
G01X500579Y940006D02*
X500578Y940005D01*
Y937896D01*
G01X496879Y946414D02*
X496878Y946413D01*
Y944304D01*
G01X500579Y946414D02*
X500578Y946413D01*
Y944304D01*
G01X487628Y949619D02*
X487629Y949618D01*
Y947509D01*
G01X491328Y949619D02*
X491329Y949618D01*
Y947509D01*
G01X487628Y943210D02*
X487629Y943209D01*
Y941100D01*
G01X485779Y940006D02*
X485778Y940005D01*
Y937896D01*
G01X491328Y943210D02*
X491329Y943209D01*
Y941100D01*
G01X493179Y940006D02*
X493178Y940005D01*
Y937896D01*
G01X487628Y936801D02*
Y934692D01*
X487629Y934691D01*
G01X495028Y936801D02*
Y934692D01*
X495029Y934691D01*
G01X491328Y936801D02*
Y934692D01*
X491329Y934691D01*
G01X500579Y952823D02*
X500578Y952822D01*
Y950713D01*
G01X496879Y965640D02*
X496878Y965639D01*
Y963530D01*
G01X485779Y952823D02*
X485778Y952822D01*
Y950713D01*
G01X493179Y952823D02*
X493178Y952822D01*
Y950713D01*
G01X491328Y962436D02*
X491329Y962435D01*
Y960326D01*
G01X493179Y959232D02*
X493178Y959231D01*
Y957122D01*
G01X487628Y962436D02*
X487629Y962435D01*
Y960326D01*
G01X485779Y959232D02*
X485778Y959231D01*
Y957122D01*
G01X500579Y959232D02*
X500578Y959231D01*
Y957122D01*
G01X498728Y962436D02*
X498729Y962435D01*
Y960326D01*
G01X495028Y956027D02*
X495029Y956026D01*
Y953917D01*
G01X487628Y956027D02*
X487629Y956026D01*
Y953917D01*
G01X491328Y956027D02*
X491329Y956026D01*
Y953917D01*
G01X487628Y981662D02*
X487629Y981661D01*
Y979552D01*
G01X485779Y978457D02*
X485778Y978456D01*
Y976347D01*
G01X491328Y981662D02*
X491329Y981661D01*
Y979552D01*
G01X493179Y978457D02*
X493178Y978456D01*
Y976347D01*
G01X498728Y981662D02*
X498729Y981661D01*
Y979552D01*
G01X500579Y978457D02*
X500578Y978456D01*
Y976347D01*
G01X495028Y975253D02*
X495029Y975252D01*
Y973143D01*
G01X487628Y975253D02*
X487629Y975252D01*
Y973143D01*
G01X491328Y975253D02*
X491329Y975252D01*
Y973143D01*
G01X485779Y972049D02*
X485778Y972048D01*
Y969939D01*
G01X487628Y968845D02*
X487629Y968844D01*
Y966735D01*
G01X491328Y968845D02*
X491329Y968844D01*
Y966735D01*
G01X493179Y972049D02*
X493178Y972048D01*
Y969939D01*
G01X500579Y972049D02*
X500578Y972048D01*
Y969939D01*
G01X498728Y968845D02*
X498729Y968844D01*
Y966735D01*
G01X499161Y997574D02*
Y999683D01*
X499162Y999684D01*
G01X500579Y984866D02*
X500578Y984865D01*
Y982756D01*
G01X496879Y984866D02*
X496878Y984865D01*
Y982756D01*
G01X488061Y997574D02*
Y999683D01*
X488062Y999684D01*
G01X491761Y997574D02*
Y999683D01*
X491762Y999684D01*
G01X501012Y1000778D02*
X501011Y1000779D01*
Y1002888D01*
G01X497312Y1013595D02*
X497311Y1015705D01*
G01X499161Y1010391D02*
Y1012500D01*
X499162Y1012501D01*
G01X501012Y1007187D02*
X501011Y1007188D01*
Y1009297D01*
G01X495461Y1003983D02*
X495462Y1003984D01*
Y1006093D01*
G01X486212Y1000778D02*
X486211Y1000779D01*
Y1002888D01*
G01X493612Y1000778D02*
Y1002887D01*
X493611Y1002888D01*
G01X491761Y1010391D02*
Y1012501D01*
G01X493612Y1007187D02*
X493611Y1007188D01*
Y1009297D01*
G01X488061Y1010391D02*
Y1012500D01*
X488062Y1012501D01*
G01X486212Y1007187D02*
Y1009296D01*
X486211Y1009297D01*
G01X499161Y1029617D02*
X499162Y1029618D01*
Y1031727D01*
G01X501012Y1026413D02*
Y1028521D01*
X501011Y1028522D01*
Y1028523D01*
G01X499161Y1016800D02*
X499162Y1016801D01*
Y1018910D01*
G01X488061Y1029617D02*
X488062Y1029618D01*
Y1031727D01*
G01X486212Y1026413D02*
Y1028521D01*
X486211Y1028522D01*
Y1028523D01*
G01X491761Y1029617D02*
X491762Y1029618D01*
Y1031727D01*
G01X493612Y1026413D02*
Y1028521D01*
X493611Y1028522D01*
Y1028523D01*
G01X486212Y1020004D02*
Y1020053D01*
X486211Y1022114D01*
G01X488061Y1016800D02*
X488062Y1016801D01*
Y1018910D01*
G01X493612Y1020004D02*
Y1020053D01*
X493611Y1022114D01*
G01X491761Y1016800D02*
X491762Y1016801D01*
Y1018910D01*
G01X488061Y1023208D02*
Y1025317D01*
X488062Y1025318D01*
G01X495461Y1023208D02*
Y1025317D01*
X495462Y1025318D01*
G01X491761Y1023208D02*
Y1025317D01*
X491762Y1025318D01*
G01X501012Y1039230D02*
Y1041339D01*
X501011Y1041340D01*
G01X499161Y1036026D02*
Y1038135D01*
X499162Y1038136D01*
G01X501012Y1032821D02*
Y1034930D01*
X501011Y1034931D01*
G01X497312Y1032821D02*
Y1034930D01*
X497311Y1034931D01*
G01X486212Y1045639D02*
Y1047748D01*
X486211Y1047749D01*
G01X493612Y1045639D02*
Y1047748D01*
X493611Y1047749D01*
G01X486212Y1039230D02*
Y1041339D01*
X486211Y1041340D01*
G01X488061Y1036026D02*
Y1038135D01*
X488062Y1038136D01*
G01X493612Y1039230D02*
Y1041339D01*
X493611Y1041340D01*
G01X491761Y1036026D02*
Y1038135D01*
X491762Y1038136D01*
G01X488061Y1042434D02*
Y1044543D01*
X488062Y1044544D01*
G01X495461Y1042434D02*
Y1044543D01*
X495462Y1044544D01*
G01X491761Y1042434D02*
Y1044543D01*
X491762Y1044544D01*
G01X501012Y1058455D02*
Y1060564D01*
X501011Y1060565D01*
G01X499161Y1055251D02*
Y1057360D01*
X499162Y1057361D01*
G01X499161Y1048842D02*
Y1050951D01*
X499162Y1050952D01*
G01X501012Y1045639D02*
Y1047748D01*
X501011Y1047749D01*
G01X501012Y1052047D02*
X501011Y1052048D01*
Y1054157D01*
G01X497312Y1052047D02*
X497311Y1052048D01*
Y1054157D01*
G01X486212Y1058455D02*
Y1060564D01*
X486211Y1060565D01*
G01X488061Y1055251D02*
Y1057360D01*
X488062Y1057361D01*
G01X493612Y1058455D02*
Y1060564D01*
X493611Y1060565D01*
G01X491761Y1055251D02*
Y1057360D01*
X491762Y1057361D01*
G01X488061Y1048842D02*
Y1050951D01*
X488062Y1050952D01*
G01X491761Y1048842D02*
Y1050951D01*
X491762Y1050952D01*
G01X488061Y1061660D02*
X488062Y1063653D01*
Y1063770D01*
G01X495461Y1061660D02*
X495462Y1063653D01*
Y1063770D01*
G01X491761Y1061660D02*
X491762Y1063653D01*
Y1063770D01*
G01X499161Y1068068D02*
X499162Y1070178D01*
G01X501012Y1064864D02*
Y1066973D01*
X501011Y1066974D01*
G01X499161Y1074477D02*
Y1076586D01*
X499162Y1076587D01*
G01X497312Y1071273D02*
X497311Y1073383D01*
G01X486212Y1077681D02*
Y1079790D01*
X486211Y1079791D01*
G01X488061Y1074477D02*
Y1076586D01*
X488062Y1076587D01*
G01X493612Y1077681D02*
Y1079790D01*
X493611Y1079791D01*
G01X491761Y1074477D02*
Y1076586D01*
X491762Y1076587D01*
G01X488061Y1068068D02*
X488062Y1070178D01*
G01X486212Y1064864D02*
Y1066973D01*
X486211Y1066974D01*
G01X491761Y1068068D02*
X491762Y1070178D01*
G01X493612Y1064864D02*
Y1066973D01*
X493611Y1066974D01*
G01X501012Y1077681D02*
Y1079790D01*
X501011Y1079791D01*
G01X491761Y1087294D02*
X491762Y1089404D01*
G01X493612Y1084090D02*
Y1086199D01*
X493611Y1086200D01*
G01X499161Y1087294D02*
X499162Y1089404D01*
G01X501012Y1084090D02*
Y1086199D01*
X501011Y1086200D01*
G01X488061Y1087294D02*
X488062Y1089404D01*
G01X486212Y1084090D02*
Y1086199D01*
X486211Y1086200D01*
G01X497312Y1090498D02*
Y1092607D01*
X497311Y1092608D01*
G01X495461Y1080885D02*
X495462Y1080886D01*
Y1082995D01*
G01X501012Y1090498D02*
Y1092607D01*
X501011Y1092608D01*
G01X488061Y1080885D02*
X488062Y1080886D01*
Y1082995D01*
G01X491761Y1080885D02*
X491762Y1080886D01*
Y1082995D01*
G01X511679Y901555D02*
X511678Y901554D01*
Y899445D01*
G01X511679Y895146D02*
X511678Y895145D01*
Y893036D01*
G01X507979Y895146D02*
X507978Y895145D01*
Y893036D01*
G01X509828Y898350D02*
X509829Y898349D01*
Y896240D01*
G01X517228Y898350D02*
X517229Y898349D01*
Y896240D01*
G01X513528Y898350D02*
X513529Y898349D01*
Y896240D01*
G01X504279Y901555D02*
X504278Y901554D01*
Y899445D01*
G01X513528Y904759D02*
X513529Y904758D01*
Y902649D01*
G01X517228Y904759D02*
X517229Y904758D01*
Y902649D01*
G01X511679Y914372D02*
X511678Y914371D01*
Y912262D01*
G01X513528Y911167D02*
Y909058D01*
X513529Y909057D01*
G01X517228Y911167D02*
Y909058D01*
X517229Y909057D01*
G01X513528Y917576D02*
Y915467D01*
X513529Y915466D01*
G01X509828Y917576D02*
Y915467D01*
X509829Y915466D01*
G01X517228Y917576D02*
Y915467D01*
X517229Y915466D01*
G01X504279Y914372D02*
X504278Y914371D01*
Y912262D01*
G01X506128Y911167D02*
Y909058D01*
X506129Y909057D01*
G01X506128Y904759D02*
X506129Y904758D01*
Y902649D01*
G01X507979Y907963D02*
X507978Y907962D01*
Y905853D01*
G01X504279Y907963D02*
X504278Y907962D01*
Y905853D01*
G01X511679Y933598D02*
X511678Y933597D01*
Y931488D01*
G01X513528Y930393D02*
X513529Y930392D01*
Y928283D01*
G01X517228Y930393D02*
X517229Y930392D01*
Y928283D01*
G01X506128Y930393D02*
X506129Y930392D01*
Y928283D01*
G01X506128Y923985D02*
X506129Y923984D01*
Y921875D01*
G01X504279Y920780D02*
X504278Y920779D01*
Y918670D01*
G01X513528Y923985D02*
X513529Y923984D01*
Y921875D01*
G01X511679Y920780D02*
X511678Y920779D01*
Y918670D01*
G01X517228Y923985D02*
X517229Y923984D01*
Y921875D01*
G01X504279Y933598D02*
X504278Y933597D01*
Y931488D01*
G01X504279Y927189D02*
X504278Y927188D01*
Y925079D01*
G01X507979Y927189D02*
X507978Y927188D01*
Y925079D01*
G01X513528Y943210D02*
X513529Y943209D01*
Y941100D01*
G01X511679Y940006D02*
X511678Y940005D01*
Y937896D01*
G01X517228Y943210D02*
X517229Y943209D01*
Y941100D01*
G01X513528Y936801D02*
X513529D01*
Y934691D01*
G01X509828Y936801D02*
X509829D01*
Y934691D01*
G01X517228Y936801D02*
X517229D01*
Y934691D01*
G01X513528Y949619D02*
X513529Y949618D01*
Y947509D01*
G01X517228Y949619D02*
X517229Y949618D01*
Y947509D01*
G01X506128Y949619D02*
X506129Y949618D01*
Y947509D01*
G01X506128Y943210D02*
X506129Y943209D01*
Y941100D01*
G01X504279Y940006D02*
X504278Y940005D01*
Y937896D01*
G01X507979Y946414D02*
X507978Y946413D01*
Y944304D01*
G01X504279Y946414D02*
X504278Y946413D01*
Y944304D01*
G01X511679Y952823D02*
X511678Y952822D01*
Y950713D01*
G01X513528Y962436D02*
X513529Y962435D01*
Y960326D01*
G01X511679Y959232D02*
X511678Y959231D01*
Y957122D01*
G01X517228Y962436D02*
X517229Y962435D01*
Y960326D01*
G01X504279Y952823D02*
X504278Y952822D01*
Y950713D01*
G01X513528Y956027D02*
X513529Y956026D01*
Y953917D01*
G01X517228Y956027D02*
X517229Y956026D01*
Y953917D01*
G01X509828Y956027D02*
X509829Y956026D01*
Y953917D01*
G01X504279Y959232D02*
X504278Y959231D01*
Y957122D01*
G01X506128Y962436D02*
X506129Y962435D01*
Y960326D01*
G01X507979Y965640D02*
X507978Y965639D01*
Y963530D01*
G01X504279Y978457D02*
X504278Y978456D01*
Y976347D01*
G01X506128Y981662D02*
Y979553D01*
X506129Y979552D01*
G01X513528Y981662D02*
X513529Y981661D01*
Y979552D01*
G01X517228Y981662D02*
X517229Y981661D01*
Y979552D01*
G01X511679Y978457D02*
Y976348D01*
X511678Y976347D01*
G01X509828Y975253D02*
X509829Y975252D01*
Y973143D01*
G01X517228Y968845D02*
X517229Y968844D01*
Y966735D01*
G01X511679Y972049D02*
X511678Y972048D01*
Y969939D01*
G01X513528Y968845D02*
X513529Y968844D01*
Y966735D01*
G01X504279Y972049D02*
X504278Y972048D01*
Y969939D01*
G01X506128Y968845D02*
X506129Y968844D01*
Y966735D01*
G01X506561Y997574D02*
Y999684D01*
G01X507979Y984866D02*
X507978Y984865D01*
Y982756D01*
G01X504279Y984866D02*
X504278Y984865D01*
Y982756D01*
G01X513961Y997574D02*
X513962Y997575D01*
Y999684D01*
G01X513961Y1003983D02*
Y1006092D01*
X513962Y1006093D01*
G01X510261Y1003983D02*
Y1006092D01*
X510262Y1006093D01*
G01X504712Y1000778D02*
Y1002887D01*
X504711Y1002888D01*
G01X513961Y1010391D02*
Y1012500D01*
X513962Y1012501D01*
G01X512112Y1007187D02*
X512111Y1007188D01*
Y1009297D01*
G01X508412Y1013595D02*
X508411Y1015705D01*
G01X506561Y1010391D02*
Y1012500D01*
X506562Y1012501D01*
G01X504712Y1007187D02*
Y1009296D01*
X504711Y1009297D01*
G01X512112Y1000778D02*
Y1002887D01*
X512111Y1002888D01*
G01X513961Y1029617D02*
Y1031726D01*
X513962Y1031727D01*
G01X512112Y1026413D02*
Y1028521D01*
X512111Y1028522D01*
Y1028523D01*
G01X512112Y1020004D02*
Y1020053D01*
X512111Y1022114D01*
G01X513961Y1016800D02*
X513962Y1016801D01*
Y1018910D01*
G01X513961Y1023208D02*
Y1025317D01*
X513962Y1025318D01*
G01X510261Y1023208D02*
Y1025317D01*
X510262Y1025318D01*
G01X506561Y1029617D02*
X506562Y1029618D01*
Y1031727D01*
G01X504712Y1026413D02*
Y1028521D01*
X504711Y1028522D01*
Y1028523D01*
G01X504712Y1020004D02*
Y1020053D01*
X504711Y1022114D01*
G01X506561Y1016800D02*
X506562Y1016801D01*
Y1018910D01*
G01X501012Y1020004D02*
Y1020053D01*
X501011Y1022114D01*
G01X504712Y1039230D02*
Y1041339D01*
X504711Y1041340D01*
G01X506561Y1036026D02*
Y1038135D01*
X506562Y1038136D01*
G01X512112Y1045639D02*
Y1047748D01*
X512111Y1047749D01*
G01X512112Y1039230D02*
Y1041339D01*
X512111Y1041340D01*
G01X513961Y1036026D02*
Y1038135D01*
X513962Y1038136D01*
G01X504712Y1045639D02*
Y1047748D01*
X504711Y1047749D01*
G01X510261Y1042434D02*
Y1044543D01*
X510262Y1044544D01*
G01X508412Y1032821D02*
Y1034930D01*
X508411Y1034931D01*
G01X513961Y1042434D02*
Y1044543D01*
X513962Y1044544D01*
G01X504712Y1032821D02*
Y1034930D01*
X504711Y1034931D01*
G01X512112Y1058455D02*
Y1060564D01*
X512111Y1060565D01*
G01X513961Y1055251D02*
Y1057360D01*
X513962Y1057361D01*
G01X510261Y1061660D02*
X510262Y1063653D01*
Y1063770D01*
G01X513961Y1061660D02*
X513962Y1063653D01*
Y1063770D01*
G01X513961Y1048842D02*
Y1050951D01*
X513962Y1050952D01*
G01X504712Y1058455D02*
Y1060564D01*
X504711Y1060565D01*
G01X506561Y1055251D02*
X506562Y1055252D01*
Y1057361D01*
G01X506561Y1048842D02*
Y1050951D01*
X506562Y1050952D01*
G01X508412Y1052047D02*
X508411Y1052048D01*
Y1054157D01*
G01X504712Y1052047D02*
X504711Y1052048D01*
Y1054157D01*
G01X513961Y1068068D02*
X513962Y1070178D01*
G01X512112Y1064864D02*
Y1066973D01*
X512111Y1066974D01*
G01X504712Y1077681D02*
Y1079790D01*
X504711Y1079791D01*
G01X506561Y1074477D02*
Y1076586D01*
X506562Y1076587D01*
G01X506561Y1068068D02*
X506562Y1070178D01*
G01X504712Y1064864D02*
Y1066973D01*
X504711Y1066974D01*
G01X512112Y1077681D02*
Y1079790D01*
X512111Y1079791D01*
G01X513961Y1074477D02*
Y1076586D01*
X513962Y1076587D01*
G01X508412Y1071273D02*
X508411Y1073383D01*
G01X501012Y1071273D02*
X501011Y1073383D01*
G01X504712Y1071273D02*
X504711Y1073383D01*
G01X513961Y1087294D02*
X513962Y1089404D01*
G01X512112Y1084090D02*
Y1086199D01*
X512111Y1086200D01*
G01X513961Y1080885D02*
X513962Y1080886D01*
Y1082995D01*
G01X510261Y1080885D02*
X510262Y1080886D01*
Y1082995D01*
G01X510261Y1093703D02*
Y1095812D01*
X510262Y1095813D01*
G01X506561Y1093703D02*
Y1095813D01*
G01Y1087294D02*
X506562Y1089404D01*
G01X504712Y1084090D02*
Y1086199D01*
X504711Y1086200D01*
G01X508412Y1090498D02*
Y1092607D01*
X508411Y1092608D01*
G01X504712Y1090498D02*
Y1092607D01*
X504711Y1092608D01*
G01X515812Y1096907D02*
Y1099016D01*
X515811Y1099017D01*
G01X532028Y866307D02*
X532029Y866306D01*
Y864197D01*
G01X526479Y899445D02*
Y901555D01*
G01X530179D02*
X530178Y901554D01*
Y899445D01*
G01X519079Y901555D02*
X519078Y901554D01*
Y899445D01*
G01X519079Y895146D02*
X519078Y895145D01*
Y893036D01*
G01X522779Y895146D02*
X522778Y895145D01*
Y893036D01*
G01X520928Y898350D02*
X520929Y898349D01*
Y896240D01*
G01X530179Y914372D02*
Y912262D01*
G01X532028Y911167D02*
Y909058D01*
X532029Y909057D01*
G01X524628Y904759D02*
X524629Y904758D01*
Y902649D01*
G01X532028Y904759D02*
X532029Y904758D01*
Y902649D01*
G01X526479Y914372D02*
Y912262D01*
G01X524628Y911167D02*
Y909058D01*
X524629Y909057D01*
G01X526479Y907963D02*
Y905853D01*
G01X522779Y907963D02*
X522778Y907962D01*
Y905853D01*
G01X530179D02*
Y907963D01*
G01X519079Y914372D02*
X519078Y914371D01*
Y912262D01*
G01X520928Y917576D02*
Y915467D01*
X520929Y915466D01*
G01X526479Y933598D02*
Y931488D01*
G01X524628Y930393D02*
X524629Y930392D01*
Y928283D01*
G01X530179Y933598D02*
Y931488D01*
G01X532028Y930393D02*
Y928284D01*
X532029Y928283D01*
G01X524628Y923985D02*
X524629Y923984D01*
Y921875D01*
G01X526479Y920780D02*
Y918670D01*
G01X532028Y923985D02*
Y921876D01*
X532029Y921875D01*
G01X530179Y920780D02*
Y918670D01*
G01X526479Y927189D02*
Y925079D01*
G01X522779Y927189D02*
X522778Y927188D01*
Y925079D01*
G01X530179Y927189D02*
Y925079D01*
G01X519079Y933598D02*
X519078Y933597D01*
Y931488D01*
G01X519079Y920780D02*
X519078Y920779D01*
Y918670D01*
G01X524628Y943210D02*
X524629Y943209D01*
Y941100D01*
G01X526479Y940006D02*
Y937896D01*
G01X532028Y943210D02*
Y941101D01*
X532029Y941100D01*
G01X530179Y940006D02*
Y937896D01*
G01X524628Y949619D02*
Y947510D01*
X524629Y947509D01*
G01X532028Y949619D02*
Y947510D01*
X532029Y947509D01*
G01X519079Y940006D02*
X519078Y940005D01*
Y937896D01*
G01X520928Y936801D02*
X520929Y934691D01*
G01X526479Y946414D02*
Y944304D01*
G01X530179Y946414D02*
Y944305D01*
X530178Y944304D01*
G01X522779Y946414D02*
Y944305D01*
X522778Y944304D01*
G01X522779Y965640D02*
X522778Y965639D01*
Y963530D01*
G01X526479Y952823D02*
Y950713D01*
G01X530179Y952823D02*
X530178Y952822D01*
Y950713D01*
G01X532028Y962436D02*
Y960327D01*
X532029Y960326D01*
G01X530179Y959232D02*
X530178Y959231D01*
Y957122D01*
G01X524628Y962436D02*
X524629Y962435D01*
Y960326D01*
G01X526479Y959232D02*
Y957122D01*
G01X519079Y952823D02*
X519078Y952822D01*
Y950713D01*
G01X519079Y959232D02*
X519078Y959231D01*
Y957122D01*
G01X520928Y956027D02*
X520929Y956026D01*
Y953917D01*
G01X572194Y1011133D02*
X586993D01*
X614727Y1022621D01*
X618533Y1026427D01*
X621685D01*
X623080Y1027822D01*
X625249D01*
G01X571817Y1008615D02*
X587888D01*
X618099Y1021129D01*
X625249D01*
G01X579181Y981238D02*
X594488Y996545D01*
X621111D01*
X623299Y994357D01*
X625249D01*
G01X581521Y979999D02*
X595350Y993828D01*
X620445D01*
X621227Y993046D01*
G01X629227Y992755D02*
X634627D01*
X636371Y991011D01*
X641391D01*
G01X526479Y972049D02*
Y969939D01*
G01X530179Y972049D02*
Y969939D01*
G01X524628Y968845D02*
X524629Y968844D01*
Y966735D01*
G01X532028Y968845D02*
X532029Y968844D01*
Y966735D01*
G01X519079Y978457D02*
Y976348D01*
X519078Y976347D01*
G01X519079Y972049D02*
X519078Y972048D01*
Y969939D01*
G01X520928Y975253D02*
X520929Y975252D01*
Y973143D01*
G01X641391Y1021129D02*
X639130D01*
X638186Y1022073D01*
X637311D01*
X636295Y1021057D01*
X635642Y1019408D01*
X631770Y1015536D01*
X629789Y1014391D01*
X624097Y1012862D01*
X623752Y1012263D01*
X621462Y1011649D01*
X620861Y1011995D01*
X618573Y1011381D01*
X618227Y1010779D01*
X615937Y1010165D01*
X615336Y1010511D01*
X613048Y1009897D01*
X612702Y1009295D01*
X610412Y1008681D01*
X609811Y1009027D01*
X607523Y1008413D01*
X607177Y1007812D01*
X604887Y1007197D01*
X604286Y1007543D01*
X601998Y1006929D01*
X601652Y1006328D01*
X599362Y1005714D01*
X598762Y1006060D01*
X594013Y1004785D01*
X587099D01*
X586614Y1004300D01*
X584244D01*
X583759Y1004785D01*
X581389D01*
X580904Y1004300D01*
X578534D01*
X578049Y1004785D01*
X575679D01*
X575194Y1004300D01*
X572824D01*
X572339Y1004785D01*
X569936D01*
X568122Y1002971D01*
G01X671091Y1024475D02*
X669270D01*
X668142Y1023347D01*
X667358D01*
X666412Y1022954D01*
X660457Y1016539D01*
X660394Y1016471D01*
X659586Y1015942D01*
X659466Y1015898D01*
X622190Y1007386D01*
X622191Y1007385D01*
X620628Y1007028D01*
Y1007029D01*
X619064Y1006671D01*
X593186Y1001931D01*
X591548Y1001782D01*
X577436D01*
G01X641391Y1024475D02*
X639266D01*
X638154Y1023363D01*
X636775D01*
X635193Y1021781D01*
X634542Y1020134D01*
X630975Y1016567D01*
X629293Y1015596D01*
X598427Y1007307D01*
Y1007306D01*
X593842Y1006075D01*
X569401D01*
X567209Y1003883D01*
G01X517661Y997574D02*
Y999684D01*
G01X532461Y997574D02*
Y999684D01*
G01X525061Y997574D02*
X525062Y997575D01*
Y999684D01*
G01X517661Y1003983D02*
Y1006092D01*
X517662Y1006093D01*
G01X521361Y1003983D02*
Y1006092D01*
X521362Y1006093D01*
G01X523212Y1013595D02*
Y1015704D01*
X523211Y1015705D01*
G01X525061Y1010391D02*
Y1012500D01*
X525062Y1012501D01*
G01X532461D02*
Y1010391D01*
G01X526912Y1007187D02*
X526911Y1007188D01*
Y1009297D01*
G01X530612Y1007187D02*
Y1009296D01*
X530611Y1009297D01*
G01X517661Y1010391D02*
Y1012500D01*
X517662Y1012501D01*
G01X519512Y1007187D02*
Y1009296D01*
X519511Y1009297D01*
G01X519512Y1000778D02*
Y1002887D01*
X519513Y1002888D01*
G01X530612Y1000778D02*
Y1002887D01*
X530611Y1002888D01*
G01X526912Y1000778D02*
Y1002887D01*
X526911Y1002888D01*
G01X525061Y1029617D02*
X525062Y1029618D01*
Y1031727D01*
G01X526912Y1026413D02*
Y1028521D01*
X526911Y1028522D01*
Y1028523D01*
G01X532461Y1029617D02*
Y1031727D01*
G01X530612Y1026413D02*
Y1028521D01*
X530611Y1028522D01*
Y1028523D01*
G01X530612Y1020004D02*
Y1020053D01*
X530611Y1022114D01*
G01X532461Y1016800D02*
Y1018910D01*
G01X526912Y1020004D02*
Y1022113D01*
X526911Y1022114D01*
G01X525061Y1016800D02*
X525062Y1016801D01*
Y1018910D01*
G01X517661Y1029617D02*
X517662Y1029618D01*
Y1031727D01*
G01X519512Y1026413D02*
Y1028521D01*
X519511Y1028522D01*
Y1028523D01*
G01X519512Y1020004D02*
Y1020053D01*
X519511Y1022114D01*
G01X517661Y1016800D02*
X517662Y1016801D01*
Y1018910D01*
G01X521361Y1023208D02*
X521362Y1023209D01*
Y1025318D01*
G01X517661Y1023208D02*
X517662Y1023209D01*
Y1025318D01*
G01X526912Y1039230D02*
Y1041339D01*
X526911Y1041340D01*
G01X525061Y1036026D02*
X525062Y1036027D01*
Y1038136D01*
G01X530612Y1039230D02*
Y1041339D01*
X530611Y1041340D01*
G01X532461Y1036026D02*
Y1038136D01*
G01X526912Y1045639D02*
Y1047747D01*
X526911Y1047748D01*
Y1047749D01*
G01X530612Y1045639D02*
Y1047748D01*
X530611Y1047749D01*
G01X526912Y1032821D02*
Y1034930D01*
X526911Y1034931D01*
G01X523212Y1032821D02*
Y1034930D01*
X523211Y1034931D01*
G01X530612Y1032821D02*
Y1034930D01*
X530611Y1034931D01*
G01X519512Y1045639D02*
Y1047748D01*
X519511Y1047749D01*
G01X519512Y1039230D02*
Y1041339D01*
X519511Y1041340D01*
G01X517661Y1036026D02*
Y1038135D01*
X517662Y1038136D01*
G01X521361Y1042434D02*
Y1044543D01*
X521362Y1044544D01*
G01X517661Y1042434D02*
Y1044543D01*
X517662Y1044544D01*
G01X519512Y1058455D02*
Y1060564D01*
X519511Y1060565D01*
G01X517661Y1055251D02*
Y1057360D01*
X517662Y1057361D01*
G01X526912Y1058455D02*
Y1060564D01*
X526911Y1060565D01*
G01X525061Y1055251D02*
Y1057360D01*
X525062Y1057361D01*
G01X530612Y1058455D02*
Y1060564D01*
X530611Y1060565D01*
G01X532461Y1055251D02*
Y1057360D01*
X532462Y1057361D01*
G01X525061Y1048842D02*
Y1050952D01*
G01X532461Y1048842D02*
X532462Y1050953D01*
G01X523212Y1052047D02*
Y1054156D01*
X523211Y1054157D01*
G01X521361Y1061660D02*
X521362Y1063653D01*
Y1063770D01*
G01X526912Y1052047D02*
Y1054156D01*
X526911Y1054157D01*
G01X517661Y1061660D02*
X517662Y1063653D01*
Y1063770D01*
G01X530612Y1052047D02*
Y1054156D01*
X530611Y1054157D01*
G01X517661Y1048842D02*
Y1050951D01*
X517662Y1050952D01*
G01X530612Y1077681D02*
Y1079790D01*
X530611Y1079791D01*
G01X532461Y1074477D02*
Y1076586D01*
X532462Y1076587D01*
G01X525061Y1068068D02*
X525062Y1070178D01*
G01X526912Y1064864D02*
Y1066973D01*
X526911Y1066974D01*
G01X532461Y1068068D02*
X532462Y1070178D01*
G01X530612Y1064864D02*
Y1066973D01*
X530611Y1066974D01*
G01X526912Y1077681D02*
Y1079790D01*
X526911Y1079791D01*
G01X525061Y1074477D02*
Y1076586D01*
X525062Y1076587D01*
G01X523212Y1071273D02*
Y1073382D01*
X523211Y1073383D01*
G01X526912Y1071273D02*
Y1073382D01*
X526911Y1073383D01*
G01X530612Y1071273D02*
Y1073382D01*
X530611Y1073383D01*
G01X517661Y1068068D02*
X517662Y1070178D01*
G01X519512Y1064864D02*
Y1066973D01*
X519511Y1066974D01*
G01X519512Y1077681D02*
Y1079790D01*
X519511Y1079791D01*
G01X517661Y1074477D02*
Y1076586D01*
X517662Y1076587D01*
G01X521361Y1093703D02*
Y1095812D01*
X521362Y1095813D01*
G01X532461Y1093703D02*
Y1095813D01*
G01X525061Y1093703D02*
Y1095812D01*
X525062Y1095813D01*
G01X525061Y1087294D02*
X525062Y1089404D01*
G01X526912Y1084090D02*
Y1086199D01*
X526911Y1086200D01*
G01X532461Y1087294D02*
Y1089403D01*
X532462Y1089404D01*
G01X530612Y1084090D02*
Y1086199D01*
X530611Y1086200D01*
G01X526912Y1090498D02*
Y1092607D01*
X526911Y1092608D01*
G01X523212Y1090498D02*
Y1092607D01*
X523211Y1092608D01*
G01X530612Y1090498D02*
Y1092607D01*
X530611Y1092608D01*
G01X517661Y1087294D02*
X517662Y1089404D01*
G01X519512Y1084090D02*
Y1086199D01*
X519511Y1086200D01*
G01X521361Y1080885D02*
X521362Y1080886D01*
Y1082995D01*
G01X517661Y1080885D02*
X517662Y1080886D01*
Y1082995D01*
G01X530612Y1096907D02*
Y1099016D01*
X530611Y1099017D01*
G01X517661Y1100111D02*
Y1102220D01*
X517662Y1102221D01*
G01X548285Y845844D02*
X545242Y842801D01*
X541921Y834782D01*
Y819845D01*
X542776Y815545D01*
X548390Y801993D01*
X559668Y790715D01*
X579545Y777434D01*
X585025Y774841D01*
X590706Y773118D01*
X599192Y771859D01*
X621227D01*
G01X629227Y771880D02*
X630966D01*
X635158Y770144D01*
X641391D01*
G01X551587Y837984D02*
X551312Y837709D01*
X549476Y833277D01*
Y820597D01*
X550044Y817742D01*
X554700Y806502D01*
X564881Y796321D01*
X567422Y794622D01*
X568451Y794828D01*
X569792Y793932D01*
X569996Y792903D01*
X571254Y792063D01*
X572348Y792281D01*
X573559Y794093D01*
X574654Y794311D01*
X575587Y793688D01*
X575805Y792593D01*
X574594Y790781D01*
X574812Y789687D01*
X575746Y789063D01*
X576840Y789281D01*
X577547Y790339D01*
X578643Y790557D01*
X579575Y789934D01*
X579793Y788839D01*
X579086Y787781D01*
X579304Y786686D01*
X582273Y784702D01*
X587131Y782404D01*
X611731D01*
X614704Y779431D01*
X617463D01*
X618216Y780184D01*
X625249D01*
G01X550065Y844007D02*
X547338Y841280D01*
X544439Y834280D01*
Y820097D01*
X545199Y816277D01*
X550493Y803497D01*
X561407Y792583D01*
X580796Y779629D01*
X585113Y777586D01*
X586167Y777266D01*
X592683D01*
X594237Y775712D01*
X595357D01*
X596911Y777266D01*
X598083D01*
X598873Y776476D01*
Y775286D01*
X599663Y774496D01*
X600783D01*
X601573Y775286D01*
Y776476D01*
X602363Y777266D01*
X603483D01*
X604273Y776476D01*
Y775365D01*
X605063Y774575D01*
X606183D01*
X606973Y775365D01*
Y776476D01*
X607763Y777266D01*
X609064D01*
X609908Y776422D01*
Y775167D01*
X610680Y774395D01*
X620438D01*
X621342Y773491D01*
X625249D01*
G01X552031Y842040D02*
X549211Y839220D01*
X546957Y833779D01*
Y820350D01*
X547622Y817008D01*
X552596Y805000D01*
X563145Y794451D01*
X582039Y781827D01*
X585040Y780407D01*
X586889Y779846D01*
X610660D01*
X613593Y776913D01*
X618364D01*
X620000Y778549D01*
X621027D01*
G01X629527Y778573D02*
X631044D01*
X632780Y776837D01*
X641391D01*
G01X543129Y851380D02*
Y853490D01*
G01X539428D02*
X539429Y853489D01*
Y851380D01*
G01X537579Y856694D02*
Y854584D01*
G01X535729Y866307D02*
Y864197D01*
G01X543129Y866307D02*
Y864198D01*
X543128Y864197D01*
G01X546828Y866307D02*
Y864197D01*
G01X535729Y857789D02*
Y859899D01*
G01X533879Y856694D02*
Y854584D01*
G01X543129Y859899D02*
Y857790D01*
X543130Y857789D01*
G01X539428Y859899D02*
X539447Y857807D01*
X539429Y857789D01*
G01X541279Y863103D02*
X541298Y861012D01*
X541279Y860993D01*
G01Y854584D02*
Y856694D01*
G01X539428Y885533D02*
Y883424D01*
X539429Y883423D01*
G01X537579Y882329D02*
Y880220D01*
X537578Y880219D01*
G01X543129Y885533D02*
Y883423D01*
G01X544979Y882329D02*
Y880219D01*
G01X537579Y875920D02*
Y873811D01*
X537578Y873810D01*
G01X539428Y872716D02*
Y870607D01*
X539429Y870606D01*
G01X544979Y875920D02*
Y873810D01*
G01X543129Y870606D02*
Y872716D01*
G01X539428Y879124D02*
Y877014D01*
G01X546828Y879124D02*
Y877014D01*
G01X535729Y879124D02*
Y877014D01*
G01X543129Y879124D02*
Y877014D01*
G01X556310Y830178D02*
Y820447D01*
X560386Y810606D01*
X562426Y808566D01*
X562425D01*
X569557Y801435D01*
X571366Y800686D01*
X578545D01*
X589971Y789260D01*
X615329D01*
X616929Y787659D01*
X618376Y787059D01*
X618382Y787057D01*
X618831Y786885D01*
X620310D01*
X620318Y786877D01*
X625249D01*
G01X553284Y831289D02*
Y827425D01*
X553774Y826935D01*
Y824565D01*
X553284Y824075D01*
Y822592D01*
X554326Y817358D01*
X554925Y815912D01*
X555565Y815647D01*
X556473Y813456D01*
X556208Y812816D01*
X557880Y808779D01*
X558843Y807816D01*
X559536D01*
X561213Y806139D01*
Y805446D01*
X562888Y803771D01*
X563581D01*
X565258Y802094D01*
Y801401D01*
X567038Y799621D01*
X570546Y798168D01*
X575329D01*
X577834Y797131D01*
X579797Y795168D01*
X580490D01*
X582167Y793491D01*
Y792798D01*
X583842Y791123D01*
X584535D01*
X586212Y789446D01*
Y788753D01*
X588731Y786234D01*
X590551D01*
X591041Y786724D01*
X593411D01*
X593901Y786234D01*
X596271D01*
X596761Y786724D01*
X599131D01*
X599621Y786234D01*
X601991D01*
X602481Y786724D01*
X604851D01*
X605341Y786234D01*
X607711D01*
X608201Y786724D01*
X610571D01*
X611061Y786234D01*
X612682D01*
X617965Y784045D01*
X618890D01*
X620131Y785286D01*
X621227D01*
G01X629227Y785272D02*
X630506D01*
X631541Y784237D01*
X633468D01*
X637258Y785808D01*
X638330D01*
X639399Y786877D01*
X641391D01*
G01X557600Y830178D02*
Y825774D01*
X558090Y825284D01*
Y822914D01*
X557600Y822424D01*
Y820704D01*
X561480Y811337D01*
X562961Y809856D01*
X563654D01*
X565331Y808179D01*
Y807486D01*
X567006Y805811D01*
X567699D01*
X569376Y804134D01*
Y803441D01*
X570288Y802529D01*
X571623Y801976D01*
X579080D01*
X580755Y800301D01*
X581448D01*
X583125Y798624D01*
Y797931D01*
X584800Y796256D01*
X585493D01*
X587170Y794579D01*
Y793886D01*
X590506Y790550D01*
X591842D01*
X592332Y791040D01*
X594702D01*
X595192Y790550D01*
X597562D01*
X598052Y791040D01*
X600422D01*
X600912Y790550D01*
X603676D01*
X604166Y791040D01*
X606536D01*
X607026Y790550D01*
X609396D01*
X609886Y791040D01*
X612256D01*
X612746Y790550D01*
X615864D01*
X617661Y788753D01*
X618376Y788457D01*
X618860Y788256D01*
X619071Y788175D01*
X621051D01*
X623099Y790223D01*
X625249D01*
G01X551994Y831288D02*
Y822464D01*
X553085Y816981D01*
X553937Y814924D01*
X553938Y814923D01*
X556786Y808048D01*
X566307Y798527D01*
X570289Y796878D01*
X575072D01*
X577103Y796037D01*
X588196Y784944D01*
X612425D01*
X617708Y782755D01*
X618790D01*
X619743Y781802D01*
X621227D01*
G01X629227Y781774D02*
X630437D01*
X631610Y782947D01*
X633725D01*
X637515Y784518D01*
X638416D01*
X639404Y783530D01*
X641391D01*
G01X570333Y846658D02*
X576040Y840951D01*
Y839833D01*
X574995Y838788D01*
Y837670D01*
X575787Y836878D01*
X576905D01*
X577950Y837923D01*
X579068D01*
X579860Y837131D01*
Y836013D01*
X578815Y834968D01*
Y833850D01*
X579607Y833058D01*
X580725D01*
X581770Y834103D01*
X582888D01*
X598122Y818869D01*
X603569Y816613D01*
X617976D01*
X618358Y816995D01*
X625249D01*
G01X567812Y841838D02*
X569283Y840367D01*
Y836082D01*
X578496Y826869D01*
X579614D01*
X580512Y827767D01*
X581848D01*
X583078Y826537D01*
Y825421D01*
X582035Y824379D01*
Y823263D01*
X582829Y822469D01*
X583945D01*
X584988Y823511D01*
X586104D01*
X595262Y814353D01*
X603957Y810752D01*
X616533D01*
X616824Y811043D01*
X620909D01*
X621650Y810302D01*
X625249D01*
G01X568822Y844461D02*
X571856Y841427D01*
Y837195D01*
X578537Y830514D01*
X582881D01*
X596941Y816454D01*
X602726Y814058D01*
X618052D01*
X619357Y815363D01*
X621227D01*
G01X629227Y815384D02*
X632928D01*
X634664Y813648D01*
X641391D01*
G01X565958Y839984D02*
X566675Y839267D01*
Y835040D01*
X581764Y819951D01*
X585900D01*
X593553Y812298D01*
X603366Y808234D01*
X617905D01*
X618341Y808670D01*
X621227D01*
G01X629227Y808691D02*
X631696D01*
X633432Y806955D01*
X641391D01*
G01X564218Y832557D02*
X570555Y826223D01*
Y824548D01*
X568759Y822752D01*
Y820770D01*
X569431Y819148D01*
X576353Y812226D01*
X577471D01*
X578263Y813018D01*
Y814136D01*
X571702Y820697D01*
Y821815D01*
X572494Y822607D01*
X573612D01*
X579758Y816461D01*
X584396D01*
X591650Y809207D01*
X596994Y806996D01*
X597421Y805965D01*
X597013Y804979D01*
X597440Y803947D01*
X598477Y803517D01*
X599507Y803944D01*
X599916Y804931D01*
X600947Y805358D01*
X602429Y804744D01*
X620348D01*
X621483Y803609D01*
X625249D01*
G01X563537Y825348D02*
Y820040D01*
X565351Y815661D01*
X573962Y807050D01*
X579418D01*
X582384Y810016D01*
X583503D01*
X584871Y808648D01*
Y807530D01*
X583764Y806423D01*
Y805305D01*
X584556Y804513D01*
X585674D01*
X586781Y805620D01*
X587899D01*
X588691Y804828D01*
Y803710D01*
X587641Y802660D01*
Y801542D01*
X588433Y800750D01*
X589551D01*
X590601Y801800D01*
X591719D01*
X592511Y801008D01*
Y799890D01*
X591370Y798749D01*
Y797631D01*
X592162Y796839D01*
X593280D01*
X594421Y797980D01*
X595539D01*
X597355Y796164D01*
X599044D01*
X599888Y797008D01*
X602582D01*
X603426Y796164D01*
X605924D01*
X609415Y799655D01*
X616987D01*
X620376Y798251D01*
X620517Y798193D01*
X621794Y796916D01*
X625249D01*
G01X565060Y827591D02*
X566830Y825821D01*
Y824703D01*
X566089Y823962D01*
Y820633D01*
X567498Y817232D01*
X575078Y809652D01*
X578458D01*
X581870Y813064D01*
X584153D01*
X591901Y805316D01*
X593256D01*
X594778Y803794D01*
Y802439D01*
X597539Y799678D01*
X599816D01*
X600608Y800470D01*
Y801385D01*
X601398Y802175D01*
X602518D01*
X603308Y801385D01*
Y799809D01*
X604098Y799019D01*
X605218D01*
X606008Y799809D01*
Y801383D01*
X606798Y802173D01*
X619981D01*
X620176Y801978D01*
X621227D01*
G01X629227Y801999D02*
X629693D01*
X630279Y802585D01*
X631423D01*
X631902Y802106D01*
Y800688D01*
X632327Y800263D01*
X634954D01*
X635454Y799763D01*
Y799130D01*
X635954Y798630D01*
X637654D01*
X639287Y800263D01*
X641391D01*
G01X560815Y825348D02*
Y819859D01*
X563235Y814016D01*
X572719Y804532D01*
X580841D01*
X591126Y794247D01*
X595711D01*
X596396Y793562D01*
X606884D01*
X610459Y797137D01*
X611997D01*
X612787Y796347D01*
Y793986D01*
X613577Y793196D01*
X614697D01*
X615487Y793986D01*
Y795978D01*
X616277Y796768D01*
X617268D01*
X618442Y796281D01*
X619438Y795285D01*
X621227D01*
G01X629227Y795306D02*
X629693D01*
X629960Y795573D01*
X631079D01*
X631627Y795025D01*
Y792747D01*
X632046Y792328D01*
X633294D01*
X634536Y793570D01*
X641391D01*
G01X574147Y852820D02*
X602467Y824500D01*
X622328D01*
X623140Y823688D01*
X625249D01*
G01X573128Y849454D02*
X576576Y846006D01*
X577268D01*
X578945Y844329D01*
Y843636D01*
X580620Y841961D01*
X581313D01*
X582990Y840284D01*
Y839591D01*
X584665Y837916D01*
X585358D01*
X587035Y836239D01*
Y835546D01*
X588710Y833871D01*
X589403D01*
X591080Y832194D01*
Y831501D01*
X592755Y829826D01*
X593448D01*
X595125Y828149D01*
Y827456D01*
X596800Y825781D01*
X597493D01*
X599169Y824105D01*
Y823412D01*
X600511Y822070D01*
X603925Y820656D01*
X606990D01*
X607480Y821146D01*
X609850D01*
X610340Y820656D01*
X612710D01*
X613200Y821146D01*
X615570D01*
X616060Y820656D01*
X618799D01*
X620183Y822040D01*
X621227D01*
G01X629227Y822071D02*
X630317D01*
X631357Y821031D01*
X631960D01*
X637638Y822755D01*
X638495D01*
X639428Y823688D01*
X641391D01*
G01X572215Y848541D02*
X599780Y820976D01*
X603668Y819366D01*
X619421D01*
X620161Y818626D01*
X621227D01*
G01X629227Y818647D02*
X630320D01*
X631414Y819741D01*
X632152D01*
X637830Y821465D01*
X638843D01*
X639967Y820341D01*
X641391D01*
G01X533879Y907963D02*
Y905853D01*
G01X584179Y885903D02*
X584476Y885606D01*
Y883827D01*
X585627Y882676D01*
X587283D01*
X588073Y881886D01*
Y880766D01*
X587283Y879976D01*
X585294D01*
X584504Y879186D01*
Y876837D01*
X585316Y876025D01*
X587454D01*
X588295Y875184D01*
Y873046D01*
X589136Y872205D01*
X591274D01*
X592115Y871364D01*
Y869226D01*
X612757Y848584D01*
X620029D01*
X621500Y847113D01*
X625249D01*
G01X581704Y879248D02*
Y875835D01*
X612026Y845513D01*
X621227D01*
G01X629227Y845479D02*
X632951D01*
X634664Y843766D01*
X641391D01*
G01X580071Y869596D02*
X580660Y869007D01*
X583553Y869003D01*
X607440Y845111D01*
Y843995D01*
X606647Y843202D01*
X605531D01*
X599657Y849076D01*
X598540D01*
X597748Y848284D01*
Y847167D01*
X604783Y840130D01*
X613518D01*
X615263Y841875D01*
X620051D01*
X621506Y840420D01*
X625249D01*
G01X577872Y859596D02*
X582239Y855229D01*
X583357D01*
X584149Y856021D01*
Y857139D01*
X582418Y858870D01*
Y859988D01*
X583210Y860780D01*
X584328D01*
X592544Y852564D01*
Y851236D01*
X590646Y849338D01*
Y846822D01*
X604381Y833087D01*
X615472D01*
X617673Y835288D01*
X620105D01*
X621666Y833727D01*
X625249D01*
G01X578923Y864911D02*
X584041D01*
X596662Y852290D01*
Y851172D01*
X594377Y848887D01*
Y846681D01*
X604419Y836639D01*
X613916D01*
X616105Y838828D01*
X621227D01*
G01X629227Y838770D02*
X630156D01*
X630877Y839491D01*
X631714D01*
X632286Y838919D01*
Y835965D01*
X633048Y835203D01*
X634126D01*
X635248Y836325D01*
X636232D01*
X637023Y835534D01*
X637917D01*
X639457Y837074D01*
X641391D01*
G01X578287Y855499D02*
X582671Y851115D01*
X583789D01*
X585863Y853189D01*
X586981D01*
X587773Y852397D01*
Y851279D01*
X585699Y849205D01*
Y848087D01*
X603888Y829898D01*
X617164D01*
X619348Y832082D01*
X621227D01*
G01X629227Y832113D02*
X630387D01*
X631438Y831062D01*
Y829725D01*
X631941Y829222D01*
X633307D01*
X634466Y830381D01*
X641391D01*
G01X533879Y927189D02*
Y925079D01*
G01X575059Y853733D02*
X577125Y851667D01*
X577818D01*
X579495Y849990D01*
Y849297D01*
X581170Y847622D01*
X581863D01*
X583540Y845945D01*
Y845252D01*
X585215Y843577D01*
X585908D01*
X587585Y841900D01*
Y841207D01*
X589260Y839532D01*
X589953D01*
X591630Y837855D01*
Y837162D01*
X593305Y835487D01*
X593998D01*
X595675Y833810D01*
Y833117D01*
X597350Y831442D01*
X598043D01*
X599720Y829765D01*
Y829072D01*
X603002Y825790D01*
X605010D01*
X605500Y826280D01*
X607870D01*
X608360Y825790D01*
X610730D01*
X611220Y826280D01*
X613590D01*
X614080Y825790D01*
X616450D01*
X616940Y826280D01*
X619310D01*
X619800Y825790D01*
X622197D01*
X623441Y827034D01*
X625249D01*
G01X583745Y922069D02*
X590607Y915207D01*
X602892D01*
X606352Y918667D01*
X618106D01*
X618580Y919141D01*
X620474D01*
G01X630045Y919062D02*
X630570D01*
X632243Y917389D01*
X641391D01*
G01X595023Y908430D02*
X605503D01*
X608116Y911043D01*
X609521D01*
X615983Y904581D01*
Y879442D01*
X619813Y875612D01*
X621227D01*
G01X629227Y875592D02*
X632143D01*
X633850Y873885D01*
X641391D01*
G01X595423Y903079D02*
X600362D01*
X601941Y901500D01*
Y900382D01*
X600972Y899413D01*
Y898295D01*
X601764Y897503D01*
X602882D01*
X603851Y898472D01*
X604969D01*
X605761Y897680D01*
Y896562D01*
X604792Y895593D01*
Y894475D01*
X605584Y893683D01*
X606702D01*
X607671Y894652D01*
X608789D01*
X610808Y892633D01*
Y877315D01*
X619206Y868917D01*
X621227D01*
G01X629227Y868904D02*
X631096D01*
X632808Y867192D01*
X641391D01*
G01X587971Y889696D02*
X590333Y887334D01*
X591311D01*
X598405Y880240D01*
Y879122D01*
X597613Y878330D01*
X596495D01*
X595266Y879559D01*
X594148D01*
X593356Y878767D01*
Y877649D01*
X595369Y875636D01*
X597616D01*
X598406Y874846D01*
Y870169D01*
X614769Y853806D01*
X625249D01*
G01X585984Y887709D02*
X591398Y882295D01*
Y880541D01*
X590011Y879154D01*
Y877290D01*
X595487Y871814D01*
Y869484D01*
X613752Y851219D01*
X617495D01*
X618455Y852179D01*
X621200D01*
X621227Y852152D01*
G01X629227Y852133D02*
X629979D01*
X630034Y852188D01*
X632419D01*
X634148Y850459D01*
X641391D01*
G01X595024Y911606D02*
X604586D01*
X607638Y914658D01*
X617643D01*
X618433Y913868D01*
Y912748D01*
X617643Y911958D01*
X615325D01*
X614535Y911168D01*
Y910048D01*
X615325Y909258D01*
X617735D01*
X618586Y908407D01*
Y880443D01*
X621798Y877231D01*
X625249D01*
G01X595423Y905665D02*
X611260D01*
X612102Y904823D01*
Y903703D01*
X611312Y902913D01*
X607174D01*
X606384Y902123D01*
Y901003D01*
X607174Y900213D01*
X612636D01*
X613426Y899423D01*
Y878369D01*
X620335Y871460D01*
X620931D01*
X621853Y870538D01*
X625249D01*
G01X591345Y898894D02*
X605886Y884353D01*
Y875381D01*
X616135Y865132D01*
Y862387D01*
X618025Y860497D01*
X621394D01*
X621396Y860499D01*
X625249D01*
G01X590059Y894384D02*
X594208Y890235D01*
X594901D01*
X596578Y888558D01*
Y887865D01*
X598253Y886190D01*
X598946D01*
X600623Y884513D01*
Y883820D01*
X602298Y882145D01*
Y878919D01*
X602788Y878429D01*
Y876059D01*
X602298Y875569D01*
Y871778D01*
X603425Y870651D01*
X604118D01*
X605795Y868974D01*
Y868281D01*
X607470Y866606D01*
X608163D01*
X609840Y864929D01*
Y864237D01*
X612516Y861561D01*
X613209D01*
X614885Y859885D01*
Y859191D01*
X615707Y858369D01*
Y857559D01*
X616498Y856768D01*
X617616D01*
X618406Y857558D01*
Y858010D01*
X619300Y858904D01*
X621227D01*
G01X629227Y858825D02*
X629912D01*
X629960Y858873D01*
X631347D01*
X632361Y857859D01*
X633468D01*
X637258Y859430D01*
X638330D01*
X639399Y860499D01*
X641391D01*
G01X592258Y899807D02*
X594137Y897928D01*
X594830D01*
X596507Y896251D01*
Y895558D01*
X598182Y893883D01*
X598875D01*
X600552Y892206D01*
Y891513D01*
X602227Y889838D01*
X602920D01*
X604597Y888161D01*
Y887468D01*
X607176Y884889D01*
Y882519D01*
X607666Y882029D01*
Y879659D01*
X607176Y879169D01*
Y875916D01*
X608862Y874230D01*
X609555D01*
X611232Y872553D01*
Y871860D01*
X613008Y870084D01*
X613701D01*
X615378Y868407D01*
Y867714D01*
X617425Y865667D01*
Y862922D01*
X618560Y861787D01*
X620209D01*
X620990Y862568D01*
Y863409D01*
X621426Y863845D01*
X625249D01*
G01X589146Y893471D02*
X601008Y881609D01*
Y871243D01*
X614417Y857834D01*
Y857024D01*
X615963Y855478D01*
X617659D01*
X617722Y855415D01*
X621227D01*
G01X629227Y855479D02*
X629270Y855436D01*
X631389D01*
X632522Y856569D01*
X633725D01*
X637515Y858140D01*
X638416D01*
X639404Y857152D01*
X641391D01*
G01X533879Y946414D02*
Y944304D01*
G01X582524Y929734D02*
X589891D01*
X590681Y928944D01*
Y927202D01*
X591471Y926412D01*
X592591D01*
X593381Y927202D01*
Y928955D01*
X594171Y929745D01*
X595291D01*
X596081Y928955D01*
Y927202D01*
X596871Y926412D01*
X597991D01*
X598781Y927202D01*
Y928765D01*
X599571Y929555D01*
X600691D01*
X601481Y928765D01*
Y927361D01*
X602271Y926571D01*
X603391D01*
X604181Y927361D01*
Y928705D01*
X604971Y929495D01*
X610822D01*
X611612Y928705D01*
Y927282D01*
X612402Y926492D01*
X618787D01*
X619723Y927428D01*
X625249D01*
G01X583724Y924610D02*
X585245D01*
X588479Y921376D01*
X592689D01*
X593479Y920586D01*
Y918524D01*
X594269Y917734D01*
X595389D01*
X596179Y918524D01*
Y920586D01*
X596969Y921376D01*
X598089D01*
X598879Y920586D01*
Y918524D01*
X599669Y917734D01*
X600789D01*
X601579Y918524D01*
Y920586D01*
X602369Y921376D01*
X617228D01*
X617869Y920735D01*
X625249D01*
G01X583724Y927143D02*
X586320D01*
X589569Y923894D01*
X604275D01*
X607174Y926793D01*
X608651D01*
X609274Y926170D01*
Y924724D01*
X610064Y923934D01*
X618179D01*
X619740Y922373D01*
X620559D01*
G01X629809Y922326D02*
X630475D01*
X631841Y923692D01*
X637787D01*
X638176Y924081D01*
X641391D01*
G01X576124Y949575D02*
X576869D01*
X577659Y950365D01*
Y951731D01*
X578449Y952521D01*
X579659D01*
X580449Y951731D01*
Y950365D01*
X581239Y949575D01*
X582449D01*
X583239Y950365D01*
Y951731D01*
X584029Y952521D01*
X585239D01*
X586029Y951731D01*
Y950365D01*
X586819Y949575D01*
X589818D01*
X592296Y952053D01*
X594958D01*
X599543Y956638D01*
X611769D01*
X613082Y956094D01*
X618323Y950853D01*
X625249D01*
G01X580024Y944363D02*
X592655D01*
X594801Y946509D01*
X596967D01*
X601235Y950777D01*
X602984D01*
X603774Y949987D01*
Y947480D01*
X604564Y946690D01*
X605684D01*
X606474Y947480D01*
Y949987D01*
X607264Y950777D01*
X609597D01*
X610620Y950353D01*
X617845Y943128D01*
X622105D01*
X623137Y944160D01*
X625249D01*
G01X578624Y946939D02*
X590827D01*
X593073Y949185D01*
X596039D01*
X600177Y953323D01*
X610707D01*
X611656Y952930D01*
X618841Y945745D01*
X620389D01*
X620402Y945758D01*
G01X629804D02*
X631659D01*
X633408Y947507D01*
X641391D01*
G01X580024Y941755D02*
X594231D01*
X596332Y943856D01*
X598407D01*
X599197Y943066D01*
Y941907D01*
X599987Y941117D01*
X601107D01*
X601897Y941907D01*
Y943066D01*
X602687Y943856D01*
X603807D01*
X604597Y943066D01*
Y941907D01*
X605387Y941117D01*
X606507D01*
X607297Y941907D01*
Y943066D01*
X608087Y943856D01*
X613153D01*
X618590Y938419D01*
X619863D01*
X620584Y939140D01*
X621227D01*
G01X629227Y939077D02*
X631582D01*
X633319Y940814D01*
X641391D01*
G01X582524Y933618D02*
X589953D01*
X590438Y934103D01*
X592808D01*
X593293Y933618D01*
X595663D01*
X596148Y934103D01*
X598518D01*
X599003Y933618D01*
X601373D01*
X601858Y934103D01*
X604228D01*
X604713Y933618D01*
X607083D01*
X607568Y934103D01*
X609938D01*
X610423Y933618D01*
X612793D01*
X616020Y930391D01*
X617133D01*
X617922Y931180D01*
Y931707D01*
X618746Y932531D01*
X619254D01*
G01X631027Y932447D02*
X631505D01*
X632471Y931481D01*
X633469D01*
X637258Y933052D01*
X638330D01*
X639399Y934121D01*
X641391D01*
G01X625249D02*
X625248Y934122D01*
X617390D01*
X614891Y936621D01*
X582524D01*
G01Y932328D02*
X612258D01*
X615485Y929101D01*
X619254D01*
G01X631027D02*
X631428D01*
X632518Y930191D01*
X633726D01*
X637515Y931762D01*
X638416D01*
X639404Y930774D01*
X641391D01*
G01X582524Y937911D02*
X586076D01*
X586566Y938401D01*
X588936D01*
X589426Y937911D01*
X591796D01*
X592286Y938401D01*
X594656D01*
X595146Y937911D01*
X597516D01*
X598006Y938401D01*
X600376D01*
X600866Y937911D01*
X603236D01*
X603726Y938401D01*
X606096D01*
X606586Y937911D01*
X608956D01*
X609446Y938401D01*
X611816D01*
X612306Y937911D01*
X615426D01*
X617925Y935412D01*
X620361D01*
X620866Y935917D01*
Y937123D01*
X621207Y937467D01*
X625249D01*
G01X533879Y965640D02*
Y963530D01*
G01X585121Y980038D02*
X594696Y989613D01*
X596174D01*
X597841Y991280D01*
X599041D01*
X600708Y989613D01*
X604258D01*
X605783Y991138D01*
X607650D01*
X609175Y989613D01*
X618898D01*
X619547Y988964D01*
X621845D01*
X623145Y987664D01*
X625249D01*
G01X585121Y976835D02*
X585124Y976838D01*
X585482D01*
X594722Y986078D01*
X621227D01*
G01X629227Y986033D02*
X635105D01*
X636820Y984318D01*
X641391D01*
G01X579189Y975267D02*
X580197Y974259D01*
X586464D01*
X594786Y982581D01*
X620521D01*
X622131Y980971D01*
X625249D01*
G01X577001Y973879D02*
X579166Y971714D01*
X587481D01*
X595336Y979569D01*
X619605D01*
X619782Y979392D01*
X621227D01*
G01X629227Y979371D02*
X635297D01*
X635869Y978799D01*
Y978335D01*
X636579Y977625D01*
X641391D01*
G01X575203Y972081D02*
X578088Y969196D01*
X588524D01*
X596379Y977051D01*
X618518D01*
X619926Y975643D01*
X620312D01*
X621677Y974278D01*
X625249D01*
G01X654949Y967585D02*
X651201D01*
X649430Y969356D01*
X645369D01*
G01X637369Y969355D02*
X636541D01*
X634129Y971767D01*
X633011D01*
X632027Y970783D01*
X632029Y969596D01*
X634382Y967251D01*
Y966132D01*
X633007Y964757D01*
X632031D01*
X629546Y967242D01*
Y968382D01*
X629124Y968804D01*
G01X621227Y969179D02*
X618669D01*
X617525Y970323D01*
X596774D01*
X590611Y964160D01*
X575874D01*
X570577Y969457D01*
G01X671091Y964239D02*
X664631D01*
X663945Y963553D01*
Y960459D01*
X663154Y959668D01*
X661695D01*
X660905Y960458D01*
Y961692D01*
X660069Y962528D01*
X658927D01*
G01X650164Y962565D02*
X649367D01*
X646117Y965815D01*
X645369D01*
G01X637369Y965865D02*
X636770D01*
X630124Y959219D01*
X629151D01*
G01X620455D02*
X619584D01*
X616822Y961981D01*
X613542Y963340D01*
X596915D01*
X592699Y959124D01*
X573174D01*
X567099Y965199D01*
G01X625249Y967585D02*
X622940D01*
X621954Y966599D01*
X617688D01*
X616482Y967805D01*
X613263D01*
X611316Y965858D01*
X608008D01*
X606336Y967530D01*
X605218D01*
X603546Y965858D01*
X602336D01*
X600389Y967805D01*
X597818D01*
X591655Y961642D01*
X574812D01*
X568987Y967467D01*
G01X641391Y964239D02*
X637645D01*
X634869Y961463D01*
Y953909D01*
X634179Y953219D01*
X632359D01*
X631669Y953909D01*
Y955207D01*
X630901Y955975D01*
X629051D01*
G01X620413Y955873D02*
X619102D01*
X615145Y959830D01*
X612883Y960767D01*
X597903D01*
X593742Y956606D01*
X572104D01*
X563511Y965199D01*
G01X573008Y970686D02*
X577016Y966678D01*
X589568D01*
X597423Y974533D01*
X616662D01*
X618541Y972654D01*
X621351D01*
G01X629051Y972682D02*
X631142D01*
X631969Y973509D01*
Y973929D01*
X632428Y974388D01*
X634297D01*
X636266Y972419D01*
X637512D01*
X638999Y970932D01*
X641391D01*
G01X671091Y1021129D02*
X669092D01*
X668164Y1022057D01*
X667616D01*
X667166Y1021870D01*
X662219Y1016539D01*
X661234Y1015478D01*
X660171Y1014782D01*
X659828Y1014656D01*
X653514Y1013215D01*
X653153Y1012639D01*
X650842Y1012111D01*
X650267Y1012472D01*
X647957Y1011945D01*
X647596Y1011369D01*
X645284Y1010842D01*
X644710Y1011203D01*
X642400Y1010676D01*
X642039Y1010100D01*
X639727Y1009573D01*
X639152Y1009934D01*
X636842Y1009407D01*
X636481Y1008831D01*
X634169Y1008304D01*
X633594Y1008665D01*
X631284Y1008138D01*
X630923Y1007562D01*
X628611Y1007035D01*
X628036Y1007396D01*
X625726Y1006869D01*
X625365Y1006293D01*
X623053Y1005766D01*
X622478Y1006127D01*
X619324Y1005407D01*
X593361Y1000651D01*
X591607Y1000492D01*
X589350D01*
X588865Y1000007D01*
X586565D01*
X586080Y1000492D01*
X577436D01*
G01X625249Y1034515D02*
X622985D01*
X621860Y1033390D01*
X619453D01*
X618734Y1032671D01*
X616052D01*
X610098Y1026703D01*
X585886Y1016673D01*
G01X572194Y1013651D02*
X586186D01*
X612532Y1024564D01*
X617422Y1029454D01*
X621227D01*
G01X629227Y1029081D02*
X630411Y1027897D01*
X632943D01*
X633345Y1028299D01*
Y1029065D01*
X631719Y1030691D01*
Y1031669D01*
X632358Y1032308D01*
X637003D01*
X638143Y1031168D01*
X641391D01*
G01X576783Y1022662D02*
X580796Y1026675D01*
X605408Y1036870D01*
X613105Y1044567D01*
X618350D01*
X620924Y1047141D01*
X622403D01*
X623162Y1047900D01*
X625249D01*
G01X579588Y1021470D02*
X582612Y1024494D01*
X606481Y1034381D01*
X613859Y1041759D01*
X618590D01*
X619644Y1042813D01*
X621227D01*
G01X629227Y1042823D02*
X631238D01*
X632019Y1043604D01*
Y1044770D01*
X632577Y1045328D01*
X634860D01*
X635634Y1044554D01*
X641391D01*
G01X582119Y1020440D02*
X583424Y1021745D01*
X607315Y1031641D01*
X613744Y1038070D01*
Y1038069D01*
X614784Y1039109D01*
X619620D01*
X620685Y1040174D01*
X622046D01*
X623079Y1041207D01*
X625249D01*
G01X583900Y1018659D02*
X584432Y1019191D01*
X608887Y1029321D01*
X615690Y1036124D01*
X621227D01*
G01X629227Y1036104D02*
X633296D01*
X634086Y1036894D01*
Y1038469D01*
X634586Y1038969D01*
X637867D01*
X638975Y1037861D01*
X641391D01*
G01X654949Y1054593D02*
X648327D01*
X646607Y1056313D01*
X645151D01*
G01X637551Y1056305D02*
X635804D01*
X635005Y1055506D01*
X633308D01*
X632777Y1054975D01*
X631227D01*
X630008Y1056194D01*
X629227D01*
G01X621227Y1056227D02*
X619822D01*
X618911Y1057138D01*
X616705D01*
X614917Y1055350D01*
X609235D01*
X608538Y1054653D01*
Y1054654D01*
X600780Y1046896D01*
X576281Y1036748D01*
X570146Y1030613D01*
G01X671091Y1051247D02*
X666147D01*
X664719Y1049819D01*
X663509D01*
X662819Y1050509D01*
Y1051690D01*
X661516Y1052993D01*
X658927D01*
G01X651051Y1052948D02*
X649185D01*
X649058Y1052821D01*
X645051D01*
G01X637651Y1052867D02*
X634069D01*
X633924Y1052722D01*
X630802D01*
X630545Y1052979D01*
X629227D01*
G01X621227D02*
X619832D01*
X617080Y1050227D01*
X611415D01*
X602942Y1041754D01*
X578298Y1031546D01*
X573353Y1026601D01*
G01X625249Y1054593D02*
X617813D01*
X616048Y1052828D01*
X610364D01*
X601792Y1044256D01*
X577199Y1034069D01*
X571976Y1028846D01*
G01X641391Y1051247D02*
X634859D01*
X634482Y1050870D01*
X633042D01*
X632345Y1050173D01*
Y1049188D01*
X632007Y1048850D01*
X630638D01*
X629987Y1049501D01*
X629227D01*
G01X621227Y1049522D02*
X620549D01*
X618697Y1047670D01*
X612556D01*
X604270Y1039384D01*
X579624Y1029175D01*
X575201Y1024752D01*
G01X534311Y1013595D02*
Y1015705D01*
G01X595728Y1093474D02*
X596739D01*
X599395Y1096130D01*
X600513D01*
X601303Y1095340D01*
Y1094335D01*
X602093Y1093545D01*
X603213D01*
X604003Y1094335D01*
Y1095340D01*
X604793Y1096130D01*
X605913D01*
X607790Y1094253D01*
X610206D01*
X612510Y1096557D01*
X618616D01*
X620567Y1098508D01*
X621686D01*
X622097Y1098097D01*
X625249D01*
G01X599828Y1088377D02*
X606983D01*
X607693Y1089087D01*
X610830D01*
X611540Y1088377D01*
X612981D01*
X613771Y1089167D01*
Y1090650D01*
X614497Y1091376D01*
X616513D01*
X617600Y1090289D01*
X619069D01*
X620184Y1091404D01*
X625249D01*
G01X599828Y1090997D02*
X604739D01*
X605414Y1091672D01*
X611187D01*
X613471Y1093956D01*
X618597D01*
X619476Y1093077D01*
X620122D01*
G01X629931D02*
X630706D01*
X632058Y1094429D01*
X635421D01*
X637751Y1094751D01*
X641391D01*
G01X599827Y1085796D02*
X614221D01*
X615681Y1087256D01*
X617543D01*
X618415Y1086384D01*
X620122D01*
G01X629931D02*
X630760D01*
X632434Y1088058D01*
X641391D01*
G01X599311Y1073063D02*
X601053Y1074805D01*
X602171D01*
X602961Y1074015D01*
Y1073497D01*
X603751Y1072707D01*
X604871D01*
X606925Y1074761D01*
X608174D01*
X609657Y1073278D01*
Y1072160D01*
X608525Y1071028D01*
X607252D01*
X606462Y1070238D01*
Y1069118D01*
X607252Y1068328D01*
X609652D01*
X612395Y1071071D01*
Y1073402D01*
X613185Y1074192D01*
X614303D01*
X614767Y1073728D01*
X618012D01*
X618956Y1074672D01*
X625249D01*
G01X594926Y1058635D02*
X595523D01*
X601936Y1065048D01*
X603054D01*
X603846Y1064256D01*
Y1063138D01*
X598322Y1057614D01*
Y1056496D01*
X599114Y1055704D01*
X600232D01*
X606691Y1062163D01*
X611962D01*
X613809Y1064010D01*
X614985D01*
X616173Y1065198D01*
Y1065934D01*
X618218Y1067979D01*
X625249D01*
G01X599726Y1067201D02*
X600894Y1068369D01*
Y1069615D01*
X601453Y1070174D01*
X603300D01*
X603723Y1069751D01*
Y1068257D01*
X607282Y1064698D01*
X610205D01*
X614929Y1069422D01*
Y1070342D01*
X615783Y1071196D01*
X617503D01*
X619047Y1069652D01*
X619633D01*
G01X630752D02*
X631373D01*
X632058Y1070337D01*
Y1070937D01*
X632813Y1071692D01*
X633986D01*
X634817Y1070861D01*
X637750D01*
X638215Y1071326D01*
X641391D01*
G01X594776Y1055498D02*
X595467D01*
X596148Y1054817D01*
Y1053915D01*
X597646Y1052417D01*
X600506D01*
X607582Y1059493D01*
X613286D01*
X615156Y1061363D01*
X617450D01*
X618672Y1062585D01*
Y1064854D01*
X620124Y1066306D01*
X620567D01*
G01X629992D02*
X630840D01*
X631631Y1065515D01*
Y1062573D01*
X632341Y1061863D01*
X634618D01*
X637388Y1064633D01*
X641391D01*
G01X599827Y1081946D02*
X601527D01*
X602017Y1081456D01*
X603717D01*
X604207Y1081946D01*
X605907D01*
X606397Y1081456D01*
X608097D01*
X608587Y1081946D01*
X610287D01*
X610777Y1081456D01*
X612477D01*
X612967Y1081946D01*
X616239D01*
X617120Y1082827D01*
X617571Y1083014D01*
X618552Y1083421D01*
X620900D01*
X621243Y1083078D01*
Y1081704D01*
X621582Y1081365D01*
X625249D01*
G01X603626Y1078717D02*
X615297D01*
X616380Y1077634D01*
X617995D01*
X618387Y1078026D01*
Y1079195D01*
X618883Y1079691D01*
X620138D01*
G01X629761Y1079763D02*
X630519D01*
X631557Y1078725D01*
X632601D01*
X634172Y1080296D01*
X638330D01*
X639399Y1081365D01*
X641391D01*
G01X599827Y1083236D02*
X615704D01*
X616389Y1083921D01*
X617571Y1084411D01*
X618295Y1084711D01*
X625249D01*
G01X603626Y1077427D02*
X614762D01*
X615845Y1076344D01*
X620138D01*
G01X629770Y1076259D02*
X630522D01*
X631698Y1077435D01*
X633136D01*
X634707Y1079006D01*
X638416D01*
X639404Y1078018D01*
X641391D01*
G01X585280Y1116695D02*
X595793Y1127208D01*
X597122D01*
X597912Y1127998D01*
Y1129433D01*
X598738Y1130259D01*
X601946D01*
X603810Y1128395D01*
X604930D01*
X606711Y1130176D01*
X607829D01*
X609554Y1128451D01*
X610740D01*
X612548Y1130259D01*
X614022D01*
X615698Y1128583D01*
X616816D01*
X618359Y1130126D01*
X619477D01*
X620307Y1129296D01*
X622084D01*
X623165Y1128215D01*
X625249D01*
G01X587061Y1114914D02*
X595982Y1123835D01*
X600873Y1125861D01*
X618301D01*
X619116Y1126676D01*
X621227D01*
G01X629227Y1126611D02*
X630422D01*
X630936Y1127125D01*
X632054D01*
X632844Y1126335D01*
Y1125145D01*
X633610Y1124379D01*
X634728D01*
X635218Y1124869D01*
X641391D01*
G01X592627Y1105168D02*
X600416Y1112957D01*
X601553D01*
X602344Y1113748D01*
Y1114439D01*
X603134Y1115229D01*
X604254D01*
X605044Y1114439D01*
Y1113747D01*
X605834Y1112957D01*
X606995D01*
X607808Y1113770D01*
Y1114436D01*
X608598Y1115226D01*
X610090D01*
X611553Y1113763D01*
Y1113425D01*
X613801Y1111177D01*
X614376Y1109790D01*
X614884Y1109282D01*
X616003D01*
X617762Y1111041D01*
X619023D01*
X619465Y1111483D01*
X625249D01*
G01X593282Y1098593D02*
X602610Y1107921D01*
X609233D01*
X610023Y1107131D01*
Y1106011D01*
X609233Y1105221D01*
X603799D01*
X603009Y1104431D01*
Y1103311D01*
X603799Y1102521D01*
X610524D01*
X611250Y1103247D01*
X612369D01*
X613011Y1102605D01*
X616639D01*
X620462Y1106428D01*
X621362D01*
X623000Y1104790D01*
X625249D01*
G01X592628Y1101586D02*
X601481Y1110439D01*
X608064D01*
X608961Y1111336D01*
X610080D01*
X611666Y1109750D01*
X612541Y1107638D01*
Y1106630D01*
X614032Y1105139D01*
X615421D01*
X620127Y1109845D01*
X621227D01*
G01X629227Y1109859D02*
X630728D01*
X631567Y1109020D01*
Y1107615D01*
X632508Y1106674D01*
X633833D01*
X635296Y1108137D01*
X641391D01*
G01X595677Y1097398D02*
X599943Y1101664D01*
X601062D01*
X601928Y1100798D01*
Y1100410D01*
X602759Y1099579D01*
X604258D01*
X604342Y1099663D01*
X607312D01*
X608284Y1098691D01*
X609707D01*
X610865Y1099849D01*
X611413Y1100076D01*
X618212D01*
X618871Y1100735D01*
Y1102326D01*
X619662Y1103117D01*
X620567D01*
G01X630376Y1103244D02*
X631115D01*
X631899Y1102460D01*
Y1099583D01*
X632689Y1098793D01*
X634561D01*
X635351Y1099583D01*
Y1102271D01*
X636061Y1102981D01*
X637829D01*
X639366Y1101444D01*
X641391D01*
G01X587886Y1109589D02*
X598450Y1120153D01*
X603020Y1122046D01*
X612600D01*
X615653Y1120006D01*
X615654Y1120005D01*
X618206Y1118301D01*
X621486D01*
X621611Y1118176D01*
X625249D01*
G01X589681Y1107793D02*
X598807Y1116919D01*
X601327Y1118604D01*
X602375Y1119037D01*
X605049D01*
X605539Y1119527D01*
X607909D01*
X608399Y1119037D01*
X610843D01*
X612248Y1118455D01*
X612989Y1117714D01*
X613682D01*
X615359Y1116037D01*
Y1115344D01*
X616258Y1114445D01*
X617694D01*
X618364Y1115115D01*
Y1115819D01*
X619154Y1116609D01*
X621227D01*
G01X629227Y1116573D02*
X631386D01*
X632423Y1115536D01*
X633468D01*
X636766Y1116903D01*
X638126D01*
X639399Y1118176D01*
X641391D01*
G01X586973Y1110501D02*
X588648Y1112176D01*
Y1112862D01*
X590325Y1114539D01*
X591011D01*
X592686Y1116214D01*
Y1116900D01*
X594363Y1118577D01*
X595049D01*
X597719Y1121247D01*
X602763Y1123336D01*
X612992D01*
X613673Y1122881D01*
X614028Y1122644D01*
X614708Y1122779D01*
X616679Y1121462D01*
X616815Y1120782D01*
X618598Y1119591D01*
X620951D01*
X621211Y1119851D01*
Y1121201D01*
X621532Y1121522D01*
X625249D01*
G01X590594Y1106881D02*
X599627Y1115914D01*
X601938Y1117460D01*
X602632Y1117747D01*
X610586D01*
X611517Y1117361D01*
X615749Y1113129D01*
X621227D01*
G01X629227Y1113075D02*
X631333D01*
X632504Y1114246D01*
X633725D01*
X637023Y1115613D01*
X638620D01*
X639404Y1114829D01*
X641391D01*
G01X534311Y1032821D02*
Y1034931D01*
G01X573527Y1134069D02*
X593487Y1154029D01*
X594605D01*
X596189Y1152445D01*
X607201D01*
X607991Y1153235D01*
Y1154355D01*
X607201Y1155145D01*
X597294D01*
X596504Y1155935D01*
Y1157055D01*
X597294Y1157845D01*
X598912D01*
X599949Y1158882D01*
X601641D01*
X602649Y1157874D01*
X603941D01*
X604949Y1158882D01*
X605886D01*
X607368Y1158269D01*
X608917Y1157234D01*
X613113Y1153038D01*
X614123Y1151527D01*
X614409Y1150836D01*
Y1149178D01*
X615758Y1147829D01*
X616480D01*
X617601Y1148294D01*
X625249D01*
G01X577518Y1124757D02*
X578358Y1125597D01*
Y1126716D01*
X576454Y1128620D01*
Y1129738D01*
X577246Y1130530D01*
X578364D01*
X580315Y1128579D01*
X581433D01*
X582225Y1129371D01*
Y1130489D01*
X580274Y1132440D01*
Y1133558D01*
X581066Y1134350D01*
X582184D01*
X584135Y1132399D01*
X585253D01*
X586045Y1133191D01*
Y1134309D01*
X584094Y1136260D01*
Y1137378D01*
X584886Y1138170D01*
X586004D01*
X587955Y1136219D01*
X589073D01*
X589865Y1137011D01*
Y1138129D01*
X587914Y1140080D01*
Y1141198D01*
X588706Y1141990D01*
X589824D01*
X591300Y1140514D01*
X592418D01*
X593210Y1141306D01*
Y1142424D01*
X591734Y1143900D01*
Y1145018D01*
X593898Y1147182D01*
X607447D01*
X610173Y1144456D01*
Y1142139D01*
X610992Y1141320D01*
X617490D01*
X618881Y1142711D01*
X621899D01*
X623009Y1141601D01*
X625249D01*
G01X574727Y1131708D02*
X593332Y1150313D01*
X594849D01*
X595428Y1149734D01*
X608052D01*
X609687Y1151369D01*
X610806D01*
X611891Y1150284D01*
Y1146300D01*
X612862Y1145329D01*
Y1144642D01*
X613652Y1143852D01*
X616277D01*
X617990Y1145565D01*
X618978D01*
X620102Y1146689D01*
X621227D01*
G01X629227Y1146700D02*
X630517D01*
X631445Y1145772D01*
Y1143894D01*
X632096Y1143243D01*
X633646D01*
X634171Y1143768D01*
Y1144448D01*
X634671Y1144948D01*
X635789D01*
X637201Y1143536D01*
X638319D01*
X639731Y1144948D01*
X641391D01*
G01X579346Y1122928D02*
X595220Y1138802D01*
X604175D01*
X604965Y1139592D01*
Y1140712D01*
X604175Y1141502D01*
X596518D01*
X595728Y1142292D01*
Y1143412D01*
X596518Y1144202D01*
X606865D01*
X607655Y1143412D01*
Y1139575D01*
X608428Y1138802D01*
X618497D01*
X619770Y1140075D01*
X621227D01*
G01X629227Y1140038D02*
X630388D01*
X631160Y1139266D01*
X633714D01*
X634111Y1138869D01*
Y1137260D01*
X634768Y1136603D01*
X637705D01*
X639357Y1138255D01*
X641391D01*
G01X581665Y1120310D02*
X596667Y1135312D01*
X619063D01*
X620221Y1136470D01*
X621340D01*
X622902Y1134908D01*
X625249D01*
G01X583446Y1118529D02*
X597694Y1132777D01*
X619679D01*
X620238Y1133336D01*
X621227D01*
G01X629227Y1133288D02*
X630437D01*
X633021Y1131562D01*
X641391D01*
G01X570275Y1139783D02*
X595772Y1165280D01*
Y1165281D01*
X610390D01*
X619377Y1156294D01*
X621686D01*
X622993Y1154987D01*
X625249D01*
G01X571502Y1137440D02*
X594886Y1160824D01*
X595841Y1161464D01*
X598107Y1162406D01*
X599625Y1162708D01*
X606601D01*
X609172Y1161645D01*
X610260Y1160918D01*
X611345Y1160193D01*
X616072Y1155466D01*
X617602Y1153175D01*
X617829Y1152627D01*
X618348Y1152108D01*
X618969D01*
X620225Y1153364D01*
X621227D01*
G01X629227Y1153339D02*
X630481D01*
X631535Y1152285D01*
X633318D01*
X637258Y1153918D01*
X638330D01*
X639399Y1154987D01*
X641391D01*
G01X572415Y1136527D02*
X595712Y1159824D01*
X596454Y1160321D01*
X598485Y1161165D01*
X599753Y1161418D01*
X606344D01*
X608561Y1160501D01*
X610522Y1159190D01*
X615069Y1154643D01*
X616458Y1152565D01*
X616734Y1151896D01*
X617813Y1150817D01*
X619301D01*
X620204Y1149914D01*
X621227D01*
G01X629227Y1149884D02*
X630505D01*
X631616Y1150995D01*
X633575D01*
X637515Y1152628D01*
X638416D01*
X639403Y1151641D01*
X641391D01*
G01X534311Y1052047D02*
Y1054157D01*
G01X565697Y1151679D02*
X596612Y1182573D01*
X599955D01*
X600745Y1183363D01*
Y1184982D01*
X601535Y1185772D01*
X602655D01*
X603445Y1184982D01*
Y1183363D01*
X604235Y1182573D01*
X605355D01*
X606145Y1183363D01*
Y1184982D01*
X606935Y1185772D01*
X608055D01*
X608845Y1184982D01*
Y1183363D01*
X609635Y1182573D01*
X610755D01*
X611545Y1183363D01*
Y1184982D01*
X612335Y1185772D01*
X613455D01*
X614245Y1184982D01*
Y1183363D01*
X615035Y1182573D01*
X616390D01*
X617716Y1181247D01*
Y1174587D01*
X619007Y1173296D01*
X620448D01*
X622025Y1171719D01*
X625249D01*
G01X569443Y1148133D02*
X598847Y1177537D01*
X606056D01*
X606846Y1176747D01*
Y1172468D01*
X607636Y1171678D01*
X608756D01*
X609546Y1172468D01*
Y1176747D01*
X610336Y1177537D01*
X611890D01*
X612680Y1176747D01*
Y1171938D01*
X617478Y1167140D01*
X619068D01*
X619919Y1166289D01*
X620680D01*
X621943Y1165026D01*
X625249D01*
G01X567608Y1149968D02*
X597695Y1180055D01*
X613635D01*
X615198Y1178492D01*
Y1172982D01*
X617488Y1170692D01*
X620600D01*
X621227Y1170065D01*
G01X629227Y1170189D02*
X632848D01*
X634664Y1168373D01*
X641391D01*
G01X571302Y1146274D02*
X599540Y1174512D01*
X602792D01*
X603582Y1173722D01*
Y1172602D01*
X602792Y1171812D01*
X600855D01*
X600065Y1171022D01*
Y1169902D01*
X600855Y1169112D01*
X611945D01*
X617292Y1163765D01*
X620968D01*
X621227Y1163506D01*
G01X629227Y1163353D02*
X630889D01*
X632562Y1161680D01*
X641391D01*
G01X564312Y1158790D02*
X597386Y1191864D01*
X607458D01*
X608248Y1192654D01*
Y1194320D01*
X609038Y1195110D01*
X614565D01*
X615542Y1196087D01*
Y1198541D01*
X614608Y1199475D01*
X611036D01*
X610246Y1200265D01*
Y1201385D01*
X611036Y1202175D01*
X614752D01*
X615542Y1202965D01*
Y1211768D01*
X618997Y1215223D01*
X625249D01*
G01X564679Y1155596D02*
X598429Y1189346D01*
X610942D01*
X612745Y1191149D01*
X614065D01*
X615349Y1189865D01*
X617250D01*
X618166Y1190781D01*
Y1210804D01*
X618931Y1211569D01*
X619461Y1212849D01*
X620188Y1213576D01*
X621227D01*
G01X629227D02*
X631382D01*
X633081Y1211877D01*
X641391D01*
G01X534311Y1071273D02*
Y1073383D01*
G01X569370Y1140704D02*
X595237Y1166571D01*
X610925D01*
X619912Y1157584D01*
X622165D01*
X622899Y1158324D01*
X625249Y1158333D01*
G01X551671Y1170582D02*
Y1175248D01*
X556776Y1180353D01*
Y1181651D01*
X558037Y1182912D01*
X559335D01*
X560596Y1184173D01*
Y1185471D01*
X561857Y1186732D01*
X563155D01*
X564416Y1187993D01*
Y1189291D01*
X565677Y1190552D01*
X566975D01*
X568236Y1191813D01*
Y1193111D01*
X569497Y1194372D01*
X570795D01*
X572056Y1195633D01*
Y1196931D01*
X573317Y1198192D01*
X574615D01*
X575876Y1199453D01*
Y1200751D01*
X577137Y1202012D01*
X578435D01*
X579696Y1203273D01*
Y1204571D01*
X580957Y1205832D01*
X582255D01*
X583516Y1207093D01*
Y1208391D01*
X584777Y1209652D01*
X586075D01*
X587336Y1210913D01*
Y1212211D01*
X588597Y1213472D01*
X589895D01*
X591156Y1214733D01*
Y1216031D01*
X592417Y1217292D01*
X593715D01*
X594976Y1218553D01*
Y1219707D01*
X596381Y1221112D01*
X597535D01*
X598796Y1222373D01*
Y1223353D01*
X600375Y1224932D01*
X601355D01*
X602616Y1226193D01*
Y1227129D01*
X604239Y1228752D01*
X605175D01*
X606436Y1230013D01*
Y1231093D01*
X607915Y1232572D01*
X608995D01*
X613307Y1236884D01*
X616550Y1239051D01*
X618852Y1240004D01*
X619242Y1240166D01*
X620470D01*
X621988Y1238648D01*
X625249D01*
G01X554193Y1170582D02*
Y1173965D01*
X611603Y1231375D01*
X615440Y1234524D01*
X618852Y1236805D01*
X619419Y1237040D01*
X621227D01*
G01X629227Y1237011D02*
X632899D01*
X634608Y1235302D01*
X641391D01*
G01X561959Y1163624D02*
X595697Y1197362D01*
Y1199278D01*
X596487Y1200068D01*
X597607D01*
X598397Y1199278D01*
Y1197690D01*
X599187Y1196900D01*
X601854D01*
X602916Y1197962D01*
Y1199388D01*
X599970Y1202334D01*
Y1203452D01*
X600762Y1204244D01*
X601880D01*
X602964Y1203160D01*
X604140D01*
X604932Y1203952D01*
Y1205070D01*
X603819Y1206183D01*
Y1207301D01*
X614962Y1218444D01*
X615732Y1219076D01*
X618852Y1221160D01*
X620680Y1221916D01*
X625249D01*
G01X562530Y1160572D02*
X596340Y1194382D01*
X603628D01*
X607474Y1198228D01*
Y1204062D01*
X608264Y1204852D01*
X611298D01*
X611920Y1205474D01*
Y1206855D01*
X611031Y1207744D01*
Y1210865D01*
X617110Y1216944D01*
X618216Y1217684D01*
X618852Y1217622D01*
X619329Y1217575D01*
X620031Y1216873D01*
X621451D01*
G01X629051Y1216876D02*
X630531D01*
X632225Y1218570D01*
X641391D01*
G01X557416Y1168060D02*
X558736Y1169380D01*
X574888Y1189059D01*
X601845Y1216016D01*
X602537D01*
X604214Y1217693D01*
Y1218386D01*
X605889Y1220061D01*
X606582D01*
X608259Y1221738D01*
Y1222430D01*
X609897Y1224068D01*
X616515Y1228489D01*
X618779Y1229513D01*
X622012D01*
X622916Y1228609D01*
X625249D01*
G01X559212Y1166266D02*
X560724Y1167779D01*
X570955Y1180234D01*
X609825Y1219036D01*
X611563Y1220607D01*
X615683Y1223983D01*
X618214Y1225858D01*
X619079D01*
X620183Y1226962D01*
X621227D01*
G01X629227Y1226956D02*
X629230Y1226959D01*
X630443D01*
X631354Y1226048D01*
X632179D01*
X637544Y1227677D01*
X638467D01*
X639399Y1228609D01*
X641391D01*
G01X556503Y1168973D02*
X557778Y1170248D01*
X573930Y1189927D01*
X609074Y1225071D01*
X615887Y1229621D01*
X618500Y1230803D01*
X621836D01*
X622988Y1231955D01*
X625249D01*
G01X560124Y1165353D02*
X561682Y1166911D01*
X571912Y1179365D01*
X573268Y1180719D01*
X573961D01*
X575640Y1182394D01*
Y1183087D01*
X577317Y1184761D01*
X578010Y1184760D01*
X579689Y1186435D01*
Y1187128D01*
X581366Y1188802D01*
X582059D01*
X583738Y1190477D01*
Y1191170D01*
X585415Y1192844D01*
X586108D01*
X587787Y1194519D01*
Y1195212D01*
X589464Y1196886D01*
X590157Y1196885D01*
X591835Y1198561D01*
X591836Y1199254D01*
X610715Y1218100D01*
X612405Y1219629D01*
X616476Y1222965D01*
X618640Y1224568D01*
X619178D01*
X620177Y1223569D01*
X621227D01*
G01X629227Y1223568D02*
X630407D01*
X631597Y1224758D01*
X632371D01*
X637736Y1226387D01*
X638225D01*
X639349Y1225263D01*
X641391D01*
G01X534311Y1090498D02*
Y1092607D01*
X534310Y1092608D01*
G01X546558Y1169393D02*
X546099Y1169852D01*
Y1180828D01*
X606624Y1241353D01*
X609199Y1242420D01*
X609626Y1243451D01*
X609249Y1244361D01*
X609676Y1245392D01*
X610713Y1245822D01*
X611744Y1245395D01*
X612121Y1244485D01*
X613152Y1244058D01*
X617638Y1245916D01*
X621092D01*
X621667Y1245341D01*
X625249D01*
G01X549145Y1170582D02*
Y1175783D01*
X550426Y1178875D01*
X609103Y1237552D01*
X616059Y1242197D01*
X618852Y1243354D01*
X619667Y1243691D01*
X621227D01*
G01X629227Y1243707D02*
X630729D01*
X635456Y1241749D01*
X637841D01*
X638087Y1241995D01*
X641391D01*
G01X654949Y780184D02*
X648769D01*
X647033Y778448D01*
X645369D01*
G01X637369Y778469D02*
X635977D01*
X635187Y779259D01*
Y780276D01*
X634396Y781067D01*
X633331D01*
X632448Y780184D01*
X625249D01*
G01X654949Y773491D02*
X648769D01*
X647033Y771755D01*
X645369D01*
G01X637369Y771776D02*
X635616D01*
X634826Y772566D01*
Y773730D01*
X634182Y774374D01*
X633331D01*
X632448Y773491D01*
X625249D01*
G01X654949Y786877D02*
X652629D01*
X651682Y787824D01*
X650373D01*
X648560Y789637D01*
X647753D01*
X646634Y788518D01*
X645369D01*
G01X637369Y788498D02*
X636169D01*
X635049Y789618D01*
X634386D01*
X630445Y787986D01*
X628518D01*
X627409Y786877D01*
X625249D01*
G01X654949Y796916D02*
X648389D01*
X646653Y795180D01*
X645369D01*
G01X637369Y795201D02*
X634464D01*
X633870Y795795D01*
Y797168D01*
X633239Y797799D01*
X629731D01*
X628848Y796916D01*
X625249D01*
G01X654949Y790223D02*
X652789D01*
X651680Y789114D01*
X650908D01*
X649095Y790927D01*
X647640D01*
X646630Y791937D01*
X645369D01*
G01X637369Y791972D02*
X636276D01*
X635212Y790908D01*
X634129D01*
X630188Y789276D01*
X628516D01*
X627569Y790223D01*
X625249D01*
G01X654949Y816995D02*
X649207D01*
X647470Y815258D01*
X645369D01*
G01X637369Y815279D02*
X635560D01*
X634826Y816013D01*
Y817234D01*
X634182Y817878D01*
X633331D01*
X632448Y816995D01*
X625249D01*
G01X654949Y810302D02*
X649257D01*
X649256Y810303D01*
X647518Y808565D01*
X645369D01*
G01X637369Y808586D02*
X635008D01*
X634274Y809320D01*
Y810541D01*
X633630Y811185D01*
X632779D01*
X631896Y810302D01*
X625249D01*
G01X654949Y803609D02*
X648389D01*
X646653Y801873D01*
X645369D01*
G01X637369Y801894D02*
X634464D01*
X633870Y802488D01*
Y803637D01*
X633015Y804492D01*
X629923D01*
X629040Y803609D01*
X625249D01*
G01X654949Y833727D02*
X651715D01*
X650977Y834465D01*
X649507D01*
X647038Y831996D01*
X645369D01*
G01X637369Y831993D02*
X635711D01*
X634275Y833429D01*
X631383D01*
X629586Y835226D01*
X628859D01*
X627360Y833727D01*
X625249D01*
G01X654949Y823688D02*
X653057D01*
X652110Y824635D01*
X650721D01*
X648997Y826359D01*
X647636D01*
X646597Y825320D01*
X645369D01*
G01X637369Y825246D02*
X636226D01*
X635203Y826269D01*
X634132D01*
X632892Y825755D01*
X631934Y824797D01*
X628518D01*
X627409Y823688D01*
X625249D01*
G01X654949Y827034D02*
X653207D01*
X652098Y825925D01*
X651256D01*
X649532Y827649D01*
X647611D01*
X646477Y828783D01*
X645369D01*
G01X637369Y828770D02*
X636291D01*
X635080Y827559D01*
X633874D01*
X632161Y826849D01*
X631399Y826087D01*
X628516D01*
X627569Y827034D01*
X625249D01*
G01X654949Y847113D02*
X648769D01*
X647073Y845417D01*
X645372D01*
X645369Y845420D01*
G01X637369Y845379D02*
X635616D01*
X634826Y846169D01*
Y847352D01*
X634182Y847996D01*
X632217D01*
X631334Y847113D01*
X625249D01*
G01X654949Y840420D02*
X648771D01*
X648770Y840421D01*
X647038Y838689D01*
X645369D01*
G01X637369Y838695D02*
X635616D01*
X634826Y839485D01*
Y839989D01*
X633129Y841686D01*
X629752D01*
X628486Y840420D01*
X625249D01*
G01X654949Y853806D02*
X649217D01*
X647476Y852065D01*
X645369D01*
G01X637369Y852079D02*
X635233D01*
X634442Y852870D01*
Y854037D01*
X633771Y854708D01*
X632920D01*
X632018Y853806D01*
X625249D01*
G01X654949Y860499D02*
X652629D01*
X651682Y861446D01*
X650373D01*
X648818Y863001D01*
X647699D01*
X646804Y862106D01*
X645369D01*
G01X637369Y862066D02*
X635649D01*
X634475Y863240D01*
X632799D01*
X631167Y861608D01*
X628518D01*
X627409Y860499D01*
X625249D01*
G01X654949Y863845D02*
X652789D01*
X651680Y862736D01*
X650908D01*
X649353Y864291D01*
X647974D01*
X646682Y865583D01*
X645369D01*
G01X637369Y865570D02*
X635470D01*
X634430Y864530D01*
X632264D01*
X630632Y862898D01*
X628516D01*
X627569Y863845D01*
X625249D01*
G01X620799Y883924D02*
X625249D01*
G01X654949D02*
X654948Y883925D01*
X648682D01*
X646983Y882226D01*
X645369D01*
G01X636648Y882251D02*
X635291D01*
X634826Y882716D01*
Y884163D01*
X634086Y884903D01*
X632215D01*
X631236Y883924D01*
X625249D01*
G01X654949Y877231D02*
X648771D01*
X648745Y877257D01*
X646988Y875500D01*
X645369D01*
G01X637369Y875520D02*
X634576D01*
X633983Y876113D01*
Y877372D01*
X633115Y878240D01*
X631460D01*
X630451Y877231D01*
X625249D01*
G01X654949Y870538D02*
X648183D01*
X646452Y868807D01*
X645369D01*
G01X637369Y868831D02*
X634572D01*
X633983Y869420D01*
Y870679D01*
X633115Y871547D01*
X629818D01*
X628809Y870538D01*
X625249D01*
G01X620799Y890617D02*
X625249D01*
G01X654949D02*
X654948Y890618D01*
X648682D01*
X646983Y888919D01*
X645369D01*
G01X636648Y888944D02*
X635291D01*
X634826Y889409D01*
Y890856D01*
X634086Y891596D01*
X632215D01*
X631236Y890617D01*
X625249D01*
G01X620799Y897310D02*
X625249D01*
G01X654949D02*
X652629D01*
X651652Y898287D01*
X650317D01*
X648510Y900094D01*
X647609D01*
X646403Y898888D01*
X645369D01*
G01X636599Y898983D02*
X636169D01*
X635101Y900051D01*
X632922D01*
X631290Y898419D01*
X628518D01*
X627409Y897310D01*
X625249D01*
G01X620799Y900656D02*
X625249D01*
G01X654949D02*
X652789D01*
X651710Y899577D01*
X650852D01*
X649045Y901384D01*
X647612D01*
X646592Y902404D01*
X645369D01*
G01X636622Y902330D02*
X636201D01*
X635212Y901341D01*
X632387D01*
X630755Y899709D01*
X628516D01*
X627569Y900656D01*
X625249D01*
G01X620799Y914042D02*
X625249D01*
G01X654949D02*
X654948Y914043D01*
X648682D01*
X647008Y912369D01*
X646194D01*
G01X636648D02*
X635291D01*
X634826Y912834D01*
Y914147D01*
X634086Y914887D01*
X632081D01*
X631236Y914042D01*
X625249D01*
G01X620799Y907349D02*
X625249D01*
G01X654949D02*
X654948Y907350D01*
X648682D01*
X646983Y905651D01*
X645369D01*
G01X636648Y905676D02*
X635291D01*
X634826Y906141D01*
Y907588D01*
X634086Y908328D01*
X632215D01*
X631236Y907349D01*
X625249D01*
G01X654949Y927428D02*
X649100D01*
X647427Y925755D01*
X646602D01*
G01X635644Y925654D02*
X635226D01*
X633438Y927442D01*
X632320D01*
X630681Y925803D01*
X629060D01*
X627435Y927428D01*
X625249D01*
G01X654949Y920735D02*
X651211D01*
X650868Y921078D01*
X649451D01*
X647366Y918993D01*
X646011D01*
G01X636694Y919010D02*
X635286D01*
X634496Y919800D01*
Y920976D01*
X633713Y921759D01*
X632595D01*
X631572Y920736D01*
X625250D01*
X625249Y920735D01*
G01X654949Y944160D02*
X648402D01*
X646656Y942414D01*
X646130D01*
G01X636695Y942412D02*
X636058D01*
X634009Y944461D01*
X632624D01*
X632124Y943961D01*
Y943320D01*
X631424Y942620D01*
X629924D01*
X628383Y944161D01*
X625250D01*
X625249Y944160D01*
G01X654949Y934121D02*
X652913D01*
X651713Y935321D01*
X650808D01*
X649548Y936581D01*
X648309D01*
X647522Y935794D01*
X647002D01*
G01X635778Y935728D02*
X635467D01*
X634384Y936811D01*
X633535D01*
X631954Y935230D01*
X628518D01*
X627409Y934121D01*
X625249D01*
G01X654949Y937467D02*
X653317D01*
X652461Y936611D01*
X651343D01*
X650083Y937871D01*
X648706D01*
X647436Y939141D01*
X647002D01*
G01X635778Y939217D02*
X635327D01*
X634211Y938101D01*
X633000D01*
X631419Y936520D01*
X628516D01*
X627569Y937467D01*
X625249D01*
G01X620799Y960892D02*
X625249D01*
G01X654949Y950853D02*
X651322D01*
X650851Y951324D01*
X649353D01*
X648563Y950534D01*
Y949884D01*
X647773Y949094D01*
X645821D01*
G01X636555Y949180D02*
X635952D01*
X634731Y950401D01*
X633612D01*
X632477Y949266D01*
X631359D01*
X629771Y950854D01*
X625250D01*
X625249Y950853D01*
G01X620799Y957546D02*
X625249D01*
G01X654949Y980971D02*
X651505D01*
X649756Y982720D01*
X645369D01*
G01X637369Y982728D02*
X636190D01*
X635103Y981641D01*
X633400D01*
X633030Y982011D01*
Y982478D01*
X632440Y983068D01*
X631092D01*
X628995Y980971D01*
X625249D01*
G01X654949Y974278D02*
X651377D01*
X648895Y976760D01*
X647777D01*
X647006Y975989D01*
X645369D01*
G01X637369Y976007D02*
X635441D01*
X633850Y977598D01*
X632459D01*
X630652Y975791D01*
X628689D01*
X627176Y974278D01*
X625249D01*
G01X654949Y994357D02*
X648290D01*
X646617Y992684D01*
X645369D01*
G01X637369Y993441D02*
X636869Y993941D01*
Y994819D01*
X635269Y996419D01*
X629497D01*
X627435Y994357D01*
X625249D01*
G01X654949Y987664D02*
X649589D01*
X647862Y989391D01*
X645369D01*
G01X637369Y989389D02*
X635293D01*
X634114Y990568D01*
X632461D01*
X631820Y989927D01*
Y989068D01*
X630416Y987664D01*
X625249D01*
G01X654949Y1027822D02*
X649685D01*
X647947Y1029560D01*
X645369D01*
G01X637369Y1029648D02*
X636221D01*
X635067Y1028494D01*
Y1026525D01*
X633896Y1025354D01*
X631609D01*
X630794Y1026169D01*
X628918D01*
X627265Y1027822D01*
X625249D01*
G01X654949Y1021129D02*
X649793D01*
X645228Y1025694D01*
G01X637553D02*
X637365Y1025506D01*
X636455D01*
X632078Y1021129D01*
X625249D01*
G01X654949Y1047900D02*
X651420D01*
X650454Y1048866D01*
X649448D01*
X648752Y1048170D01*
X647868D01*
X646419Y1049619D01*
X645369D01*
G01X637369Y1049636D02*
X636247D01*
X635755Y1049144D01*
X634366D01*
X634020Y1048798D01*
Y1047549D01*
X633590Y1047119D01*
X628181D01*
X627400Y1047900D01*
X625249D01*
G01X654949Y1041207D02*
X650527D01*
X648815Y1042919D01*
X645369D01*
G01X637369Y1042947D02*
X636181D01*
X632791Y1039557D01*
X629195D01*
X627545Y1041207D01*
X625249D01*
G01X654949Y1034515D02*
X654470Y1034994D01*
X650237D01*
X648927Y1036304D01*
X645369D01*
G01X637369Y1036275D02*
X636300D01*
X634149Y1034124D01*
X631490D01*
X630312Y1032946D01*
X628970D01*
X627401Y1034515D01*
X625249D01*
G01X620899Y1061286D02*
X625249D01*
G01X654949D02*
X652624D01*
X651028Y1062882D01*
X649666D01*
X647916Y1061132D01*
Y1060482D01*
X647047Y1059613D01*
X646073D01*
G01X636648D02*
X635927D01*
X634639Y1058325D01*
X631941D01*
X628980Y1061286D01*
X625249D01*
G01X654949Y1074672D02*
X649284D01*
X647611Y1072999D01*
X646894D01*
G01X635775D02*
X635353D01*
X634431Y1073921D01*
Y1074703D01*
X633640Y1075494D01*
X632386D01*
X631089Y1074197D01*
X629629D01*
X629154Y1074672D01*
X625249D01*
G01X654949Y1067979D02*
X648752D01*
X647079Y1066306D01*
X646073D01*
G01X636264Y1065991D02*
X634575Y1064302D01*
X633752D01*
X633335Y1064719D01*
Y1067289D01*
X632645Y1067979D01*
X625249D01*
G01X654949Y1091404D02*
X648170D01*
X646497Y1089731D01*
X646073D01*
G01X636264D02*
X635821D01*
X635264Y1090288D01*
Y1091652D01*
X634474Y1092442D01*
X633193D01*
X631581Y1090830D01*
X630462D01*
X629887Y1091405D01*
X625250D01*
X625249Y1091404D01*
G01X654949Y1081365D02*
X652789D01*
X651842Y1082312D01*
X650373D01*
X648757Y1083928D01*
X647556D01*
X646616Y1082988D01*
X645974D01*
G01X635939Y1082976D02*
X634949D01*
X633891Y1084034D01*
X632598D01*
X631038Y1082474D01*
X628518D01*
X627409Y1081365D01*
X625249D01*
G01X654949Y1084711D02*
X652733D01*
X651652Y1083630D01*
X650880D01*
X649292Y1085218D01*
X647833D01*
X646585Y1086466D01*
X645974D01*
G01X635960Y1086429D02*
X635007D01*
X633902Y1085324D01*
X632063D01*
X630503Y1083764D01*
X628516D01*
X627569Y1084711D01*
X625249D01*
G01X654949Y1098097D02*
X650214D01*
X649511Y1098800D01*
X648283D01*
X647492Y1098009D01*
Y1096812D01*
X646702Y1096022D01*
X646073D01*
G01X636264Y1096424D02*
X635330D01*
X635075Y1096169D01*
X631773D01*
X629844Y1098098D01*
X625250D01*
X625249Y1098097D01*
G01X654949Y1111483D02*
X648719D01*
X646970Y1109734D01*
X645369D01*
G01X637369Y1109773D02*
X636149D01*
X635322Y1110600D01*
Y1111905D01*
X634631Y1112596D01*
X633308D01*
X632195Y1111483D01*
X625249D01*
G01X654949Y1104790D02*
X648182D01*
X646470Y1106502D01*
X645369D01*
G01X637369Y1106534D02*
X636066D01*
X633986Y1104454D01*
X632388D01*
X630421Y1106421D01*
X628895D01*
X627264Y1104790D01*
X625249D01*
G01X654949Y1128215D02*
X648365D01*
X646625Y1126475D01*
X645369D01*
G01X637369Y1126498D02*
X635616D01*
X634826Y1127288D01*
Y1128454D01*
X634182Y1129098D01*
X629755D01*
X628872Y1128215D01*
X625249D01*
G01X654949Y1118176D02*
X652789D01*
X651842Y1119123D01*
X650373D01*
X648757Y1120739D01*
X647556D01*
X646640Y1119823D01*
X645369D01*
G01X637369Y1119787D02*
X636231D01*
X635101Y1120917D01*
X633410D01*
X631778Y1119285D01*
X628518D01*
X627409Y1118176D01*
X625249D01*
G01X654949Y1121522D02*
X652789D01*
X651680Y1120413D01*
X650908D01*
X649292Y1122029D01*
X647833D01*
X646593Y1123269D01*
X645369D01*
G01X637369Y1123242D02*
X636247D01*
X635212Y1122207D01*
X632875D01*
X631243Y1120575D01*
X628516D01*
X627569Y1121522D01*
X625249D01*
G01X654949Y1141601D02*
X651361D01*
X650856Y1142106D01*
X649268D01*
X647054Y1139892D01*
X645370D01*
X645369Y1139893D01*
G01X637369Y1139902D02*
X635853D01*
X635327Y1140428D01*
Y1141101D01*
X634827Y1141601D01*
X630796D01*
X629703Y1142694D01*
X628256D01*
X627163Y1141601D01*
X625249D01*
G01X654949Y1134908D02*
X651310D01*
X650450Y1135768D01*
X648923D01*
X648513Y1135358D01*
Y1134056D01*
X647721Y1133264D01*
X645369D01*
G01X637369Y1133201D02*
X634609D01*
X631646Y1136164D01*
X630146D01*
X628890Y1134908D01*
X625249D01*
G01X654949Y1148294D02*
X648313D01*
X646616Y1146597D01*
X645377D01*
X645369Y1146605D01*
G01X637369Y1146589D02*
X635856D01*
X635264Y1147181D01*
Y1148677D01*
X634622Y1149319D01*
X633503D01*
X632478Y1148294D01*
X625249D01*
G01X654949Y1154987D02*
X652789D01*
X651842Y1155934D01*
X650373D01*
X648757Y1157550D01*
X647556D01*
X646640Y1156634D01*
X645369D01*
G01X637369Y1156598D02*
X636231D01*
X635101Y1157728D01*
X633410D01*
X631778Y1156096D01*
X628518D01*
X627409Y1154987D01*
X625249D01*
G01X654949Y1158333D02*
X652789D01*
X651680Y1157224D01*
X650908D01*
X649292Y1158840D01*
X647833D01*
X646593Y1160080D01*
X645369D01*
G01X637369Y1160053D02*
X636247D01*
X635212Y1159018D01*
X632875D01*
X631243Y1157386D01*
X628516D01*
X627569Y1158333D01*
X625249D01*
G01X654949Y1171719D02*
X648535D01*
X646817Y1170001D01*
X645369D01*
G01X637369Y1170017D02*
X635654D01*
X634826Y1170845D01*
Y1171958D01*
X634086Y1172698D01*
X629517D01*
X628538Y1171719D01*
X625249D01*
G01X654949Y1165026D02*
X648377D01*
X646659Y1163308D01*
X645369D01*
G01X637369Y1163324D02*
X635807D01*
X634996Y1164135D01*
Y1165976D01*
X634558Y1166414D01*
X633961D01*
X632474Y1167901D01*
X631583D01*
X628708Y1165026D01*
X625249D01*
G01X620799Y1185105D02*
X625249D01*
G01X654949D02*
X654948Y1185106D01*
X648682D01*
X646983Y1183407D01*
X645369D01*
G01X636648Y1183432D02*
X635291D01*
X634826Y1183897D01*
Y1185344D01*
X634086Y1186084D01*
X632215D01*
X631236Y1185105D01*
X625249D01*
G01X620799Y1178412D02*
X625249D01*
G01X654949D02*
X654948Y1178413D01*
X648682D01*
X646983Y1176714D01*
X645369D01*
G01X636648Y1176739D02*
X635291D01*
X634826Y1177204D01*
Y1178651D01*
X634086Y1179391D01*
X632215D01*
X631236Y1178412D01*
X625249D01*
G01X620799Y1191798D02*
X625249D01*
G01X654949D02*
X652629D01*
X651644Y1192783D01*
X650455D01*
X648877Y1194361D01*
X647556D01*
X646601Y1193406D01*
X645369D01*
G01X636590Y1193471D02*
X636169D01*
X635101Y1194539D01*
X633143D01*
X631511Y1192907D01*
X628518D01*
X627409Y1191798D01*
X625249D01*
G01X620799Y1208530D02*
X625249D01*
G01X654949D02*
X651533D01*
X650858Y1209205D01*
X649118D01*
X646732Y1206819D01*
X645369D01*
G01X636387Y1206857D02*
X635461D01*
X634239Y1205635D01*
X632387D01*
X631291Y1206731D01*
Y1207264D01*
X630025Y1208530D01*
X625249D01*
G01X620799Y1201837D02*
X625249D01*
G01X654949D02*
X648473D01*
X646765Y1200129D01*
X645369D01*
G01X636656Y1200164D02*
X635429D01*
X634826Y1200767D01*
Y1202732D01*
X633992Y1203566D01*
X632335D01*
X630606Y1201837D01*
X625249D01*
G01X620799Y1195144D02*
X625249D01*
G01X654949D02*
X652789D01*
X651718Y1194073D01*
X650990D01*
X649412Y1195651D01*
X647631D01*
X646419Y1196863D01*
X645369D01*
G01X636590Y1196818D02*
X636201D01*
X635212Y1195829D01*
X632608D01*
X630976Y1194197D01*
X628516D01*
X627569Y1195144D01*
X625249D01*
G01X654949Y1221916D02*
X649079D01*
X647368Y1220205D01*
X645369D01*
G01X637369Y1220200D02*
X634626D01*
X634065Y1220761D01*
Y1222122D01*
X633421Y1222766D01*
X632560D01*
X631258Y1221464D01*
X628910D01*
X628458Y1221916D01*
X625249D01*
G01X654949Y1215223D02*
X651539D01*
X650687Y1216075D01*
X649301D01*
X646754Y1213528D01*
X645369D01*
G01X637369D02*
X635560D01*
X634826Y1214262D01*
Y1215288D01*
X634036Y1216078D01*
X632551D01*
X631696Y1215223D01*
X625249D01*
G01X654949Y1238648D02*
X648205D01*
X646493Y1236936D01*
X645369D01*
G01X637369Y1236940D02*
X635616D01*
X634826Y1237730D01*
Y1239179D01*
X634035Y1239970D01*
X630002D01*
X628680Y1238648D01*
X625249D01*
G01X654949Y1228609D02*
X652929D01*
X651982Y1229556D01*
X650721D01*
X648997Y1231280D01*
X648292D01*
X647271Y1230259D01*
X645369D01*
G01X637369Y1230167D02*
X635188D01*
X634005Y1231350D01*
X631828D01*
X630196Y1229718D01*
X628518D01*
X627409Y1228609D01*
X625249D01*
G01X654949Y1231955D02*
X653207D01*
X652098Y1230846D01*
X651256D01*
X649532Y1232570D01*
X648415D01*
X647334Y1233651D01*
X645372D01*
X645369Y1233648D01*
G01X637369Y1233629D02*
X635321D01*
X634332Y1232640D01*
X631293D01*
X629661Y1231008D01*
X628516D01*
X627569Y1231955D01*
X625249D01*
G01X654949Y1245341D02*
X648623D01*
X646912Y1243630D01*
X645369D01*
G01X637369Y1243521D02*
X635703D01*
X634899Y1244325D01*
Y1245447D01*
X633895Y1246451D01*
X628642D01*
X627532Y1245341D01*
X625249D01*
G01X671091Y770144D02*
X665888D01*
X664896Y769152D01*
X663384D01*
X662462Y770074D01*
Y771108D01*
X661690Y771880D01*
X658927D01*
G01X650927Y771859D02*
X649766D01*
X648051Y770144D01*
X641391D01*
G01X671091Y776837D02*
X665888D01*
X664896Y775845D01*
X663384D01*
X662462Y776767D01*
Y777783D01*
X661672Y778573D01*
X658927D01*
G01X650927Y778552D02*
X649766D01*
X648051Y776837D01*
X641391D01*
G01X671091Y786877D02*
X669108D01*
X668107Y785876D01*
X664990D01*
X663236Y784122D01*
X661307D01*
X660182Y785247D01*
X658927D01*
G01X650927Y785228D02*
X649698D01*
X648606Y784136D01*
X648124D01*
X646451Y785809D01*
X644548D01*
X643480Y786877D01*
X641391D01*
G01X671091Y783530D02*
X668855D01*
X667799Y784586D01*
X665525D01*
X663771Y782832D01*
X661198D01*
X660194Y781828D01*
X658927D01*
G01X650927Y781829D02*
X649702D01*
X648685Y782846D01*
X647589D01*
X645916Y784519D01*
X644360D01*
X643371Y783530D01*
X641391D01*
G01X671091Y800263D02*
X665888D01*
X664896Y799271D01*
X663384D01*
X662462Y800193D01*
Y801208D01*
X661671Y801999D01*
X658927D01*
G01X650927Y801978D02*
X649766D01*
X648051Y800263D01*
X641391D01*
G01X671091Y793570D02*
X665888D01*
X664896Y792578D01*
X663384D01*
X662462Y793500D01*
Y794515D01*
X661671Y795306D01*
X658927D01*
G01X650927Y795285D02*
X649766D01*
X648051Y793570D01*
X641391D01*
G01X671091Y813648D02*
X665888D01*
X664896Y812656D01*
X663384D01*
X662462Y813578D01*
Y814594D01*
X661672Y815384D01*
X658927D01*
G01X650927Y815363D02*
X649876D01*
X648161Y813648D01*
X641391D01*
G01X671091Y806955D02*
X665888D01*
X664896Y805963D01*
X663384D01*
X662462Y806885D01*
Y807901D01*
X661672Y808691D01*
X658927D01*
G01X650927Y808670D02*
X649898D01*
X648183Y806955D01*
X641391D01*
G01X671091Y820341D02*
X669126D01*
X668071Y821396D01*
X666379D01*
X664625Y819642D01*
X661938D01*
X660938Y818642D01*
X658927D01*
G01X650927Y818588D02*
X649727D01*
X648745Y819570D01*
X646991D01*
X645232Y821329D01*
X644420D01*
X643432Y820341D01*
X641391D01*
G01X671091Y830381D02*
X665888D01*
X664896Y829389D01*
X663248D01*
X662462Y830175D01*
Y831344D01*
X661689Y832117D01*
X658927D01*
G01X650927Y832096D02*
X649766D01*
X648051Y830381D01*
X641391D01*
G01X671091Y823688D02*
X669251D01*
X668249Y822686D01*
X665844D01*
X664090Y820932D01*
X662011D01*
X660890Y822053D01*
X658927D01*
G01X650927Y822037D02*
X649813D01*
X648636Y820860D01*
X647526D01*
X645767Y822619D01*
X644328D01*
X643259Y823688D01*
X641391D01*
G01X671091Y850459D02*
X665888D01*
X664896Y849467D01*
X663384D01*
X662462Y850389D01*
Y851396D01*
X661672Y852186D01*
X658927D01*
G01X650927Y852197D02*
X649937D01*
X648199Y850459D01*
X641391D01*
G01X671091Y843766D02*
X665888D01*
X664896Y842774D01*
X663384D01*
X662462Y843696D01*
Y844712D01*
X661672Y845502D01*
X658927D01*
G01X650927Y845481D02*
X649766D01*
X648051Y843766D01*
X641391D01*
G01X671091Y837074D02*
X665888D01*
X664535Y835721D01*
X663252D01*
X662462Y836511D01*
Y838019D01*
X661671Y838810D01*
X658927D01*
G01X650927Y838789D02*
X649766D01*
X648051Y837074D01*
X641391D01*
G01X671091Y867192D02*
X665888D01*
X664896Y866200D01*
X663384D01*
X662462Y867122D01*
Y868256D01*
X661779Y868939D01*
X658927D01*
G01X650927Y868922D02*
X648869D01*
X647139Y867192D01*
X641391D01*
G01X671091Y860499D02*
X669108D01*
X668107Y859498D01*
X664990D01*
X663236Y857744D01*
X661307D01*
X660182Y858869D01*
X658927D01*
G01X650927Y858850D02*
X649698D01*
X648606Y857758D01*
X648124D01*
X647303Y858579D01*
X645246Y859431D01*
X644548D01*
X643480Y860499D01*
X641391D01*
G01X671091Y857152D02*
X668855D01*
X667799Y858208D01*
X665525D01*
X663771Y856454D01*
X661198D01*
X660194Y855450D01*
X658927D01*
G01X650927Y855451D02*
X649702D01*
X648685Y856468D01*
X647589D01*
X646572Y857485D01*
X644989Y858141D01*
X644376D01*
X643387Y857152D01*
X641391D01*
G01X671091Y873885D02*
X665888D01*
X664896Y872893D01*
X663384D01*
X662462Y873815D01*
Y874949D01*
X661779Y875632D01*
X658927D01*
G01X650927Y875615D02*
X649613D01*
X647883Y873885D01*
X641391D01*
G01X636941Y880577D02*
X641391D01*
G01X671091D02*
X665888D01*
X664896Y879585D01*
X663384D01*
X662462Y880507D01*
Y881641D01*
X661779Y882324D01*
X658927D01*
G01X650927Y882307D02*
X649645D01*
X647915Y880577D01*
X641391D01*
G01X636941Y887270D02*
X641391D01*
G01X671091D02*
X665888D01*
X664896Y886278D01*
X663384D01*
X662462Y887200D01*
Y888334D01*
X661779Y889017D01*
X658927D01*
G01X650927Y889000D02*
X649505D01*
X647775Y887270D01*
X641391D01*
G01X636941Y897310D02*
X641391D01*
G01X671091D02*
X669108D01*
X668107Y896309D01*
X664990D01*
X663236Y894555D01*
X661307D01*
X660182Y895680D01*
X658927D01*
G01X650927Y895661D02*
X649698D01*
X648606Y894569D01*
X648124D01*
X646451Y896242D01*
X644548D01*
X643480Y897310D01*
X641391D01*
G01X636941Y893963D02*
X641391D01*
G01X671091D02*
X668855D01*
X667799Y895019D01*
X665525D01*
X663771Y893265D01*
X661198D01*
X660194Y892261D01*
X658927D01*
G01X650927Y892262D02*
X649702D01*
X648685Y893279D01*
X647589D01*
X645916Y894952D01*
X644716D01*
X643727Y893963D01*
X641391D01*
G01X671091Y917389D02*
X666762D01*
X664794Y915421D01*
X663393D01*
X662465Y916349D01*
Y917059D01*
X662472Y917066D01*
Y918284D01*
X661694Y919062D01*
X659797D01*
G01X650126D02*
X649732D01*
X647763Y917093D01*
X645130D01*
X644833Y917390D01*
X641392D01*
X641391Y917389D01*
G01X636941Y910696D02*
X641391D01*
G01X671091D02*
X665888D01*
X664896Y909704D01*
X663384D01*
X662462Y910626D01*
Y911648D01*
X661690Y912420D01*
X658927D01*
G01X650927Y912428D02*
X649783D01*
X648051Y910696D01*
X641391D01*
G01X636941Y904003D02*
X641391D01*
G01X671091D02*
X665888D01*
X664896Y903011D01*
X663384D01*
X662462Y903933D01*
Y904995D01*
X661690Y905767D01*
X658927D01*
G01X650927Y905731D02*
X649779D01*
X648051Y904003D01*
X641391D01*
G01X671091Y924081D02*
X666068D01*
X664826Y922839D01*
X663559D01*
X662769Y923629D01*
Y925031D01*
X661979Y925821D01*
X660861D01*
G01X650227Y925810D02*
X649731D01*
X647647Y923726D01*
X645498D01*
X645141Y924083D01*
X641393D01*
X641391Y924081D01*
G01X671091Y934121D02*
X669108D01*
X668055Y933068D01*
X666002D01*
X664300Y931366D01*
X662171D01*
X661046Y932491D01*
X660494D01*
G01X649253Y932472D02*
X648846D01*
X647759Y931385D01*
X646849D01*
X645181Y933053D01*
X643878D01*
X642810Y934121D01*
X641391D01*
G01X671091Y930774D02*
X668855D01*
X667851Y931778D01*
X666537D01*
X664835Y930076D01*
X662200D01*
X661196Y929072D01*
X660494D01*
G01X649253Y929101D02*
X648814D01*
X647820Y930095D01*
X646314D01*
X644646Y931763D01*
X643830D01*
X642841Y930774D01*
X641391D01*
G01X671091Y947507D02*
X665645D01*
X664849Y948303D01*
X663613D01*
X662823Y947513D01*
Y945510D01*
X662033Y944720D01*
X659969D01*
X659310Y945379D01*
G01X650231Y945834D02*
X649581D01*
X648285Y947130D01*
X644948D01*
X644571Y947507D01*
X641391D01*
G01X671091Y940814D02*
X665051D01*
X663942Y939705D01*
X662824D01*
X662034Y940495D01*
Y941883D01*
X661337Y942580D01*
X659714D01*
G01X650194Y942525D02*
X649513D01*
X647802Y940814D01*
X641391D01*
G01X671091Y977625D02*
X667813D01*
X666830Y978608D01*
X664850D01*
X663660Y977418D01*
X661734D01*
X661370Y977782D01*
Y978492D01*
X660471Y979391D01*
X658927D01*
G01X650927Y979330D02*
X646774D01*
X645069Y977625D01*
X641391D01*
G01X671091Y970932D02*
X665617D01*
X664109Y972440D01*
Y973445D01*
X663319Y974235D01*
X661393D01*
X659813Y972655D01*
X658927D01*
G01X650927Y972667D02*
X646319D01*
X642129Y970932D01*
X641391D01*
G01X671091Y991011D02*
X667597D01*
X663920Y994688D01*
X662140D01*
X660188Y992736D01*
X658927D01*
G01X650927Y992761D02*
X649363D01*
X647613Y991011D01*
X641391D01*
G01X671091Y984318D02*
X666470D01*
X665320Y983168D01*
X663970D01*
X662970Y984168D01*
Y985541D01*
X662470Y986041D01*
X658927D01*
G01X650927Y986028D02*
X648385D01*
X647525Y985168D01*
X644461D01*
X643611Y984318D01*
X641391D01*
G01X671091Y1031168D02*
X666700D01*
X665020Y1029488D01*
X663380D01*
X659963Y1032905D01*
X658927D01*
G01X650927Y1032903D02*
X648559D01*
X646824Y1031168D01*
X641391D01*
G01X671091Y1044554D02*
X666974D01*
X666190Y1045338D01*
X665250D01*
X664190Y1044278D01*
X661970D01*
X661490Y1044758D01*
Y1045602D01*
X660780Y1046312D01*
X658927D01*
G01X650927Y1046260D02*
X647996D01*
X646290Y1044554D01*
X641391D01*
G01X671091Y1037861D02*
X666040D01*
X664337Y1036158D01*
X663070D01*
X662400Y1036828D01*
Y1038821D01*
X661610Y1039611D01*
X658927D01*
G01X650927Y1039589D02*
X646471D01*
X644743Y1037861D01*
X641391D01*
G01X671091Y1071326D02*
X667967D01*
X667570Y1071723D01*
X666603D01*
X664321Y1069441D01*
X662802D01*
X662465Y1069778D01*
Y1072129D01*
X661595Y1072999D01*
X660076D01*
G01X650267D02*
X649874D01*
X647834Y1070959D01*
X643733D01*
X643365Y1071327D01*
X641392D01*
X641391Y1071326D01*
G01X671091Y1064633D02*
X666184D01*
X665292Y1063741D01*
X663525D01*
X662582Y1064684D01*
Y1065516D01*
X661792Y1066306D01*
X660076D01*
G01X650267D02*
X649472D01*
X647444Y1064278D01*
X645497D01*
X645141Y1064634D01*
X641392D01*
X641391Y1064633D01*
G01X671091Y1081365D02*
X669108D01*
X668081Y1080338D01*
X665636D01*
X663908Y1078610D01*
X661993D01*
X660911Y1079692D01*
X660578D01*
G01X649518D02*
X649026D01*
X648011Y1078677D01*
X647716D01*
X646348Y1079244D01*
X645295Y1080297D01*
X644060D01*
X642992Y1081365D01*
X641391D01*
G01X671091Y1078018D02*
X668855D01*
X667825Y1079048D01*
X666171D01*
X664443Y1077320D01*
X661942D01*
X660967Y1076345D01*
X660646D01*
G01X649497D02*
X649018D01*
X647976Y1077387D01*
X647459D01*
X645617Y1078150D01*
X644760Y1079007D01*
X644008D01*
X643019Y1078018D01*
X641391D01*
G01X671091Y1094751D02*
X665006D01*
X663969Y1093714D01*
Y1092614D01*
X663319Y1091964D01*
X659879D01*
X659210Y1092633D01*
G01X649822Y1093078D02*
X648059D01*
X646780Y1094357D01*
X644181D01*
X643787Y1094751D01*
X641391D01*
G01X671091Y1088058D02*
X665271D01*
X664182Y1086969D01*
X663064D01*
X662274Y1087759D01*
Y1088941D01*
X661484Y1089731D01*
X661050D01*
G01X649518D02*
X648793D01*
X647120Y1088058D01*
X641391D01*
G01X671091Y1108137D02*
X665888D01*
X664596Y1106845D01*
X663284D01*
X662462Y1107667D01*
Y1109048D01*
X661676Y1109834D01*
X658980D01*
X658966Y1109830D01*
X658947Y1109839D01*
X658927D01*
G01X650927Y1109845D02*
X649749D01*
X648041Y1108137D01*
X641391D01*
G01X671091Y1101444D02*
X668748D01*
X667198Y1102994D01*
X665549D01*
X664794Y1102239D01*
Y1101214D01*
X664015Y1100435D01*
X662296D01*
X661506Y1101225D01*
Y1102359D01*
X660716Y1103149D01*
X658927D01*
G01X650927D02*
X648245D01*
X646540Y1101444D01*
X641391D01*
G01X671091Y1124869D02*
X665888D01*
X664896Y1123877D01*
X663384D01*
X662462Y1124799D01*
Y1125868D01*
X661743Y1126587D01*
X658927D01*
G01X650927Y1126571D02*
X649399D01*
X647697Y1124869D01*
X641391D01*
G01X671091Y1118176D02*
X669108D01*
X668107Y1117175D01*
X664990D01*
X663236Y1115421D01*
X661307D01*
X660182Y1116546D01*
X658927D01*
G01X650927Y1116527D02*
X649698D01*
X648606Y1115435D01*
X648124D01*
X646451Y1117108D01*
X644548D01*
X643480Y1118176D01*
X641391D01*
G01X671091Y1114829D02*
X668855D01*
X667799Y1115885D01*
X665525D01*
X663771Y1114131D01*
X661198D01*
X660194Y1113127D01*
X658927D01*
G01X650927Y1113128D02*
X649702D01*
X648685Y1114145D01*
X647589D01*
X645916Y1115818D01*
X644716D01*
X643727Y1114829D01*
X641391D01*
G01X671091Y1144948D02*
X665888D01*
X664896Y1143956D01*
X663384D01*
X662462Y1144878D01*
Y1145876D01*
X661672Y1146666D01*
X658927D01*
G01X650927Y1146650D02*
X649221D01*
X646606Y1144035D01*
X644416D01*
X643503Y1144948D01*
X641391D01*
G01X671091Y1138255D02*
X665888D01*
X664896Y1137263D01*
X663384D01*
X662462Y1138185D01*
Y1139207D01*
X661696Y1139973D01*
X658927D01*
G01X650927Y1139957D02*
X649781D01*
X648079Y1138255D01*
X641391D01*
G01X671091Y1131562D02*
X665888D01*
X664896Y1130570D01*
X663384D01*
X662462Y1131492D01*
Y1132626D01*
X661808Y1133280D01*
X658927D01*
G01X650927Y1133264D02*
X650221D01*
X648519Y1131562D01*
X641391D01*
G01X671091Y1154987D02*
X669108D01*
X668107Y1153986D01*
X665979D01*
X664294Y1153288D01*
X663238Y1152232D01*
X661307D01*
X660182Y1153357D01*
X658927D01*
G01X650927Y1153338D02*
X649698D01*
X648606Y1152246D01*
X647970D01*
X646297Y1153919D01*
X644548D01*
X643480Y1154987D01*
X641391D01*
G01X671091Y1151641D02*
X668854D01*
X667799Y1152696D01*
X666236D01*
X665025Y1152194D01*
X663773Y1150942D01*
X661198D01*
X660195Y1149939D01*
X658927D01*
G01X650927Y1149940D02*
X649701D01*
X648685Y1150956D01*
X647435D01*
X645762Y1152629D01*
X644716D01*
X643728Y1151641D01*
X641391D01*
G01X636941Y1175066D02*
X641391D01*
G01X671091D02*
X665888D01*
X664896Y1174074D01*
X663384D01*
X662462Y1174996D01*
Y1176092D01*
X661770Y1176784D01*
X658927D01*
G01X650927Y1176768D02*
X649893D01*
X648191Y1175066D01*
X641391D01*
G01X671091Y1168373D02*
X665888D01*
X664896Y1167381D01*
X663384D01*
X662462Y1168303D01*
Y1169301D01*
X661672Y1170091D01*
X658927D01*
G01X650927Y1170075D02*
X649365D01*
X647663Y1168373D01*
X641391D01*
G01X671091Y1161680D02*
X665888D01*
X664643Y1160435D01*
X663309D01*
X662462Y1161282D01*
Y1162492D01*
X661556Y1163398D01*
X658927D01*
G01X650927Y1163382D02*
X649221D01*
X647519Y1161680D01*
X641391D01*
G01X636941Y1181759D02*
X641391D01*
G01X671091D02*
X665888D01*
X664896Y1180767D01*
X663384D01*
X662462Y1181689D01*
Y1182680D01*
X661672Y1183470D01*
X658927D01*
G01X650927Y1183454D02*
X649334D01*
X647639Y1181759D01*
X641391D01*
G01X636941Y1191798D02*
X641391D01*
G01X671091D02*
X669108D01*
X668107Y1190797D01*
X665860D01*
X664106Y1189043D01*
X661307D01*
X660202Y1190148D01*
X658930D01*
X658927Y1190145D01*
G01X650927D02*
X650924Y1190148D01*
X649697D01*
X648606Y1189057D01*
X648124D01*
X646451Y1190730D01*
X644548D01*
X643480Y1191798D01*
X641391D01*
G01X671091Y1188452D02*
X668854D01*
X667799Y1189507D01*
X666395D01*
X664641Y1187753D01*
X661198D01*
X660201Y1186756D01*
X658930D01*
X658927Y1186759D01*
G01X650927Y1186756D02*
X649696D01*
X648685Y1187767D01*
X647589D01*
X645916Y1189440D01*
X644716D01*
X643728Y1188452D01*
X641391D01*
G01D02*
X641390Y1188451D01*
X636941D01*
G01Y1205184D02*
X641391D01*
G01X671091D02*
X665888D01*
X664896Y1204192D01*
X663384D01*
X662462Y1205114D01*
Y1206117D01*
X661676Y1206903D01*
X658927D01*
G01X650927Y1206893D02*
X649520D01*
X647811Y1205184D01*
X641391D01*
G01X636941Y1198491D02*
X641391D01*
G01X671091D02*
X665888D01*
X664896Y1197499D01*
X663384D01*
X662462Y1198421D01*
Y1199407D01*
X661660Y1200209D01*
X658927D01*
G01X650927Y1200206D02*
X649718D01*
X648003Y1198491D01*
X641391D01*
G01X671091Y1218570D02*
X665888D01*
X664756Y1217438D01*
X663072D01*
X662462Y1218048D01*
Y1219503D01*
X661676Y1220289D01*
X658927D01*
G01X650927Y1220269D02*
X649862D01*
X648163Y1218570D01*
X641391D01*
G01X671091Y1211877D02*
X665888D01*
X664896Y1210885D01*
X663384D01*
X662462Y1211807D01*
Y1212781D01*
X661672Y1213571D01*
X658927D01*
G01X650927Y1213570D02*
X650925Y1213572D01*
X649760D01*
X648065Y1211877D01*
X641391D01*
G01X671091Y1228609D02*
X669076D01*
X668075Y1227608D01*
X665946D01*
X664481Y1227001D01*
X663886Y1226406D01*
X662554Y1225854D01*
X661939D01*
X660818Y1226975D01*
X658927D01*
G01X650927Y1226966D02*
X649196D01*
X647995Y1225765D01*
X647265D01*
X645489Y1227541D01*
X644328D01*
X643260Y1228609D01*
X641391D01*
G01X671091Y1225263D02*
X669126D01*
X668071Y1226318D01*
X666203D01*
X665212Y1225907D01*
X664617Y1225312D01*
X662811Y1224564D01*
X661838D01*
X660838Y1223564D01*
X658927D01*
G01X650927Y1223569D02*
X648982D01*
X648076Y1224475D01*
X646730D01*
X644954Y1226251D01*
X644420D01*
X643432Y1225263D01*
X641391D01*
G01X671091Y1241995D02*
X665888D01*
X664896Y1241003D01*
X663384D01*
X662462Y1241925D01*
Y1242904D01*
X661651Y1243715D01*
X658927D01*
G01X650927Y1243716D02*
X649760D01*
X647390Y1241346D01*
X645308D01*
X644659Y1241995D01*
X641391D01*
G01X671091Y1235302D02*
X665888D01*
X664610Y1234024D01*
X662962D01*
X662462Y1234524D01*
Y1236256D01*
X661705Y1237013D01*
X658927D01*
G01X650927Y1237014D02*
X648879D01*
X647167Y1235302D01*
X641391D01*
G01X650499Y960892D02*
X654949D01*
G01X650499Y957546D02*
X654949D01*
G01X714349Y780184D02*
X714348Y780185D01*
X708082D01*
X706383Y778486D01*
X704769D01*
G01X696048Y778511D02*
X694691D01*
X694226Y778976D01*
Y780423D01*
X693486Y781163D01*
X691615D01*
X690636Y780184D01*
X684649D01*
G01D02*
X680299D01*
G01X714349Y773491D02*
X714348Y773492D01*
X708082D01*
X706383Y771793D01*
X704769D01*
G01X696048Y771818D02*
X694691D01*
X694226Y772283D01*
Y773730D01*
X693486Y774470D01*
X691615D01*
X690636Y773491D01*
X684649D01*
G01D02*
X680299D01*
G01Y786877D02*
X684649D01*
G01D02*
X686809D01*
X687918Y787986D01*
X690815D01*
X692447Y789618D01*
X694501D01*
X695569Y788550D01*
X696150D01*
G01X704769Y788529D02*
X706045D01*
X706956Y789440D01*
X708157D01*
X709773Y787824D01*
X711082D01*
X712029Y786877D01*
X714349D01*
G01Y803609D02*
X714348Y803610D01*
X708082D01*
X706383Y801911D01*
X704769D01*
G01X696048Y801936D02*
X694691D01*
X694226Y802401D01*
Y803848D01*
X693486Y804588D01*
X691615D01*
X690636Y803609D01*
X684649D01*
G01X714349Y796916D02*
X714348Y796917D01*
X708082D01*
X706383Y795218D01*
X704769D01*
G01X696048Y795243D02*
X694691D01*
X694226Y795708D01*
Y797155D01*
X693486Y797895D01*
X691615D01*
X690636Y796916D01*
X684649D01*
G01D02*
X680299D01*
G01Y790223D02*
X684649D01*
G01D02*
X686969D01*
X687916Y789276D01*
X690280D01*
X691912Y790908D01*
X694612D01*
X695601Y791897D01*
X696150D01*
G01X704769Y791921D02*
X706042D01*
X707233Y790730D01*
X708692D01*
X710308Y789114D01*
X711080D01*
X712189Y790223D01*
X714349D01*
G01Y816995D02*
X714348Y816996D01*
X708082D01*
X706383Y815297D01*
X704769D01*
G01X696048Y815322D02*
X694691D01*
X694226Y815787D01*
Y817234D01*
X693486Y817974D01*
X691615D01*
X690636Y816995D01*
X684649D01*
G01D02*
X680299D01*
G01X714349Y810302D02*
X714348Y810303D01*
X708082D01*
X706383Y808604D01*
X704769D01*
G01X696048Y808629D02*
X694691D01*
X694226Y809094D01*
Y810541D01*
X693486Y811281D01*
X691615D01*
X690636Y810302D01*
X684649D01*
G01D02*
X680299D01*
G01X684649Y803609D02*
X680299D01*
G01X714349Y833727D02*
X714348Y833728D01*
X708082D01*
X706383Y832029D01*
X704769D01*
G01X696048Y832054D02*
X694691D01*
X694226Y832519D01*
Y833966D01*
X693486Y834706D01*
X691615D01*
X690636Y833727D01*
X684649D01*
G01D02*
X680299D01*
G01Y823688D02*
X684649D01*
G01D02*
X686809D01*
X687918Y824797D01*
X690815D01*
X692447Y826429D01*
X694501D01*
X695569Y825361D01*
X696150D01*
G01X704769Y825340D02*
X706045D01*
X706956Y826251D01*
X708157D01*
X709773Y824635D01*
X711082D01*
X712029Y823688D01*
X714349D01*
G01X680299Y827034D02*
X684649D01*
G01D02*
X686969D01*
X687916Y826087D01*
X690280D01*
X691912Y827719D01*
X694612D01*
X695601Y828708D01*
X696150D01*
G01X704769Y828732D02*
X706042D01*
X707233Y827541D01*
X708692D01*
X710308Y825925D01*
X711080D01*
X712189Y827034D01*
X714349D01*
G01Y853806D02*
X714348Y853807D01*
X708082D01*
X706383Y852108D01*
X704769D01*
G01X696048Y852133D02*
X694691D01*
X694226Y852598D01*
Y854045D01*
X693486Y854785D01*
X691615D01*
X690636Y853806D01*
X684649D01*
G01X714349Y847113D02*
X714348Y847114D01*
X708082D01*
X706383Y845415D01*
X704769D01*
G01X696048Y845440D02*
X694691D01*
X694226Y845905D01*
Y847352D01*
X693486Y848092D01*
X691615D01*
X690636Y847113D01*
X684649D01*
G01D02*
X680299D01*
G01X714349Y840420D02*
X714348Y840421D01*
X708082D01*
X706383Y838722D01*
X704769D01*
G01X696048Y838747D02*
X694691D01*
X694226Y839212D01*
Y840659D01*
X693486Y841399D01*
X691615D01*
X690636Y840420D01*
X684649D01*
G01D02*
X680299D01*
G01X684649Y853806D02*
X680299D01*
G01Y860499D02*
X684649D01*
G01D02*
X686809D01*
X687918Y861608D01*
X690815D01*
X692447Y863240D01*
X694501D01*
X695569Y862172D01*
X696150D01*
G01X704769Y862151D02*
X706045D01*
X706956Y863062D01*
X708157D01*
X709773Y861446D01*
X711082D01*
X712029Y860499D01*
X714349D01*
G01X680299Y863845D02*
X684649D01*
G01D02*
X686969D01*
X687916Y862898D01*
X690280D01*
X691912Y864530D01*
X694612D01*
X695601Y865519D01*
X696150D01*
G01X704769Y865543D02*
X706042D01*
X707233Y864352D01*
X708692D01*
X710308Y862736D01*
X711080D01*
X712189Y863845D01*
X714349D01*
G01Y883924D02*
X714348Y883925D01*
X708082D01*
X706383Y882226D01*
X704769D01*
G01X696048Y882251D02*
X694691D01*
X694226Y882716D01*
Y884163D01*
X693486Y884903D01*
X691615D01*
X690636Y883924D01*
X684649D01*
G01D02*
X680299D01*
G01X714349Y877231D02*
X714348Y877232D01*
X708082D01*
X706383Y875533D01*
X704769D01*
G01X696048Y875558D02*
X694691D01*
X694226Y876023D01*
Y877470D01*
X693486Y878210D01*
X691615D01*
X690636Y877231D01*
X684649D01*
G01D02*
X680299D01*
G01X714349Y870538D02*
X714348Y870539D01*
X708082D01*
X706383Y868840D01*
X704769D01*
G01X696048Y868865D02*
X694691D01*
X694226Y869330D01*
Y870777D01*
X693486Y871517D01*
X691615D01*
X690636Y870538D01*
X684649D01*
G01D02*
X680299D01*
G01X714349Y890617D02*
X714348Y890618D01*
X708082D01*
X706383Y888919D01*
X704769D01*
G01X696048Y888944D02*
X694691D01*
X694226Y889409D01*
Y890856D01*
X693486Y891596D01*
X691615D01*
X690636Y890617D01*
X684649D01*
G01D02*
X680299D01*
G01Y897310D02*
X684649D01*
G01D02*
X686809D01*
X687918Y898419D01*
X690815D01*
X692447Y900051D01*
X694501D01*
X695569Y898983D01*
X696150D01*
G01X704769Y898962D02*
X706045D01*
X706956Y899873D01*
X708157D01*
X709773Y898257D01*
X711082D01*
X712029Y897310D01*
X714349D01*
G01X680299Y900656D02*
X684649D01*
G01D02*
X686969D01*
X687916Y899709D01*
X690280D01*
X691912Y901341D01*
X694612D01*
X695601Y902330D01*
X696150D01*
G01X704769Y902354D02*
X706042D01*
X707233Y901163D01*
X708692D01*
X710308Y899547D01*
X711080D01*
X712189Y900656D01*
X714349D01*
G01Y914042D02*
X714348Y914043D01*
X708082D01*
X706383Y912344D01*
X704769D01*
G01X696048Y912369D02*
X694691D01*
X694226Y912834D01*
Y914281D01*
X693486Y915021D01*
X691615D01*
X690636Y914042D01*
X684649D01*
G01D02*
X680299D01*
G01X714349Y907349D02*
X714348Y907350D01*
X708082D01*
X706383Y905651D01*
X704769D01*
G01X696048Y905676D02*
X694691D01*
X694226Y906141D01*
Y907588D01*
X693486Y908328D01*
X691615D01*
X690636Y907349D01*
X684649D01*
G01D02*
X680299D01*
G01X714349Y927428D02*
X714348Y927429D01*
X708082D01*
X706383Y925730D01*
X704769D01*
G01X696048Y925755D02*
X694691D01*
X694226Y926220D01*
Y927667D01*
X693486Y928407D01*
X691615D01*
X690636Y927428D01*
X684649D01*
G01D02*
X680299D01*
G01X714349Y920735D02*
X714348Y920736D01*
X708082D01*
X706383Y919037D01*
X704769D01*
G01X696048Y919062D02*
X694691D01*
X694226Y919527D01*
Y920974D01*
X693486Y921714D01*
X691615D01*
X690636Y920735D01*
X684649D01*
G01D02*
X680299D01*
G01X714349Y950853D02*
X714348Y950854D01*
X708082D01*
X706383Y949155D01*
X704769D01*
G01X696048Y949180D02*
X694691D01*
X694226Y949645D01*
Y951092D01*
X693486Y951832D01*
X691615D01*
X690636Y950853D01*
X684649D01*
G01X714349Y944160D02*
X714348Y944161D01*
X708082D01*
X706383Y942462D01*
X704769D01*
G01X696048Y942487D02*
X694691D01*
X694226Y942952D01*
Y944399D01*
X693486Y945139D01*
X691615D01*
X690636Y944160D01*
X684649D01*
G01D02*
X680299D01*
G01Y934121D02*
X684649D01*
G01D02*
X686809D01*
X687918Y935230D01*
X690815D01*
X692447Y936862D01*
X694501D01*
X695569Y935794D01*
X696150D01*
G01X704769Y935773D02*
X706045D01*
X706956Y936684D01*
X708157D01*
X709773Y935068D01*
X711082D01*
X712029Y934121D01*
X714349D01*
G01X680299Y937467D02*
X684649D01*
G01D02*
X686969D01*
X687916Y936520D01*
X690280D01*
X691912Y938152D01*
X694612D01*
X695601Y939141D01*
X696150D01*
G01X704769Y939165D02*
X706042D01*
X707233Y937974D01*
X708692D01*
X710308Y936358D01*
X711080D01*
X712189Y937467D01*
X714349D01*
G01X680299Y960892D02*
X684649D01*
G01Y950853D02*
X680299D01*
G01X684649Y957546D02*
X680299D01*
G01Y980971D02*
X684649D01*
G01D02*
X688844D01*
X690790Y979025D01*
X692071D01*
X695690Y982644D01*
X696113D01*
G01X704769Y982693D02*
X706407D01*
X708130Y980970D01*
X714348D01*
X714349Y980971D01*
G01X680299Y974278D02*
X684649D01*
G01D02*
X688844D01*
X690790Y972332D01*
X692071D01*
X695690Y975951D01*
X696113D01*
G01X704769Y976000D02*
X706407D01*
X708130Y974277D01*
X714348D01*
X714349Y974278D01*
G01X680299Y967585D02*
X684649D01*
G01X680299Y994357D02*
X684649D01*
G01D02*
X693169D01*
X695604Y996792D01*
X700994D01*
X703170Y998968D01*
X705903D01*
X710514Y994357D01*
X714349D01*
G01X680299Y987664D02*
X684649D01*
G01D02*
X688844D01*
X690790Y985718D01*
X692071D01*
X695690Y989337D01*
X696113D01*
G01X704769Y989386D02*
X706407D01*
X708130Y987663D01*
X714348D01*
X714349Y987664D01*
G01X679999Y1027822D02*
X684649D01*
G01D02*
X688844D01*
X690790Y1025876D01*
X692071D01*
X695690Y1029495D01*
X696113D01*
G01X704769Y1029544D02*
X706407D01*
X708130Y1027821D01*
X714348D01*
X714349Y1027822D01*
G01X680299Y1021129D02*
X684649D01*
G01D02*
X688144D01*
X691657Y1017616D01*
X693139D01*
X694979Y1019456D01*
X696077D01*
G01X704769Y1019505D02*
X706952D01*
X708576Y1021129D01*
X714349D01*
G01X684649Y1047900D02*
X688844D01*
X690790Y1045954D01*
X692071D01*
X695690Y1049573D01*
X696113D01*
G01X704769Y1049622D02*
X706407D01*
X708130Y1047899D01*
X714348D01*
X714349Y1047900D01*
G01X696141Y1044554D02*
X700791D01*
G01X679999Y1041207D02*
X684649D01*
G01D02*
X688272D01*
X690123Y1039356D01*
X691242D01*
X694766Y1042880D01*
X695634D01*
G01X704769Y1042929D02*
X706407D01*
X708130Y1041206D01*
X714348D01*
X714349Y1041207D01*
G01X696141Y1037861D02*
X700791D01*
G01X714349Y1034515D02*
X714348Y1034514D01*
X708130D01*
X706407Y1036237D01*
X704769D01*
G01X695729Y1036188D02*
X694668D01*
X691134Y1032654D01*
X690015D01*
X688154Y1034515D01*
X684649D01*
G01X679999Y1034514D02*
X684648D01*
X684649Y1034515D01*
G01X680299Y1061286D02*
X684649D01*
G01D02*
X686828D01*
X687807Y1062265D01*
X693486D01*
X694226Y1061525D01*
Y1060078D01*
X694748Y1059556D01*
X696577D01*
G01X704769Y1059588D02*
X706011D01*
X708508Y1062085D01*
X711566D01*
X712365Y1061286D01*
X714349D01*
G01X679999Y1047900D02*
X684649D01*
G01Y1054593D02*
X679999D01*
G01X714349Y1074672D02*
X714348Y1074673D01*
X708082D01*
X706383Y1072974D01*
X704769D01*
G01X696048Y1072999D02*
X694691D01*
X694226Y1073464D01*
Y1074911D01*
X693486Y1075651D01*
X691615D01*
X690636Y1074672D01*
X684649D01*
G01D02*
X680299D01*
G01X714349Y1067979D02*
X714348Y1067980D01*
X708082D01*
X706383Y1066281D01*
X704769D01*
G01X696048Y1066306D02*
X694691D01*
X694226Y1066771D01*
Y1068218D01*
X693486Y1068958D01*
X691615D01*
X690636Y1067979D01*
X684649D01*
G01D02*
X680299D01*
G01X714349Y1091404D02*
X714348Y1091405D01*
X708082D01*
X706383Y1089706D01*
X704769D01*
G01X696048Y1089731D02*
X694691D01*
X694226Y1090196D01*
Y1091643D01*
X693486Y1092383D01*
X691615D01*
X690636Y1091404D01*
X684649D01*
G01D02*
X680299D01*
G01Y1081365D02*
X684649D01*
G01D02*
X686809D01*
X687918Y1082474D01*
X690815D01*
X692447Y1084106D01*
X694501D01*
X695569Y1083038D01*
X696150D01*
G01X704769Y1083017D02*
X706045D01*
X706956Y1083928D01*
X708157D01*
X709773Y1082312D01*
X711082D01*
X712029Y1081365D01*
X714349D01*
G01X680299Y1084711D02*
X684649D01*
G01D02*
X686969D01*
X687916Y1083764D01*
X690280D01*
X691912Y1085396D01*
X694612D01*
X695601Y1086385D01*
X696150D01*
G01X704769Y1086409D02*
X706042D01*
X707233Y1085218D01*
X708692D01*
X710308Y1083602D01*
X711080D01*
X712189Y1084711D01*
X714349D01*
G01Y1098097D02*
X714348Y1098098D01*
X708082D01*
X706383Y1096399D01*
X704769D01*
G01X696048Y1096424D02*
X694691D01*
X694226Y1096889D01*
Y1098336D01*
X693486Y1099076D01*
X691615D01*
X690636Y1098097D01*
X684649D01*
G01D02*
X680299D01*
G01X714349Y1111483D02*
X714348Y1111484D01*
X708082D01*
X706383Y1109785D01*
X704769D01*
G01X696048Y1109810D02*
X694691D01*
X694226Y1110275D01*
Y1111722D01*
X693486Y1112462D01*
X691615D01*
X690636Y1111483D01*
X684649D01*
G01D02*
X680299D01*
G01X714349Y1104790D02*
X714348Y1104791D01*
X708082D01*
X706383Y1103092D01*
X704769D01*
G01X696048Y1103117D02*
X694691D01*
X694226Y1103582D01*
Y1105029D01*
X693486Y1105769D01*
X691615D01*
X690636Y1104790D01*
X684649D01*
G01D02*
X680299D01*
G01X714349Y1128215D02*
X714348Y1128216D01*
X708082D01*
X706383Y1126517D01*
X704769D01*
G01X696048Y1126542D02*
X694691D01*
X694226Y1127007D01*
Y1128454D01*
X693486Y1129194D01*
X691615D01*
X690636Y1128215D01*
X684649D01*
G01D02*
X680299D01*
G01Y1118176D02*
X684649D01*
G01D02*
X686809D01*
X687918Y1119285D01*
X690815D01*
X692447Y1120917D01*
X694501D01*
X695569Y1119849D01*
X696150D01*
G01X704769Y1119828D02*
X706045D01*
X706956Y1120739D01*
X708157D01*
X709773Y1119123D01*
X711082D01*
X712029Y1118176D01*
X714349D01*
G01X680299Y1121522D02*
X684649D01*
G01D02*
X686969D01*
X687916Y1120575D01*
X690280D01*
X691912Y1122207D01*
X694612D01*
X695601Y1123196D01*
X696150D01*
G01X704769Y1123220D02*
X706042D01*
X707233Y1122029D01*
X708692D01*
X710308Y1120413D01*
X711080D01*
X712189Y1121522D01*
X714349D01*
G01Y1141601D02*
X714348Y1141602D01*
X708082D01*
X706383Y1139903D01*
X704769D01*
G01X696048Y1139928D02*
X694691D01*
X694226Y1140393D01*
Y1141840D01*
X693486Y1142580D01*
X691615D01*
X690636Y1141601D01*
X684649D01*
G01D02*
X680299D01*
G01X714349Y1134908D02*
X714348Y1134909D01*
X708082D01*
X706383Y1133210D01*
X704769D01*
G01X696048Y1133235D02*
X694691D01*
X694226Y1133700D01*
Y1135147D01*
X693486Y1135887D01*
X691615D01*
X690636Y1134908D01*
X684649D01*
G01D02*
X680299D01*
G01X714349Y1148294D02*
X714348Y1148295D01*
X708082D01*
X706383Y1146596D01*
X704769D01*
G01X696048Y1146621D02*
X694691D01*
X694226Y1147086D01*
Y1148533D01*
X693486Y1149273D01*
X691615D01*
X690636Y1148294D01*
X684649D01*
G01D02*
X680299D01*
G01Y1154987D02*
X684649D01*
G01D02*
X686809D01*
X687918Y1156096D01*
X690815D01*
X692447Y1157728D01*
X694501D01*
X695569Y1156660D01*
X696150D01*
G01X704769Y1156639D02*
X706045D01*
X706956Y1157550D01*
X708157D01*
X709773Y1155934D01*
X711082D01*
X712029Y1154987D01*
X714349D01*
G01X680299Y1158333D02*
X684649D01*
G01D02*
X686969D01*
X687916Y1157386D01*
X690280D01*
X691912Y1159018D01*
X694612D01*
X695601Y1160007D01*
X696150D01*
G01X704769Y1160031D02*
X706042D01*
X707233Y1158840D01*
X708692D01*
X710308Y1157224D01*
X711080D01*
X712189Y1158333D01*
X714349D01*
G01Y1178412D02*
X714348Y1178413D01*
X708082D01*
X706383Y1176714D01*
X704769D01*
G01X696048Y1176739D02*
X694691D01*
X694226Y1177204D01*
Y1178651D01*
X693486Y1179391D01*
X691615D01*
X690636Y1178412D01*
X684649D01*
G01X714349Y1171719D02*
X714348Y1171720D01*
X708082D01*
X706383Y1170021D01*
X704769D01*
G01X696048Y1170046D02*
X694691D01*
X694226Y1170511D01*
Y1171958D01*
X693486Y1172698D01*
X691615D01*
X690636Y1171719D01*
X684649D01*
G01D02*
X680299D01*
G01X714349Y1165026D02*
X714348Y1165027D01*
X708082D01*
X706383Y1163328D01*
X704769D01*
G01X696048Y1163353D02*
X694691D01*
X694226Y1163818D01*
Y1165265D01*
X693486Y1166005D01*
X691615D01*
X690636Y1165026D01*
X684649D01*
G01D02*
X680299D01*
G01X714349Y1185105D02*
X714348Y1185106D01*
X708082D01*
X706383Y1183407D01*
X704769D01*
G01X696048Y1183432D02*
X694691D01*
X694226Y1183897D01*
Y1185344D01*
X693486Y1186084D01*
X691615D01*
X690636Y1185105D01*
X684649D01*
G01D02*
X680299D01*
G01X684649Y1178412D02*
X680299D01*
G01Y1191798D02*
X684649D01*
G01D02*
X686809D01*
X687918Y1192907D01*
X690815D01*
X692447Y1194539D01*
X694501D01*
X695569Y1193471D01*
X696150D01*
G01X704769Y1193450D02*
X706045D01*
X706956Y1194361D01*
X708157D01*
X709773Y1192745D01*
X711082D01*
X712029Y1191798D01*
X714349D01*
G01Y1208530D02*
X714348Y1208531D01*
X708082D01*
X706383Y1206832D01*
X704769D01*
G01X696048Y1206857D02*
X694691D01*
X694226Y1207322D01*
Y1208769D01*
X693486Y1209509D01*
X691615D01*
X690636Y1208530D01*
X684649D01*
G01D02*
X680299D01*
G01X714349Y1201837D02*
X714348Y1201838D01*
X708082D01*
X706383Y1200139D01*
X704769D01*
G01X696048Y1200164D02*
X694691D01*
X694226Y1200629D01*
Y1202076D01*
X693486Y1202816D01*
X691615D01*
X690636Y1201837D01*
X684649D01*
G01D02*
X680299D01*
G01Y1195144D02*
X684649D01*
G01D02*
X686969D01*
X687916Y1194197D01*
X690280D01*
X691912Y1195829D01*
X694612D01*
X695601Y1196818D01*
X696150D01*
G01X704769Y1196842D02*
X706042D01*
X707233Y1195651D01*
X708692D01*
X710308Y1194035D01*
X711080D01*
X712189Y1195144D01*
X714349D01*
G01Y1221916D02*
X714348Y1221917D01*
X708082D01*
X706383Y1220218D01*
X704769D01*
G01X696048Y1220243D02*
X694691D01*
X694226Y1220708D01*
Y1222155D01*
X693486Y1222895D01*
X691615D01*
X690636Y1221916D01*
X684649D01*
G01D02*
X680299D01*
G01X714349Y1215223D02*
X714348Y1215224D01*
X708082D01*
X706383Y1213525D01*
X704769D01*
G01X696048Y1213550D02*
X694691D01*
X694226Y1214015D01*
Y1215462D01*
X693486Y1216202D01*
X691615D01*
X690636Y1215223D01*
X684649D01*
G01D02*
X680299D01*
G01X714349Y1238648D02*
X714348Y1238649D01*
X708082D01*
X706383Y1236950D01*
X704769D01*
G01X696048Y1236975D02*
X694691D01*
X694226Y1237440D01*
Y1238887D01*
X693486Y1239627D01*
X691615D01*
X690636Y1238648D01*
X684649D01*
G01D02*
X680299D01*
G01Y1228609D02*
X684649D01*
G01D02*
X686809D01*
X687918Y1229718D01*
X690815D01*
X692447Y1231350D01*
X694501D01*
X695569Y1230282D01*
X696150D01*
G01X704769Y1230261D02*
X706045D01*
X706956Y1231172D01*
X708157D01*
X709773Y1229556D01*
X711082D01*
X712029Y1228609D01*
X714349D01*
G01X680299Y1231955D02*
X684649D01*
G01D02*
X686969D01*
X687916Y1231008D01*
X690280D01*
X691912Y1232640D01*
X694612D01*
X695601Y1233629D01*
X696150D01*
G01X704769Y1233653D02*
X706042D01*
X707233Y1232462D01*
X708692D01*
X710308Y1230846D01*
X711080D01*
X712189Y1231955D01*
X714349D01*
G01Y1245341D02*
X714348Y1245342D01*
X708082D01*
X706383Y1243643D01*
X704769D01*
G01X696048Y1243668D02*
X694691D01*
X694226Y1244133D01*
Y1245580D01*
X693486Y1246320D01*
X691615D01*
X690636Y1245341D01*
X684649D01*
G01D02*
X680299D01*
G01X700791Y770144D02*
X707477D01*
X709178Y771845D01*
X710327D01*
G01X718327Y771865D02*
X721009D01*
X721812Y771062D01*
Y770074D01*
X722734Y769152D01*
X724246D01*
X725238Y770144D01*
X730491D01*
G01X696441D02*
X700791D01*
G01X696441Y776837D02*
X700791D01*
G01D02*
X707477D01*
X709178Y778538D01*
X710327D01*
G01X718327Y778558D02*
X721009D01*
X721812Y777755D01*
Y776767D01*
X722734Y775845D01*
X724246D01*
X725238Y776837D01*
X730491D01*
G01X696441Y786877D02*
X700791D01*
G01D02*
X702880D01*
X703948Y785809D01*
X705851D01*
X707524Y784136D01*
X708006D01*
X709098Y785228D01*
X710327D01*
G01X718327Y785247D02*
X719582D01*
X720707Y784122D01*
X722636D01*
X724390Y785876D01*
X727507D01*
X728508Y786877D01*
X730491D01*
G01X696441Y783530D02*
X700791D01*
G01D02*
X703127D01*
X704116Y784519D01*
X705316D01*
X706989Y782846D01*
X708085D01*
X709102Y781829D01*
X710327D01*
G01X718327Y781828D02*
X719594D01*
X720598Y782832D01*
X723171D01*
X724925Y784586D01*
X727199D01*
X728255Y783530D01*
X730491D01*
G01X696441Y800263D02*
X700791D01*
G01D02*
X707477D01*
X709178Y801964D01*
X710327D01*
G01X718327Y801984D02*
X721009D01*
X721812Y801181D01*
Y800193D01*
X722734Y799271D01*
X724246D01*
X725238Y800263D01*
X730491D01*
G01X696441Y793570D02*
X700791D01*
G01D02*
X707477D01*
X709178Y795271D01*
X710327D01*
G01X718327Y795291D02*
X721009D01*
X721812Y794488D01*
Y793500D01*
X722734Y792578D01*
X724246D01*
X725238Y793570D01*
X730491D01*
G01X696441Y813648D02*
X700791D01*
G01D02*
X707477D01*
X709178Y815349D01*
X710327D01*
G01X718327Y815369D02*
X721009D01*
X721812Y814566D01*
Y813578D01*
X722734Y812656D01*
X724246D01*
X725238Y813648D01*
X730491D01*
G01X696441Y806955D02*
X700791D01*
G01D02*
X707477D01*
X709178Y808656D01*
X710327D01*
G01X718327Y808676D02*
X721009D01*
X721812Y807873D01*
Y806885D01*
X722734Y805963D01*
X724246D01*
X725238Y806955D01*
X730491D01*
G01X700791Y820341D02*
X703127D01*
X704116Y821330D01*
X705316D01*
X706989Y819657D01*
X708085D01*
X709102Y818640D01*
X710327D01*
G01X718327Y818639D02*
X719594D01*
X720598Y819643D01*
X723171D01*
X724925Y821397D01*
X727199D01*
X728255Y820341D01*
X730491D01*
G01X696441Y830381D02*
X700791D01*
G01D02*
X707477D01*
X709178Y832082D01*
X710327D01*
G01X718327Y832102D02*
X721009D01*
X721812Y831299D01*
Y830311D01*
X722734Y829389D01*
X724246D01*
X725238Y830381D01*
X730491D01*
G01X696441Y823688D02*
X700791D01*
G01D02*
X702880D01*
X703948Y822620D01*
X705851D01*
X707524Y820947D01*
X708006D01*
X709098Y822039D01*
X710327D01*
G01X718327Y822058D02*
X719582D01*
X720707Y820933D01*
X722636D01*
X724390Y822687D01*
X727507D01*
X728508Y823688D01*
X730491D01*
G01X696441Y820341D02*
X700791D01*
G01X696441Y850459D02*
X700791D01*
G01D02*
X707477D01*
X709178Y852160D01*
X710327D01*
G01X718327Y852180D02*
X721009D01*
X721812Y851377D01*
Y850389D01*
X722734Y849467D01*
X724246D01*
X725238Y850459D01*
X730491D01*
G01X696441Y843766D02*
X700791D01*
G01D02*
X707477D01*
X709178Y845467D01*
X710327D01*
G01X718327Y845487D02*
X721009D01*
X721812Y844684D01*
Y843696D01*
X722734Y842774D01*
X724246D01*
X725238Y843766D01*
X730491D01*
G01X696441Y837074D02*
X700791D01*
G01D02*
X707477D01*
X709178Y838775D01*
X710327D01*
G01X718327Y838795D02*
X721009D01*
X721812Y837992D01*
Y837004D01*
X722734Y836082D01*
X724246D01*
X725238Y837074D01*
X730491D01*
G01X696441Y867192D02*
X700791D01*
G01D02*
X707477D01*
X709178Y868893D01*
X710327D01*
G01X718327Y868913D02*
X721009D01*
X721812Y868110D01*
Y867122D01*
X722734Y866200D01*
X724246D01*
X725238Y867192D01*
X730491D01*
G01X696441Y860499D02*
X700791D01*
G01D02*
X702880D01*
X703948Y859431D01*
X705851D01*
X707524Y857758D01*
X708006D01*
X709098Y858850D01*
X710327D01*
G01X718327Y858869D02*
X719582D01*
X720707Y857744D01*
X722636D01*
X724390Y859498D01*
X727507D01*
X728508Y860499D01*
X730491D01*
G01X696441Y857152D02*
X700791D01*
G01D02*
X703127D01*
X704116Y858141D01*
X705316D01*
X706989Y856468D01*
X708085D01*
X709102Y855451D01*
X710327D01*
G01X718327Y855450D02*
X719594D01*
X720598Y856454D01*
X723171D01*
X724925Y858208D01*
X727199D01*
X728255Y857152D01*
X730491D01*
G01X696441Y873885D02*
X700791D01*
G01D02*
X707477D01*
X709178Y875586D01*
X710327D01*
G01X718327Y875606D02*
X721009D01*
X721812Y874803D01*
Y873815D01*
X722734Y872893D01*
X724246D01*
X725238Y873885D01*
X730491D01*
G01X696441Y880577D02*
X700791D01*
G01D02*
X707477D01*
X709178Y882278D01*
X710327D01*
G01X718327Y882298D02*
X721009D01*
X721812Y881495D01*
Y880507D01*
X722734Y879585D01*
X724246D01*
X725238Y880577D01*
X730491D01*
G01X696441Y887270D02*
X700791D01*
G01D02*
X707477D01*
X709178Y888971D01*
X710327D01*
G01X718327Y888991D02*
X721009D01*
X721812Y888188D01*
Y887200D01*
X722734Y886278D01*
X724246D01*
X725238Y887270D01*
X730491D01*
G01X696441Y897310D02*
X700791D01*
G01D02*
X702880D01*
X703948Y896242D01*
X705851D01*
X707524Y894569D01*
X708006D01*
X709098Y895661D01*
X710327D01*
G01X718327Y895680D02*
X719582D01*
X720707Y894555D01*
X722636D01*
X724390Y896309D01*
X727507D01*
X728508Y897310D01*
X730491D01*
G01X696441Y893963D02*
X700791D01*
G01D02*
X703127D01*
X704116Y894952D01*
X705316D01*
X706989Y893279D01*
X708085D01*
X709102Y892262D01*
X710327D01*
G01X718327Y892261D02*
X719594D01*
X720598Y893265D01*
X723171D01*
X724925Y895019D01*
X727199D01*
X728255Y893963D01*
X730491D01*
G01X696441Y910696D02*
X700791D01*
G01D02*
X707477D01*
X709178Y912397D01*
X710327D01*
G01X718327Y912417D02*
X721009D01*
X721812Y911614D01*
Y910626D01*
X722734Y909704D01*
X724246D01*
X725238Y910696D01*
X730491D01*
G01X696441Y904003D02*
X700791D01*
G01D02*
X707477D01*
X709178Y905704D01*
X710327D01*
G01X718327Y905724D02*
X721009D01*
X721812Y904921D01*
Y903933D01*
X722734Y903011D01*
X724246D01*
X725238Y904003D01*
X730491D01*
G01X696441Y924081D02*
X700791D01*
G01D02*
X707477D01*
X709178Y925782D01*
X710327D01*
G01X718327Y925802D02*
X721009D01*
X721812Y924999D01*
Y924011D01*
X722734Y923089D01*
X724246D01*
X725238Y924081D01*
X730491D01*
G01X696441Y917389D02*
X700791D01*
G01D02*
X707477D01*
X709178Y919090D01*
X710327D01*
G01X718327Y919110D02*
X721009D01*
X721812Y918307D01*
Y917319D01*
X722734Y916397D01*
X724246D01*
X725238Y917389D01*
X730491D01*
G01X700791Y934121D02*
X702880D01*
X703948Y933053D01*
X705851D01*
X707524Y931380D01*
X708006D01*
X709098Y932472D01*
X710327D01*
G01X718327Y932491D02*
X719582D01*
X720707Y931366D01*
X722636D01*
X724390Y933120D01*
X727507D01*
X728508Y934121D01*
X730491D01*
G01X696441Y930774D02*
X700791D01*
G01D02*
X703127D01*
X704116Y931763D01*
X705316D01*
X706989Y930090D01*
X708085D01*
X709102Y929073D01*
X710327D01*
G01X718327Y929072D02*
X719594D01*
X720598Y930076D01*
X723171D01*
X724925Y931830D01*
X727199D01*
X728255Y930774D01*
X730491D01*
G01X696441Y947507D02*
X700791D01*
G01D02*
X707477D01*
X709178Y949208D01*
X710327D01*
G01X718327Y949228D02*
X721009D01*
X721812Y948425D01*
Y947437D01*
X722734Y946515D01*
X724246D01*
X725238Y947507D01*
X730491D01*
G01X696441Y940814D02*
X700791D01*
G01D02*
X707477D01*
X709178Y942515D01*
X710327D01*
G01X718327Y942535D02*
X721009D01*
X721812Y941732D01*
Y940744D01*
X722734Y939822D01*
X724246D01*
X725238Y940814D01*
X730491D01*
G01X696441Y934121D02*
X700791D01*
G01X714349Y960892D02*
X709899D01*
G01X700791Y964239D02*
X696441D01*
G01X714349Y957546D02*
X709899D01*
G01X696441Y977625D02*
X700791D01*
G01D02*
X707231D01*
X708946Y979340D01*
X710327D01*
G01X718327Y979327D02*
X719406D01*
X722811Y975922D01*
X724400D01*
X726103Y977625D01*
X730491D01*
G01X709999Y967585D02*
X714349D01*
G01X696441Y970932D02*
X700791D01*
G01D02*
X707231D01*
X708946Y972647D01*
X710327D01*
G01X718327Y972634D02*
X719406D01*
X722811Y969229D01*
X724400D01*
X726103Y970932D01*
X730491D01*
G01X696441Y991011D02*
X700791D01*
G01D02*
X707231D01*
X708946Y992726D01*
X710327D01*
G01X718327Y992713D02*
X719406D01*
X722811Y989308D01*
X724400D01*
X726103Y991011D01*
X730491D01*
G01X696441Y984318D02*
X700791D01*
G01D02*
X707231D01*
X708946Y986033D01*
X710327D01*
G01X718327Y986020D02*
X719406D01*
X722811Y982615D01*
X724400D01*
X726103Y984318D01*
X730491D01*
G01X696441Y1021129D02*
X700791D01*
G01X696441Y1024475D02*
X700791D01*
G01Y1031168D02*
X707231D01*
X708946Y1032883D01*
X710327D01*
G01X718327Y1032870D02*
X719406D01*
X722811Y1029465D01*
X724400D01*
X726103Y1031168D01*
X730491D01*
G01X700791Y1044554D02*
X707231D01*
X708946Y1046269D01*
X710327D01*
G01X718327Y1046256D02*
X719406D01*
X722811Y1042851D01*
X724400D01*
X726103Y1044554D01*
X730491D01*
G01X700791Y1037861D02*
X707231D01*
X708946Y1039576D01*
X710327D01*
G01X718327Y1039563D02*
X719406D01*
X722811Y1036158D01*
X724400D01*
X726103Y1037861D01*
X730491D01*
G01X696441Y1031168D02*
X700791D01*
G01X709999Y1054593D02*
X714349D01*
G01X696441Y1051247D02*
X700791D01*
G01X696441Y1071325D02*
X700790D01*
X700791Y1071326D01*
G01D02*
X707477D01*
X709178Y1073027D01*
X710327D01*
G01X718327Y1073047D02*
X721009D01*
X721812Y1072244D01*
Y1071256D01*
X722734Y1070334D01*
X724246D01*
X725238Y1071326D01*
X730491D01*
G01X696441Y1064633D02*
X700791D01*
G01D02*
X707477D01*
X709178Y1066334D01*
X710327D01*
G01X718327Y1066354D02*
X721009D01*
X721812Y1065551D01*
Y1064563D01*
X722734Y1063641D01*
X724246D01*
X725238Y1064633D01*
X730491D01*
G01X700791Y1081365D02*
X702880D01*
X703948Y1080297D01*
X705851D01*
X707524Y1078624D01*
X708006D01*
X709098Y1079716D01*
X710327D01*
G01X718327Y1079735D02*
X719582D01*
X720707Y1078610D01*
X722636D01*
X724390Y1080364D01*
X727507D01*
X728508Y1081365D01*
X730491D01*
G01X696441Y1078018D02*
X700791D01*
G01D02*
X703127D01*
X704116Y1079007D01*
X705316D01*
X706989Y1077334D01*
X708085D01*
X709102Y1076317D01*
X710327D01*
G01X718327Y1076316D02*
X719594D01*
X720598Y1077320D01*
X723171D01*
X724925Y1079074D01*
X727199D01*
X728255Y1078018D01*
X730491D01*
G01X696441Y1094751D02*
X700791D01*
G01D02*
X707477D01*
X709178Y1096452D01*
X710327D01*
G01X718327Y1096472D02*
X721009D01*
X721812Y1095669D01*
Y1094681D01*
X722734Y1093759D01*
X724246D01*
X725238Y1094751D01*
X730491D01*
G01X696441Y1088058D02*
X700791D01*
G01D02*
X707477D01*
X709178Y1089759D01*
X710327D01*
G01X718327Y1089779D02*
X721009D01*
X721812Y1088976D01*
Y1087988D01*
X722734Y1087066D01*
X724246D01*
X725238Y1088058D01*
X730491D01*
G01X696441Y1081365D02*
X700791D01*
G01X696441Y1108136D02*
X696442Y1108137D01*
X700791D01*
G01D02*
X707477D01*
X709178Y1109838D01*
X710327D01*
G01X718327Y1109858D02*
X721009D01*
X721812Y1109055D01*
Y1108067D01*
X722734Y1107145D01*
X724246D01*
X725238Y1108137D01*
X730491D01*
G01X696441Y1101444D02*
X700791D01*
G01D02*
X707477D01*
X709178Y1103145D01*
X710327D01*
G01X718327Y1103165D02*
X721009D01*
X721812Y1102362D01*
Y1101374D01*
X722734Y1100452D01*
X724246D01*
X725238Y1101444D01*
X730491D01*
G01X696441Y1124869D02*
X700791D01*
G01D02*
X707477D01*
X709178Y1126570D01*
X710327D01*
G01X718327Y1126590D02*
X721009D01*
X721812Y1125787D01*
Y1124799D01*
X722734Y1123877D01*
X724246D01*
X725238Y1124869D01*
X730491D01*
G01X696441Y1118176D02*
X700791D01*
G01D02*
X702880D01*
X703948Y1117108D01*
X705851D01*
X707524Y1115435D01*
X708006D01*
X709098Y1116527D01*
X710327D01*
G01X718327Y1116546D02*
X719582D01*
X720707Y1115421D01*
X722636D01*
X724390Y1117175D01*
X727507D01*
X728508Y1118176D01*
X730491D01*
G01X696441Y1114829D02*
X700791D01*
G01D02*
X703127D01*
X704116Y1115818D01*
X705316D01*
X706989Y1114145D01*
X708085D01*
X709102Y1113128D01*
X710327D01*
G01X718327Y1113127D02*
X719594D01*
X720598Y1114131D01*
X723171D01*
X724925Y1115885D01*
X727199D01*
X728255Y1114829D01*
X730491D01*
G01X696441Y1144947D02*
X696442Y1144948D01*
X700791D01*
G01D02*
X707477D01*
X709178Y1146649D01*
X710327D01*
G01X718327Y1146669D02*
X721009D01*
X721812Y1145866D01*
Y1144878D01*
X722734Y1143956D01*
X724246D01*
X725238Y1144948D01*
X730491D01*
G01X696441Y1138255D02*
X700791D01*
G01D02*
X707477D01*
X709178Y1139956D01*
X710327D01*
G01X718327Y1139976D02*
X721009D01*
X721812Y1139173D01*
Y1138185D01*
X722734Y1137263D01*
X724246D01*
X725238Y1138255D01*
X730491D01*
G01X696441Y1131562D02*
X700791D01*
G01D02*
X707477D01*
X709178Y1133263D01*
X710327D01*
G01X718327Y1133283D02*
X721009D01*
X721812Y1132480D01*
Y1131492D01*
X722734Y1130570D01*
X724246D01*
X725238Y1131562D01*
X730491D01*
G01X696441Y1154987D02*
X700791D01*
G01D02*
X702880D01*
X703948Y1153919D01*
X705851D01*
X707524Y1152246D01*
X708006D01*
X709098Y1153338D01*
X710327D01*
G01X718327Y1153357D02*
X719582D01*
X720707Y1152232D01*
X722636D01*
X724390Y1153986D01*
X727507D01*
X728508Y1154987D01*
X730491D01*
G01X696441Y1151640D02*
X700790D01*
X700791Y1151641D01*
G01D02*
X703128D01*
X704116Y1152629D01*
X705316D01*
X706989Y1150956D01*
X708085D01*
X709101Y1149940D01*
X710327D01*
G01X718327Y1149939D02*
X719595D01*
X720598Y1150942D01*
X723171D01*
X724925Y1152696D01*
X727199D01*
X728254Y1151641D01*
X730491D01*
G01X696441Y1175066D02*
X700791D01*
G01D02*
X707477D01*
X709178Y1176767D01*
X710327D01*
G01X718327Y1176787D02*
X721009D01*
X721812Y1175984D01*
Y1174996D01*
X722734Y1174074D01*
X724246D01*
X725238Y1175066D01*
X730491D01*
G01X696441Y1168373D02*
X700791D01*
G01D02*
X707477D01*
X709178Y1170074D01*
X710327D01*
G01X718327Y1170094D02*
X721009D01*
X721812Y1169291D01*
Y1168303D01*
X722734Y1167381D01*
X724246D01*
X725238Y1168373D01*
X730491D01*
G01X696441Y1161680D02*
X700791D01*
G01D02*
X707477D01*
X709178Y1163381D01*
X710327D01*
G01X718327Y1163401D02*
X721009D01*
X721812Y1162598D01*
Y1161610D01*
X722734Y1160688D01*
X724246D01*
X725238Y1161680D01*
X730491D01*
G01X696441Y1181758D02*
X700790D01*
X700791Y1181759D01*
G01D02*
X707477D01*
X709178Y1183460D01*
X710327D01*
G01X718327Y1183480D02*
X721009D01*
X721812Y1182677D01*
Y1181689D01*
X722734Y1180767D01*
X724246D01*
X725238Y1181759D01*
X730491D01*
G01X696441Y1191798D02*
X700791D01*
G01D02*
X702880D01*
X703948Y1190730D01*
X705851D01*
X707524Y1189057D01*
X708006D01*
X709098Y1190149D01*
X710327D01*
G01X718327Y1190168D02*
X719582D01*
X720707Y1189043D01*
X722636D01*
X724390Y1190797D01*
X727507D01*
X728508Y1191798D01*
X730491D01*
G01X696441Y1188451D02*
X700790D01*
X700791Y1188452D01*
G01D02*
X703128D01*
X704116Y1189440D01*
X705316D01*
X706989Y1187767D01*
X708085D01*
X709101Y1186751D01*
X710327D01*
G01X718327Y1186750D02*
X719595D01*
X720598Y1187753D01*
X723171D01*
X724925Y1189507D01*
X727199D01*
X728254Y1188452D01*
X730491D01*
G01X696441Y1205184D02*
X700791D01*
G01D02*
X707477D01*
X709178Y1206885D01*
X710327D01*
G01X718327Y1206905D02*
X721009D01*
X721812Y1206102D01*
Y1205114D01*
X722734Y1204192D01*
X724246D01*
X725238Y1205184D01*
X730491D01*
G01X696441Y1198491D02*
X700791D01*
G01D02*
X707477D01*
X709178Y1200192D01*
X710327D01*
G01X718327Y1200212D02*
X721009D01*
X721812Y1199409D01*
Y1198421D01*
X722734Y1197499D01*
X724246D01*
X725238Y1198491D01*
X730491D01*
G01X696441Y1218569D02*
X700790D01*
X700791Y1218570D01*
G01D02*
X707477D01*
X709178Y1220271D01*
X710327D01*
G01X718327Y1220291D02*
X721009D01*
X721812Y1219488D01*
Y1218500D01*
X722734Y1217578D01*
X724246D01*
X725238Y1218570D01*
X730491D01*
G01X696441Y1211877D02*
X700791D01*
G01D02*
X707477D01*
X709178Y1213578D01*
X710327D01*
G01X718327Y1213598D02*
X721009D01*
X721812Y1212795D01*
Y1211807D01*
X722734Y1210885D01*
X724246D01*
X725238Y1211877D01*
X730491D01*
G01X700791Y1228609D02*
X702880D01*
X703948Y1227541D01*
X705851D01*
X707524Y1225868D01*
X708006D01*
X709098Y1226960D01*
X710327D01*
G01X718327Y1226979D02*
X719582D01*
X720707Y1225854D01*
X722636D01*
X724390Y1227608D01*
X727507D01*
X728508Y1228609D01*
X730491D01*
G01X696441Y1225262D02*
X696442Y1225263D01*
X700791D01*
G01D02*
X703128D01*
X704116Y1226251D01*
X705316D01*
X706989Y1224578D01*
X708085D01*
X709101Y1223562D01*
X710327D01*
G01X718327Y1223561D02*
X719595D01*
X720598Y1224564D01*
X723171D01*
X724925Y1226318D01*
X727199D01*
X728254Y1225263D01*
X730491D01*
G01X696441Y1241995D02*
X700791D01*
G01D02*
X707477D01*
X709178Y1243696D01*
X710327D01*
G01X718327Y1243716D02*
X721009D01*
X721812Y1242913D01*
Y1241925D01*
X722734Y1241003D01*
X724246D01*
X725238Y1241995D01*
X730491D01*
G01X696441Y1235302D02*
X700791D01*
G01D02*
X707477D01*
X709178Y1237003D01*
X710327D01*
G01X718327Y1237023D02*
X721009D01*
X721812Y1236220D01*
Y1235232D01*
X722734Y1234310D01*
X724246D01*
X725238Y1235302D01*
X730491D01*
G01X696441Y1228609D02*
X700791D01*
G01X726141Y964239D02*
X730491D01*
G01X726141Y1021129D02*
X730491D01*
G01X726141Y1024475D02*
X730491D01*
G01X726141Y1051247D02*
X730491D01*
G01X773749Y780184D02*
X773748Y780185D01*
X767482D01*
X765783Y778486D01*
X764169D01*
G01X755448Y778511D02*
X754091D01*
X753626Y778976D01*
Y780423D01*
X752886Y781163D01*
X751015D01*
X750036Y780184D01*
X744049D01*
G01D02*
X739699D01*
G01X773749Y773491D02*
X773748Y773492D01*
X767482D01*
X765783Y771793D01*
X764169D01*
G01X755448Y771818D02*
X754091D01*
X753626Y772283D01*
Y773730D01*
X752886Y774470D01*
X751015D01*
X750036Y773491D01*
X744049D01*
G01D02*
X739699D01*
G01Y786877D02*
X744049D01*
G01D02*
X746209D01*
X747318Y787986D01*
X750215D01*
X751847Y789618D01*
X753901D01*
X754969Y788550D01*
X755550D01*
G01X764169Y788529D02*
X765445D01*
X766356Y789440D01*
X767557D01*
X769173Y787824D01*
X770482D01*
X771429Y786877D01*
X773749D01*
G01Y796916D02*
X773748Y796917D01*
X767482D01*
X765783Y795218D01*
X764169D01*
G01X755448Y795243D02*
X754091D01*
X753626Y795708D01*
Y797155D01*
X752886Y797895D01*
X751015D01*
X750036Y796916D01*
X744049D01*
G01D02*
X739699D01*
G01Y790223D02*
X744049D01*
G01D02*
X746369D01*
X747316Y789276D01*
X749680D01*
X751312Y790908D01*
X754012D01*
X755001Y791897D01*
X755550D01*
G01X764169Y791921D02*
X765442D01*
X766633Y790730D01*
X768092D01*
X769708Y789114D01*
X770480D01*
X771589Y790223D01*
X773749D01*
G01Y816995D02*
X773748Y816996D01*
X767482D01*
X765783Y815297D01*
X764169D01*
G01X755448Y815322D02*
X754091D01*
X753626Y815787D01*
Y817234D01*
X752886Y817974D01*
X751015D01*
X750036Y816995D01*
X744049D01*
G01D02*
X739699D01*
G01X773749Y810302D02*
X773748Y810303D01*
X767482D01*
X765783Y808604D01*
X764169D01*
G01X755448Y808629D02*
X754091D01*
X753626Y809094D01*
Y810541D01*
X752886Y811281D01*
X751015D01*
X750036Y810302D01*
X744049D01*
G01D02*
X739699D01*
G01X773749Y803609D02*
X773748Y803610D01*
X767482D01*
X765783Y801911D01*
X764169D01*
G01X755448Y801936D02*
X754091D01*
X753626Y802401D01*
Y803848D01*
X752886Y804588D01*
X751015D01*
X750036Y803609D01*
X744049D01*
G01D02*
X739699D01*
G01X773749Y833727D02*
X773748Y833728D01*
X767482D01*
X765783Y832029D01*
X764169D01*
G01X755448Y832054D02*
X754091D01*
X753626Y832519D01*
Y833966D01*
X752886Y834706D01*
X751015D01*
X750036Y833727D01*
X744049D01*
G01D02*
X739699D01*
G01Y823688D02*
X744049D01*
G01D02*
X746209D01*
X747318Y824797D01*
X750215D01*
X751847Y826429D01*
X753901D01*
X754969Y825361D01*
X755550D01*
G01X764169Y825340D02*
X765445D01*
X766356Y826251D01*
X767557D01*
X769173Y824635D01*
X770482D01*
X771429Y823688D01*
X773749D01*
G01X739699Y827034D02*
X744049D01*
G01D02*
X746369D01*
X747316Y826087D01*
X749680D01*
X751312Y827719D01*
X754012D01*
X755001Y828708D01*
X755550D01*
G01X764169Y828732D02*
X765442D01*
X766633Y827541D01*
X768092D01*
X769708Y825925D01*
X770480D01*
X771589Y827034D01*
X773749D01*
G01Y847113D02*
X773748Y847114D01*
X767482D01*
X765783Y845415D01*
X764169D01*
G01X755448Y845440D02*
X754091D01*
X753626Y845905D01*
Y847352D01*
X752886Y848092D01*
X751015D01*
X750036Y847113D01*
X744049D01*
G01D02*
X739699D01*
G01X773749Y840420D02*
X773748Y840421D01*
X767482D01*
X765783Y838722D01*
X764169D01*
G01X755448Y838747D02*
X754091D01*
X753626Y839212D01*
Y840659D01*
X752886Y841399D01*
X751015D01*
X750036Y840420D01*
X744049D01*
G01D02*
X739699D01*
G01X773749Y853806D02*
X773748Y853807D01*
X767482D01*
X765783Y852108D01*
X764169D01*
G01X755448Y852133D02*
X754091D01*
X753626Y852598D01*
Y854045D01*
X752886Y854785D01*
X751015D01*
X750036Y853806D01*
X744049D01*
G01D02*
X739699D01*
G01Y860499D02*
X744049D01*
G01D02*
X746209D01*
X747318Y861608D01*
X750215D01*
X751847Y863240D01*
X753901D01*
X754969Y862172D01*
X755550D01*
G01X764169Y862151D02*
X765445D01*
X766356Y863062D01*
X767557D01*
X769173Y861446D01*
X770482D01*
X771429Y860499D01*
X773749D01*
G01X739699Y863845D02*
X744049D01*
G01D02*
X746369D01*
X747316Y862898D01*
X749680D01*
X751312Y864530D01*
X754012D01*
X755001Y865519D01*
X755550D01*
G01X764169Y865543D02*
X765442D01*
X766633Y864352D01*
X768092D01*
X769708Y862736D01*
X770480D01*
X771589Y863845D01*
X773749D01*
G01Y883924D02*
X773748Y883925D01*
X767482D01*
X765783Y882226D01*
X764169D01*
G01X755448Y882251D02*
X754091D01*
X753626Y882716D01*
Y884163D01*
X752886Y884903D01*
X751015D01*
X750036Y883924D01*
X744049D01*
G01D02*
X739699D01*
G01X773749Y877231D02*
X773748Y877232D01*
X767482D01*
X765783Y875533D01*
X764169D01*
G01X755448Y875558D02*
X754091D01*
X753626Y876023D01*
Y877470D01*
X752886Y878210D01*
X751015D01*
X750036Y877231D01*
X744049D01*
G01D02*
X739699D01*
G01X773749Y870538D02*
X773748Y870539D01*
X767482D01*
X765783Y868840D01*
X764169D01*
G01X755448Y868865D02*
X754091D01*
X753626Y869330D01*
Y870777D01*
X752886Y871517D01*
X751015D01*
X750036Y870538D01*
X744049D01*
G01D02*
X739699D01*
G01X773749Y890617D02*
X773748Y890618D01*
X767482D01*
X765783Y888919D01*
X764169D01*
G01X755448Y888944D02*
X754091D01*
X753626Y889409D01*
Y890856D01*
X752886Y891596D01*
X751015D01*
X750036Y890617D01*
X744049D01*
G01D02*
X739699D01*
G01Y897310D02*
X744049D01*
G01D02*
X746209D01*
X747318Y898419D01*
X750215D01*
X751847Y900051D01*
X753901D01*
X754969Y898983D01*
X755550D01*
G01X764169Y898962D02*
X765445D01*
X766356Y899873D01*
X767557D01*
X769173Y898257D01*
X770482D01*
X771429Y897310D01*
X773749D01*
G01X739699Y900656D02*
X744049D01*
G01D02*
X746369D01*
X747316Y899709D01*
X749680D01*
X751312Y901341D01*
X754012D01*
X755001Y902330D01*
X755550D01*
G01X764169Y902354D02*
X765442D01*
X766633Y901163D01*
X768092D01*
X769708Y899547D01*
X770480D01*
X771589Y900656D01*
X773749D01*
G01Y914042D02*
X773748Y914043D01*
X767482D01*
X765783Y912344D01*
X764169D01*
G01X755448Y912369D02*
X754091D01*
X753626Y912834D01*
Y914281D01*
X752886Y915021D01*
X751015D01*
X750036Y914042D01*
X744049D01*
G01D02*
X739699D01*
G01X773749Y907349D02*
X773748Y907350D01*
X767482D01*
X765783Y905651D01*
X764169D01*
G01X755448Y905676D02*
X754091D01*
X753626Y906141D01*
Y907588D01*
X752886Y908328D01*
X751015D01*
X750036Y907349D01*
X744049D01*
G01D02*
X739699D01*
G01X773749Y927428D02*
X773748Y927429D01*
X767328D01*
X765654Y925755D01*
X764873D01*
G01X755064D02*
X754091D01*
X753626Y926220D01*
Y927667D01*
X752886Y928407D01*
X751015D01*
X750036Y927428D01*
X744049D01*
G01D02*
X739699D01*
G01X773749Y920735D02*
X773748Y920736D01*
X767328D01*
X765654Y919062D01*
X764873D01*
G01X755064D02*
X754091D01*
X753626Y919527D01*
Y920974D01*
X752886Y921714D01*
X751015D01*
X750036Y920735D01*
X744049D01*
G01D02*
X739699D01*
G01X773749Y944160D02*
X773748Y944161D01*
X767328D01*
X765654Y942487D01*
X764873D01*
G01X755064D02*
X754091D01*
X753626Y942952D01*
Y944399D01*
X752886Y945139D01*
X751015D01*
X750036Y944160D01*
X744049D01*
G01D02*
X739699D01*
G01Y934121D02*
X744049D01*
G01D02*
X746209D01*
X747318Y935230D01*
X750097D01*
X751729Y936862D01*
X753901D01*
X754969Y935794D01*
X755296D01*
G01X764873D02*
X765466D01*
X766356Y936684D01*
X767557D01*
X769173Y935068D01*
X770482D01*
X771429Y934121D01*
X773749D01*
G01X739699Y937467D02*
X744049D01*
G01D02*
X746369D01*
X747316Y936520D01*
X749562D01*
X751194Y938152D01*
X754012D01*
X755001Y939141D01*
X755509D01*
G01X764988D02*
X765466D01*
X766633Y937974D01*
X768092D01*
X769708Y936358D01*
X770480D01*
X771589Y937467D01*
X773749D01*
G01X739699Y960892D02*
X744049D01*
G01X773749Y950853D02*
X773748Y950854D01*
X767328D01*
X765654Y949180D01*
X764873D01*
G01X755064D02*
X754091D01*
X753626Y949645D01*
Y951092D01*
X752886Y951832D01*
X751015D01*
X750036Y950853D01*
X744049D01*
G01D02*
X739699D01*
G01X744049Y957546D02*
X739699D01*
G01Y980971D02*
X744049D01*
G01D02*
X748244D01*
X750190Y979025D01*
X751471D01*
X755090Y982644D01*
X755513D01*
G01X764169Y982693D02*
X765807D01*
X767530Y980970D01*
X773748D01*
X773749Y980971D01*
G01X739699Y974278D02*
X744049D01*
G01D02*
X748244D01*
X750190Y972332D01*
X751471D01*
X755090Y975951D01*
X755513D01*
G01X764169Y976000D02*
X765807D01*
X767530Y974277D01*
X773748D01*
X773749Y974278D01*
G01X739699Y967585D02*
X744049D01*
G01X739699Y994357D02*
X744049D01*
G01D02*
X748861D01*
X750060Y993158D01*
X752210D01*
X755822Y996770D01*
X767001D01*
X769414Y994357D01*
X773749D01*
G01X739699Y987664D02*
X744049D01*
G01D02*
X748244D01*
X750190Y985718D01*
X751471D01*
X755090Y989337D01*
X755513D01*
G01X764169Y989386D02*
X765807D01*
X767530Y987663D01*
X773748D01*
X773749Y987664D01*
G01X739699Y1027822D02*
X744049D01*
G01D02*
X748244D01*
X750190Y1025876D01*
X751471D01*
X755090Y1029495D01*
X755513D01*
G01X764169Y1029544D02*
X765807D01*
X767530Y1027821D01*
X773748D01*
X773749Y1027822D01*
G01X739699Y1021129D02*
X744049D01*
G01D02*
X747544D01*
X751057Y1017616D01*
X752539D01*
X754379Y1019456D01*
X755477D01*
G01X764169Y1019505D02*
X766352D01*
X767976Y1021129D01*
X773749D01*
G01X739699Y1041207D02*
X744049D01*
G01D02*
X747672D01*
X749523Y1039356D01*
X750642D01*
X754166Y1042880D01*
X755034D01*
G01X764169Y1042929D02*
X765807D01*
X767530Y1041206D01*
X773748D01*
X773749Y1041207D01*
G01X739699Y1034514D02*
X739700Y1034515D01*
X744049D01*
G01D02*
X747554D01*
X749415Y1032654D01*
X750534D01*
X754068Y1036188D01*
X755129D01*
G01X764169Y1036237D02*
X765807D01*
X767530Y1034514D01*
X773748D01*
X773749Y1034515D01*
G01Y1061286D02*
X773748Y1061287D01*
X767328D01*
X765654Y1059613D01*
X764873D01*
G01X755064D02*
X753338D01*
X752873Y1060078D01*
Y1061525D01*
X752133Y1062265D01*
X751015D01*
X750036Y1061286D01*
X744049D01*
G01D02*
X739699D01*
G01Y1047900D02*
X744049D01*
G01D02*
X748244D01*
X750190Y1045954D01*
X751471D01*
X755090Y1049573D01*
X755513D01*
G01X764169Y1049622D02*
X765807D01*
X767530Y1047899D01*
X773748D01*
X773749Y1047900D01*
G01X739699Y1054593D02*
X744049D01*
G01X773749Y1074672D02*
X773748Y1074673D01*
X767328D01*
X765654Y1072999D01*
X764873D01*
G01X755064D02*
X754091D01*
X753626Y1073464D01*
Y1074911D01*
X752886Y1075651D01*
X751015D01*
X750036Y1074672D01*
X744049D01*
G01D02*
X739699D01*
G01X773749Y1067979D02*
X773748Y1067980D01*
X767328D01*
X765654Y1066306D01*
X764873D01*
G01X755064D02*
X754091D01*
X753626Y1066771D01*
Y1068218D01*
X752886Y1068958D01*
X751015D01*
X750036Y1067979D01*
X744049D01*
G01D02*
X739699D01*
G01X773749Y1091404D02*
X773748Y1091405D01*
X767328D01*
X765654Y1089731D01*
X764873D01*
G01X755064D02*
X754091D01*
X753626Y1090196D01*
Y1091643D01*
X752886Y1092383D01*
X751015D01*
X750036Y1091404D01*
X744049D01*
G01D02*
X739699D01*
G01Y1081365D02*
X744049D01*
G01D02*
X746209D01*
X747318Y1082474D01*
X749582D01*
X751214Y1084106D01*
X753901D01*
X754969Y1083038D01*
X755296D01*
G01X764873D02*
X765466D01*
X766356Y1083928D01*
X767557D01*
X769173Y1082312D01*
X770482D01*
X771429Y1081365D01*
X773749D01*
G01X739699Y1084711D02*
X744049D01*
G01D02*
X746369D01*
X747316Y1083764D01*
X749047D01*
X750679Y1085396D01*
X754012D01*
X755001Y1086385D01*
X755509D01*
G01X764988D02*
X765466D01*
X766633Y1085218D01*
X768092D01*
X769708Y1083602D01*
X770480D01*
X771589Y1084711D01*
X773749D01*
G01Y1098097D02*
X773748Y1098098D01*
X767328D01*
X765654Y1096424D01*
X764873D01*
G01X755064D02*
X754091D01*
X753626Y1096889D01*
Y1098336D01*
X752886Y1099076D01*
X751015D01*
X750036Y1098097D01*
X744049D01*
G01D02*
X739699D01*
G01X773749Y1111483D02*
X773748Y1111484D01*
X767482D01*
X765783Y1109785D01*
X764169D01*
G01X755023Y1109810D02*
X754091D01*
X753626Y1110275D01*
Y1111722D01*
X752886Y1112462D01*
X751015D01*
X750036Y1111483D01*
X744049D01*
G01D02*
X739699D01*
G01X773749Y1104790D02*
X773748Y1104791D01*
X767482D01*
X765783Y1103092D01*
X764169D01*
G01X755448Y1103117D02*
X754091D01*
X753626Y1103582D01*
Y1105029D01*
X752886Y1105769D01*
X751015D01*
X750036Y1104790D01*
X744049D01*
G01D02*
X739699D01*
G01X773749Y1128215D02*
X773748Y1128216D01*
X767482D01*
X765783Y1126517D01*
X764169D01*
G01X755448Y1126542D02*
X754091D01*
X753626Y1127007D01*
Y1128454D01*
X752886Y1129194D01*
X751015D01*
X750036Y1128215D01*
X744049D01*
G01D02*
X739699D01*
G01Y1118176D02*
X744049D01*
G01D02*
X746209D01*
X747318Y1119285D01*
X750215D01*
X751847Y1120917D01*
X753901D01*
X754969Y1119849D01*
X755550D01*
G01X764169Y1119828D02*
X765445D01*
X766356Y1120739D01*
X767557D01*
X769173Y1119123D01*
X770482D01*
X771429Y1118176D01*
X773749D01*
G01X739699Y1121522D02*
X744049D01*
G01D02*
X746369D01*
X747316Y1120575D01*
X749680D01*
X751312Y1122207D01*
X754012D01*
X755001Y1123196D01*
X755550D01*
G01X764169Y1123220D02*
X765442D01*
X766633Y1122029D01*
X768092D01*
X769708Y1120413D01*
X770480D01*
X771589Y1121522D01*
X773749D01*
G01Y1141601D02*
X773748Y1141602D01*
X767482D01*
X765783Y1139903D01*
X764169D01*
G01X755448Y1139928D02*
X754091D01*
X753626Y1140393D01*
Y1141840D01*
X752886Y1142580D01*
X751015D01*
X750036Y1141601D01*
X744049D01*
G01D02*
X739699D01*
G01X773749Y1134908D02*
X773748Y1134909D01*
X767482D01*
X765783Y1133210D01*
X764169D01*
G01X755448Y1133235D02*
X754091D01*
X753626Y1133700D01*
Y1135147D01*
X752886Y1135887D01*
X751015D01*
X750036Y1134908D01*
X744049D01*
G01D02*
X739699D01*
G01X773749Y1148294D02*
X773748Y1148295D01*
X767482D01*
X765783Y1146596D01*
X764169D01*
G01X755448Y1146621D02*
X754091D01*
X753626Y1147086D01*
Y1148533D01*
X752886Y1149273D01*
X751015D01*
X750036Y1148294D01*
X744049D01*
G01D02*
X739699D01*
G01Y1154987D02*
X744049D01*
G01D02*
X746209D01*
X747318Y1156096D01*
X750215D01*
X751847Y1157728D01*
X753901D01*
X754969Y1156660D01*
X755550D01*
G01X764169Y1156639D02*
X765445D01*
X766356Y1157550D01*
X767557D01*
X769173Y1155934D01*
X770482D01*
X771429Y1154987D01*
X773749D01*
G01X739699Y1158333D02*
X744049D01*
G01D02*
X746369D01*
X747316Y1157386D01*
X749680D01*
X751312Y1159018D01*
X754012D01*
X755001Y1160007D01*
X755550D01*
G01X764169Y1160031D02*
X765442D01*
X766633Y1158840D01*
X768092D01*
X769708Y1157224D01*
X770480D01*
X771589Y1158333D01*
X773749D01*
G01Y1171719D02*
X773748Y1171720D01*
X767482D01*
X765783Y1170021D01*
X764169D01*
G01X755448Y1170046D02*
X754091D01*
X753626Y1170511D01*
Y1171958D01*
X752886Y1172698D01*
X751015D01*
X750036Y1171719D01*
X744049D01*
G01D02*
X739699D01*
G01X773749Y1165026D02*
X773748Y1165027D01*
X767482D01*
X765783Y1163328D01*
X764169D01*
G01X755448Y1163353D02*
X754091D01*
X753626Y1163818D01*
Y1165265D01*
X752886Y1166005D01*
X751015D01*
X750036Y1165026D01*
X744049D01*
G01D02*
X739699D01*
G01X773749Y1185105D02*
X773748Y1185106D01*
X767482D01*
X765783Y1183407D01*
X764169D01*
G01X755186Y1183432D02*
X753111D01*
X752646Y1183897D01*
Y1185344D01*
X751906Y1186084D01*
X750035D01*
X749056Y1185105D01*
X744049D01*
G01D02*
X739699D01*
G01X773749Y1178412D02*
X773748Y1178413D01*
X767482D01*
X765783Y1176714D01*
X764169D01*
G01X755448Y1176739D02*
X754091D01*
X753626Y1177204D01*
Y1178651D01*
X752886Y1179391D01*
X751015D01*
X750036Y1178412D01*
X744049D01*
G01D02*
X739699D01*
G01Y1191798D02*
X744049D01*
G01D02*
X746209D01*
X747318Y1192907D01*
X750215D01*
X751847Y1194539D01*
X753901D01*
X754969Y1193471D01*
X755550D01*
G01X764169Y1193450D02*
X765445D01*
X766356Y1194361D01*
X767557D01*
X769173Y1192745D01*
X770482D01*
X771429Y1191798D01*
X773749D01*
G01Y1208530D02*
X773748Y1208531D01*
X767482D01*
X765783Y1206832D01*
X764169D01*
G01X755448Y1206857D02*
X754091D01*
X753626Y1207322D01*
Y1208769D01*
X752886Y1209509D01*
X751015D01*
X750036Y1208530D01*
X744049D01*
G01D02*
X739699D01*
G01X773749Y1201837D02*
X773748Y1201838D01*
X767482D01*
X765783Y1200139D01*
X764169D01*
G01X755448Y1200164D02*
X754091D01*
X753626Y1200629D01*
Y1202076D01*
X752886Y1202816D01*
X751015D01*
X750036Y1201837D01*
X744049D01*
G01D02*
X739699D01*
G01Y1195144D02*
X744049D01*
G01D02*
X746369D01*
X747316Y1194197D01*
X749680D01*
X751312Y1195829D01*
X754012D01*
X755001Y1196818D01*
X755550D01*
G01X764169Y1196842D02*
X765442D01*
X766633Y1195651D01*
X768092D01*
X769708Y1194035D01*
X770480D01*
X771589Y1195144D01*
X773749D01*
G01Y1221916D02*
X773748Y1221917D01*
X767482D01*
X765783Y1220218D01*
X764169D01*
G01X755448Y1220243D02*
X754091D01*
X753626Y1220708D01*
Y1222155D01*
X752886Y1222895D01*
X751015D01*
X750036Y1221916D01*
X744049D01*
G01D02*
X739699D01*
G01X773749Y1215223D02*
X773748Y1215224D01*
X767482D01*
X765783Y1213525D01*
X764169D01*
G01X755448Y1213550D02*
X754091D01*
X753626Y1214015D01*
Y1215462D01*
X752886Y1216202D01*
X751015D01*
X750036Y1215223D01*
X744049D01*
G01D02*
X739699D01*
G01X773749Y1238648D02*
X773748Y1238649D01*
X767482D01*
X765783Y1236950D01*
X764169D01*
G01X755448Y1236975D02*
X754091D01*
X753626Y1237440D01*
Y1238887D01*
X752886Y1239627D01*
X751015D01*
X750036Y1238648D01*
X744049D01*
G01D02*
X739699D01*
G01Y1228609D02*
X744049D01*
G01D02*
X746209D01*
X747318Y1229718D01*
X750215D01*
X751847Y1231350D01*
X753901D01*
X754969Y1230282D01*
X755550D01*
G01X764169Y1230261D02*
X765445D01*
X766356Y1231172D01*
X767557D01*
X769173Y1229556D01*
X770482D01*
X771429Y1228609D01*
X773749D01*
G01X739699Y1231955D02*
X744049D01*
G01D02*
X746369D01*
X747316Y1231008D01*
X749680D01*
X751312Y1232640D01*
X754012D01*
X755001Y1233629D01*
X755550D01*
G01X764169Y1233653D02*
X765442D01*
X766633Y1232462D01*
X768092D01*
X769708Y1230846D01*
X770480D01*
X771589Y1231955D01*
X773749D01*
G01Y1245341D02*
X773748Y1245342D01*
X767482D01*
X765783Y1243643D01*
X764169D01*
G01X755448Y1243668D02*
X754091D01*
X753626Y1244133D01*
Y1245580D01*
X752886Y1246320D01*
X751015D01*
X750036Y1245341D01*
X744049D01*
G01D02*
X739699D01*
G01X760191Y770144D02*
X766877D01*
X768578Y771845D01*
X769727D01*
G01X777727Y771865D02*
X780409D01*
X781212Y771062D01*
Y770074D01*
X782134Y769152D01*
X783646D01*
X784638Y770144D01*
X789891D01*
G01X755841D02*
X760191D01*
G01X755841Y776837D02*
X760191D01*
G01D02*
X766877D01*
X768578Y778538D01*
X769727D01*
G01X777727Y778558D02*
X780409D01*
X781212Y777755D01*
Y776767D01*
X782134Y775845D01*
X783646D01*
X784638Y776837D01*
X789891D01*
G01X755841Y786877D02*
X760191D01*
G01D02*
X762280D01*
X763348Y785809D01*
X765251D01*
X766924Y784136D01*
X767406D01*
X768498Y785228D01*
X769727D01*
G01X777727Y785247D02*
X778982D01*
X780107Y784122D01*
X782036D01*
X783790Y785876D01*
X786907D01*
X787908Y786877D01*
X789891D01*
G01X755841Y783530D02*
X760191D01*
G01D02*
X762527D01*
X763516Y784519D01*
X764716D01*
X766389Y782846D01*
X767485D01*
X768502Y781829D01*
X769727D01*
G01X777727Y781828D02*
X778994D01*
X779998Y782832D01*
X782571D01*
X784325Y784586D01*
X786599D01*
X787655Y783530D01*
X789891D01*
G01X755841Y800263D02*
X760191D01*
G01D02*
X766877D01*
X768578Y801964D01*
X769727D01*
G01X777727Y801984D02*
X780409D01*
X781212Y801181D01*
Y800193D01*
X782134Y799271D01*
X783646D01*
X784638Y800263D01*
X789891D01*
G01X755841Y793570D02*
X760191D01*
G01D02*
X766877D01*
X768578Y795271D01*
X769727D01*
G01X777727Y795291D02*
X780409D01*
X781212Y794488D01*
Y793500D01*
X782134Y792578D01*
X783646D01*
X784638Y793570D01*
X789891D01*
G01X755841Y813648D02*
X760191D01*
G01D02*
X766877D01*
X768578Y815349D01*
X769727D01*
G01X777727Y815369D02*
X780409D01*
X781212Y814566D01*
Y813578D01*
X782134Y812656D01*
X783646D01*
X784638Y813648D01*
X789891D01*
G01X755841Y806955D02*
X760191D01*
G01D02*
X766877D01*
X768578Y808656D01*
X769727D01*
G01X777727Y808676D02*
X780409D01*
X781212Y807873D01*
Y806885D01*
X782134Y805963D01*
X783646D01*
X784638Y806955D01*
X789891D01*
G01X755841Y830381D02*
X760191D01*
G01D02*
X766877D01*
X768578Y832082D01*
X769727D01*
G01X777727Y832102D02*
X780409D01*
X781212Y831299D01*
Y830311D01*
X782134Y829389D01*
X783646D01*
X784638Y830381D01*
X789891D01*
G01X755841Y823688D02*
X760191D01*
G01D02*
X762280D01*
X763348Y822620D01*
X765251D01*
X766924Y820947D01*
X767406D01*
X768498Y822039D01*
X769727D01*
G01X777727Y822058D02*
X778982D01*
X780107Y820933D01*
X782036D01*
X783790Y822687D01*
X786907D01*
X787908Y823688D01*
X789891D01*
G01X755841Y820341D02*
X760191D01*
G01D02*
X762527D01*
X763516Y821330D01*
X764716D01*
X766389Y819657D01*
X767485D01*
X768502Y818640D01*
X769727D01*
G01X777727Y818639D02*
X778994D01*
X779998Y819643D01*
X782571D01*
X784325Y821397D01*
X786599D01*
X787655Y820341D01*
X789891D01*
G01X755841Y850459D02*
X760191D01*
G01D02*
X766877D01*
X768578Y852160D01*
X769727D01*
G01X777727Y852180D02*
X780409D01*
X781212Y851377D01*
Y850389D01*
X782134Y849467D01*
X783646D01*
X784638Y850459D01*
X789891D01*
G01X755841Y843766D02*
X760191D01*
G01D02*
X766877D01*
X768578Y845467D01*
X769727D01*
G01X777727Y845487D02*
X780409D01*
X781212Y844684D01*
Y843696D01*
X782134Y842774D01*
X783646D01*
X784638Y843766D01*
X789891D01*
G01X755841Y837074D02*
X760191D01*
G01D02*
X766877D01*
X768578Y838775D01*
X769727D01*
G01X777727Y838795D02*
X780409D01*
X781212Y837992D01*
Y837004D01*
X782134Y836082D01*
X783646D01*
X784638Y837074D01*
X789891D01*
G01X755841Y867192D02*
X760191D01*
G01D02*
X766877D01*
X768578Y868893D01*
X769727D01*
G01X777727Y868913D02*
X780409D01*
X781212Y868110D01*
Y867122D01*
X782134Y866200D01*
X783646D01*
X784638Y867192D01*
X789891D01*
G01X755841Y860499D02*
X760191D01*
G01D02*
X762280D01*
X763348Y859431D01*
X765251D01*
X766924Y857758D01*
X767406D01*
X768498Y858850D01*
X769727D01*
G01X777727Y858869D02*
X778982D01*
X780107Y857744D01*
X782036D01*
X783790Y859498D01*
X786907D01*
X787908Y860499D01*
X789891D01*
G01X755841Y857152D02*
X760191D01*
G01D02*
X762527D01*
X763516Y858141D01*
X764716D01*
X766389Y856468D01*
X767485D01*
X768502Y855451D01*
X769727D01*
G01X777727Y855450D02*
X778994D01*
X779998Y856454D01*
X782571D01*
X784325Y858208D01*
X786599D01*
X787655Y857152D01*
X789891D01*
G01X755841Y873885D02*
X760191D01*
G01D02*
X766877D01*
X768578Y875586D01*
X769727D01*
G01X777727Y875606D02*
X780409D01*
X781212Y874803D01*
Y873815D01*
X782134Y872893D01*
X783646D01*
X784638Y873885D01*
X789891D01*
G01X755841Y880577D02*
X760191D01*
G01D02*
X766877D01*
X768578Y882278D01*
X769727D01*
G01X777727Y882298D02*
X780409D01*
X781212Y881495D01*
Y880507D01*
X782134Y879585D01*
X783646D01*
X784638Y880577D01*
X789891D01*
G01X755841Y887270D02*
X760191D01*
G01D02*
X766877D01*
X768578Y888971D01*
X769727D01*
G01X777727Y888991D02*
X780409D01*
X781212Y888188D01*
Y887200D01*
X782134Y886278D01*
X783646D01*
X784638Y887270D01*
X789891D01*
G01X755841Y897310D02*
X760191D01*
G01D02*
X762280D01*
X763348Y896242D01*
X765251D01*
X766924Y894569D01*
X767406D01*
X768498Y895661D01*
X769727D01*
G01X777727Y895680D02*
X778982D01*
X780107Y894555D01*
X782036D01*
X783790Y896309D01*
X786907D01*
X787908Y897310D01*
X789891D01*
G01X755841Y893963D02*
X760191D01*
G01D02*
X762527D01*
X763516Y894952D01*
X764716D01*
X766389Y893279D01*
X767485D01*
X768502Y892262D01*
X769727D01*
G01X777727Y892261D02*
X778994D01*
X779998Y893265D01*
X782571D01*
X784325Y895019D01*
X786599D01*
X787655Y893963D01*
X789891D01*
G01X755841Y910696D02*
X760191D01*
G01D02*
X766877D01*
X768578Y912397D01*
X769727D01*
G01X777727Y912417D02*
X780409D01*
X781212Y911614D01*
Y910626D01*
X782134Y909704D01*
X783646D01*
X784638Y910696D01*
X789891D01*
G01X755841Y904003D02*
X760191D01*
G01D02*
X766877D01*
X768578Y905704D01*
X769727D01*
G01X777727Y905724D02*
X780409D01*
X781212Y904921D01*
Y903933D01*
X782134Y903011D01*
X783646D01*
X784638Y904003D01*
X789891D01*
G01X755841Y924081D02*
X760191D01*
G01D02*
X766477D01*
X768150Y925754D01*
X769067D01*
G01X778876D02*
X780422D01*
X781212Y924964D01*
Y923710D01*
X782002Y922920D01*
X783477D01*
X784638Y924081D01*
X789891D01*
G01X755841Y917389D02*
X760191D01*
G01D02*
X766905D01*
X768578Y919062D01*
X769067D01*
G01X778876D02*
X780422D01*
X781212Y918272D01*
Y917102D01*
X782002Y916312D01*
X783561D01*
X784638Y917389D01*
X789891D01*
G01X755841Y930774D02*
X760191D01*
G01D02*
X762527D01*
X763516Y931763D01*
X764716D01*
X766389Y930090D01*
X767440D01*
X768429Y929101D01*
X768854D01*
G01X778431D02*
X779023D01*
X779998Y930076D01*
X782571D01*
X784325Y931830D01*
X786599D01*
X787655Y930774D01*
X789891D01*
G01X755841Y947507D02*
X760191D01*
G01D02*
X766477D01*
X768150Y949180D01*
X769067D01*
G01X778876D02*
X780422D01*
X781212Y948390D01*
Y947136D01*
X782002Y946346D01*
X783477D01*
X784638Y947507D01*
X789891D01*
G01X755841Y940814D02*
X760191D01*
G01D02*
X766905D01*
X768578Y942487D01*
X769067D01*
G01X778876D02*
X780422D01*
X781212Y941697D01*
Y940527D01*
X782002Y939737D01*
X783561D01*
X784638Y940814D01*
X789891D01*
G01X755841Y934121D02*
X760191D01*
G01D02*
X762280D01*
X763348Y933053D01*
X765251D01*
X766924Y931380D01*
X767430D01*
X768498Y932448D01*
X769067D01*
G01X778546D02*
X779025D01*
X780107Y931366D01*
X782036D01*
X783790Y933120D01*
X786907D01*
X787908Y934121D01*
X789891D01*
G01X760191Y964239D02*
X755841D01*
G01Y977625D02*
X760191D01*
G01D02*
X766631D01*
X768346Y979340D01*
X769727D01*
G01X777727Y979327D02*
X778806D01*
X782211Y975922D01*
X783800D01*
X785503Y977625D01*
X789891D01*
G01X755741Y970932D02*
X760191D01*
G01D02*
X766631D01*
X768346Y972647D01*
X769727D01*
G01X777727Y972634D02*
X778806D01*
X782211Y969229D01*
X783800D01*
X785503Y970932D01*
X789891D01*
G01X755841Y991011D02*
X760191D01*
G01D02*
X766631D01*
X768346Y992726D01*
X769727D01*
G01X777727Y992713D02*
X778806D01*
X782211Y989308D01*
X783800D01*
X785503Y991011D01*
X789891D01*
G01X755841Y984318D02*
X760191D01*
G01D02*
X766631D01*
X768346Y986033D01*
X769727D01*
G01X777727Y986020D02*
X778806D01*
X782211Y982615D01*
X783800D01*
X785503Y984318D01*
X789891D01*
G01X755841Y1021129D02*
X760191D01*
G01Y1024475D02*
X755841D01*
G01X755541Y1044554D02*
X760191D01*
G01D02*
X766631D01*
X768346Y1046269D01*
X769727D01*
G01X777727Y1046256D02*
X778806D01*
X782211Y1042851D01*
X783800D01*
X785503Y1044554D01*
X789891D01*
G01X755541Y1037861D02*
X760191D01*
G01D02*
X766631D01*
X768346Y1039576D01*
X769727D01*
G01X777727Y1039563D02*
X778806D01*
X782211Y1036158D01*
X783800D01*
X785503Y1037861D01*
X789891D01*
G01X755841Y1031168D02*
X760191D01*
G01D02*
X766631D01*
X768346Y1032883D01*
X769727D01*
G01X777727Y1032870D02*
X778806D01*
X782211Y1029465D01*
X783800D01*
X785503Y1031168D01*
X789891D01*
G01X760191Y1051247D02*
X755841D01*
G01X755676Y1071326D02*
X760191D01*
G01D02*
X766477D01*
X768150Y1072999D01*
X769067D01*
G01X778876D02*
X780422D01*
X781212Y1072209D01*
Y1070955D01*
X782002Y1070165D01*
X783477D01*
X784638Y1071326D01*
X789891D01*
G01X755741Y1064633D02*
X760191D01*
G01D02*
X766905D01*
X768578Y1066306D01*
X769067D01*
G01X778876D02*
X780422D01*
X781212Y1065516D01*
Y1064346D01*
X782002Y1063556D01*
X783561D01*
X784638Y1064633D01*
X789891D01*
G01X755841Y1078018D02*
X760191D01*
G01D02*
X762527D01*
X763516Y1079007D01*
X764716D01*
X766389Y1077334D01*
X767440D01*
X768429Y1076345D01*
X768854D01*
G01X778431D02*
X779023D01*
X779998Y1077320D01*
X782571D01*
X784325Y1079074D01*
X786599D01*
X787655Y1078018D01*
X789891D01*
G01X755841Y1094751D02*
X760191D01*
G01D02*
X766477D01*
X768150Y1096424D01*
X769067D01*
G01X778876D02*
X780422D01*
X781212Y1095634D01*
Y1094380D01*
X782002Y1093590D01*
X783477D01*
X784638Y1094751D01*
X789891D01*
G01X755841Y1088058D02*
X760191D01*
G01D02*
X766905D01*
X768578Y1089731D01*
X769067D01*
G01X778876D02*
X780422D01*
X781212Y1088941D01*
Y1087771D01*
X782002Y1086981D01*
X783561D01*
X784638Y1088058D01*
X789891D01*
G01X755841Y1081365D02*
X760191D01*
G01D02*
X762280D01*
X763348Y1080297D01*
X765251D01*
X766924Y1078624D01*
X767430D01*
X768498Y1079692D01*
X769067D01*
G01X778546D02*
X779025D01*
X780107Y1078610D01*
X782036D01*
X783790Y1080364D01*
X786907D01*
X787908Y1081365D01*
X789891D01*
G01X755676Y1108137D02*
X760191D01*
G01D02*
X766877D01*
X768578Y1109838D01*
X769727D01*
G01X777727Y1109858D02*
X780409D01*
X781212Y1109055D01*
Y1108067D01*
X782134Y1107145D01*
X783646D01*
X784638Y1108137D01*
X789891D01*
G01X755841Y1101444D02*
X760191D01*
G01D02*
X766877D01*
X768578Y1103145D01*
X769727D01*
G01X777727Y1103165D02*
X780409D01*
X781212Y1102362D01*
Y1101374D01*
X782134Y1100452D01*
X783646D01*
X784638Y1101444D01*
X789891D01*
G01X755841Y1124869D02*
X760191D01*
G01D02*
X766877D01*
X768578Y1126570D01*
X769727D01*
G01X777727Y1126590D02*
X780409D01*
X781212Y1125787D01*
Y1124799D01*
X782134Y1123877D01*
X783646D01*
X784638Y1124869D01*
X789891D01*
G01X755841Y1118176D02*
X760191D01*
G01D02*
X762280D01*
X763348Y1117108D01*
X765251D01*
X766924Y1115435D01*
X767406D01*
X768498Y1116527D01*
X769727D01*
G01X777727Y1116546D02*
X778982D01*
X780107Y1115421D01*
X782036D01*
X783790Y1117175D01*
X786907D01*
X787908Y1118176D01*
X789891D01*
G01X755841Y1114829D02*
X760191D01*
G01D02*
X762527D01*
X763516Y1115818D01*
X764716D01*
X766389Y1114145D01*
X767485D01*
X768502Y1113128D01*
X769727D01*
G01X777727Y1113127D02*
X778994D01*
X779998Y1114131D01*
X782571D01*
X784325Y1115885D01*
X786599D01*
X787655Y1114829D01*
X789891D01*
G01X755841Y1144947D02*
X755842Y1144948D01*
X760191D01*
G01X755841Y1138255D02*
X760191D01*
G01D02*
X766877D01*
X768578Y1139956D01*
X769727D01*
G01X777727Y1139976D02*
X780409D01*
X781212Y1139173D01*
Y1138185D01*
X782134Y1137263D01*
X783646D01*
X784638Y1138255D01*
X789891D01*
G01X755841Y1131562D02*
X760191D01*
G01D02*
X766877D01*
X768578Y1133263D01*
X769727D01*
G01X777727Y1133283D02*
X780409D01*
X781212Y1132480D01*
Y1131492D01*
X782134Y1130570D01*
X783646D01*
X784638Y1131562D01*
X789891D01*
G01X760191Y1144948D02*
X766877D01*
X768578Y1146649D01*
X769727D01*
G01X777727Y1146669D02*
X780409D01*
X781212Y1145866D01*
Y1144878D01*
X782134Y1143956D01*
X783646D01*
X784638Y1144948D01*
X789891D01*
G01X755841Y1154987D02*
X760191D01*
G01D02*
X762280D01*
X763348Y1153919D01*
X765251D01*
X766924Y1152246D01*
X767406D01*
X768498Y1153338D01*
X769727D01*
G01X777727Y1153357D02*
X778982D01*
X780107Y1152232D01*
X782036D01*
X783790Y1153986D01*
X786907D01*
X787908Y1154987D01*
X789891D01*
G01X755841Y1151640D02*
X755842Y1151641D01*
X760191D01*
G01D02*
X762528D01*
X763516Y1152629D01*
X764716D01*
X766389Y1150956D01*
X767485D01*
X768501Y1149940D01*
X769727D01*
G01X777727Y1149939D02*
X778995D01*
X779998Y1150942D01*
X782571D01*
X784325Y1152696D01*
X786599D01*
X787654Y1151641D01*
X789891D01*
G01X755841Y1175066D02*
X760191D01*
G01D02*
X766877D01*
X768578Y1176767D01*
X769727D01*
G01X777727Y1176787D02*
X780409D01*
X781212Y1175984D01*
Y1174996D01*
X782134Y1174074D01*
X783646D01*
X784638Y1175066D01*
X789891D01*
G01X755841Y1168373D02*
X760191D01*
G01D02*
X766877D01*
X768578Y1170074D01*
X769727D01*
G01X777727Y1170094D02*
X780409D01*
X781212Y1169291D01*
Y1168303D01*
X782134Y1167381D01*
X783646D01*
X784638Y1168373D01*
X789891D01*
G01X755841Y1161680D02*
X760191D01*
G01D02*
X766877D01*
X768578Y1163381D01*
X769727D01*
G01X777727Y1163401D02*
X780409D01*
X781212Y1162598D01*
Y1161610D01*
X782134Y1160688D01*
X783646D01*
X784638Y1161680D01*
X789891D01*
G01X755676Y1181759D02*
X760191D01*
G01D02*
X766877D01*
X768578Y1183460D01*
X769727D01*
G01X777727Y1183480D02*
X780409D01*
X781212Y1182677D01*
Y1181689D01*
X782134Y1180767D01*
X783646D01*
X784638Y1181759D01*
X789891D01*
G01X755841Y1191798D02*
X760191D01*
G01D02*
X762280D01*
X763348Y1190730D01*
X765251D01*
X766924Y1189057D01*
X767406D01*
X768498Y1190149D01*
X769727D01*
G01X777727Y1190168D02*
X778982D01*
X780107Y1189043D01*
X782036D01*
X783790Y1190797D01*
X786907D01*
X787908Y1191798D01*
X789891D01*
G01X755676Y1188452D02*
X760191D01*
G01D02*
X762528D01*
X763516Y1189440D01*
X764716D01*
X766389Y1187767D01*
X767485D01*
X768501Y1186751D01*
X769727D01*
G01X777727Y1186750D02*
X778995D01*
X779998Y1187753D01*
X782571D01*
X784325Y1189507D01*
X786599D01*
X787654Y1188452D01*
X789891D01*
G01X755841Y1205184D02*
X760191D01*
G01D02*
X766877D01*
X768578Y1206885D01*
X769727D01*
G01X777727Y1206905D02*
X780409D01*
X781212Y1206102D01*
Y1205114D01*
X782134Y1204192D01*
X783646D01*
X784638Y1205184D01*
X789891D01*
G01X755841Y1198491D02*
X760191D01*
G01D02*
X766877D01*
X768578Y1200192D01*
X769727D01*
G01X777727Y1200212D02*
X780409D01*
X781212Y1199409D01*
Y1198421D01*
X782134Y1197499D01*
X783646D01*
X784638Y1198491D01*
X789891D01*
G01X755841Y1218569D02*
X755842Y1218570D01*
X760191D01*
G01D02*
X766877D01*
X768578Y1220271D01*
X769727D01*
G01X777727Y1220291D02*
X780409D01*
X781212Y1219488D01*
Y1218500D01*
X782134Y1217578D01*
X783646D01*
X784638Y1218570D01*
X789891D01*
G01X755841Y1211877D02*
X760191D01*
G01D02*
X766877D01*
X768578Y1213578D01*
X769727D01*
G01X777727Y1213598D02*
X780409D01*
X781212Y1212795D01*
Y1211807D01*
X782134Y1210885D01*
X783646D01*
X784638Y1211877D01*
X789891D01*
G01X755841Y1225262D02*
X755842Y1225263D01*
X760191D01*
G01D02*
X762528D01*
X763516Y1226251D01*
X764716D01*
X766389Y1224578D01*
X767485D01*
X768501Y1223562D01*
X769727D01*
G01X777727Y1223561D02*
X778995D01*
X779998Y1224564D01*
X782571D01*
X784325Y1226318D01*
X786599D01*
X787654Y1225263D01*
X789891D01*
G01X755841Y1241995D02*
X760191D01*
G01D02*
X766877D01*
X768578Y1243696D01*
X769727D01*
G01X777727Y1243716D02*
X780409D01*
X781212Y1242913D01*
Y1241925D01*
X782134Y1241003D01*
X783646D01*
X784638Y1241995D01*
X789891D01*
G01X755841Y1235302D02*
X760191D01*
G01D02*
X766877D01*
X768578Y1237003D01*
X769727D01*
G01X777727Y1237023D02*
X780409D01*
X781212Y1236220D01*
Y1235232D01*
X782134Y1234310D01*
X783646D01*
X784638Y1235302D01*
X789891D01*
G01X755841Y1228609D02*
X760191D01*
G01D02*
X762280D01*
X763348Y1227541D01*
X765251D01*
X766924Y1225868D01*
X767406D01*
X768498Y1226960D01*
X769727D01*
G01X777727Y1226979D02*
X778982D01*
X780107Y1225854D01*
X782036D01*
X783790Y1227608D01*
X786907D01*
X787908Y1228609D01*
X789891D01*
G01X769399Y960892D02*
X773749D01*
G01Y957546D02*
X769399D01*
G01Y967585D02*
X773749D01*
G01Y1054593D02*
X769399D01*
G01X785541Y964239D02*
X789891D01*
G01X785541Y1021129D02*
X789891D01*
G01Y1024475D02*
X785541D01*
G01X789891Y1051247D02*
X785541D01*
G01X833149Y780184D02*
X833148Y780185D01*
X826882D01*
X825183Y778486D01*
X823569D01*
G01X814848Y778511D02*
X813491D01*
X813026Y778976D01*
Y780423D01*
X812286Y781163D01*
X810415D01*
X809436Y780184D01*
X803449D01*
G01D02*
X799099D01*
G01X833149Y773491D02*
X833148Y773492D01*
X826882D01*
X825183Y771793D01*
X823569D01*
G01X814848Y771818D02*
X813491D01*
X813026Y772283D01*
Y773730D01*
X812286Y774470D01*
X810415D01*
X809436Y773491D01*
X803449D01*
G01D02*
X799099D01*
G01Y786877D02*
X803449D01*
G01D02*
X805609D01*
X806718Y787986D01*
X809615D01*
X811247Y789618D01*
X813301D01*
X814369Y788550D01*
X814950D01*
G01X823569Y788529D02*
X824845D01*
X825756Y789440D01*
X826957D01*
X828573Y787824D01*
X829882D01*
X830829Y786877D01*
X833149D01*
G01Y796916D02*
X833148Y796917D01*
X826882D01*
X825183Y795218D01*
X823569D01*
G01X814848Y795243D02*
X813491D01*
X813026Y795708D01*
Y797155D01*
X812286Y797895D01*
X810415D01*
X809436Y796916D01*
X803449D01*
G01D02*
X799099D01*
G01Y790223D02*
X803449D01*
G01D02*
X805769D01*
X806716Y789276D01*
X809080D01*
X810712Y790908D01*
X813412D01*
X814401Y791897D01*
X814950D01*
G01X823569Y791921D02*
X824842D01*
X826033Y790730D01*
X827492D01*
X829108Y789114D01*
X829880D01*
X830989Y790223D01*
X833149D01*
G01Y816995D02*
X833148Y816996D01*
X826882D01*
X825183Y815297D01*
X823569D01*
G01X814848Y815322D02*
X813491D01*
X813026Y815787D01*
Y817234D01*
X812286Y817974D01*
X810415D01*
X809436Y816995D01*
X803449D01*
G01D02*
X799099D01*
G01X833149Y810302D02*
X833148Y810303D01*
X826882D01*
X825183Y808604D01*
X823569D01*
G01X814848Y808629D02*
X813491D01*
X813026Y809094D01*
Y810541D01*
X812286Y811281D01*
X810415D01*
X809436Y810302D01*
X803449D01*
G01D02*
X799099D01*
G01X833149Y803609D02*
X833148Y803610D01*
X826882D01*
X825183Y801911D01*
X823569D01*
G01X814848Y801936D02*
X813491D01*
X813026Y802401D01*
Y803848D01*
X812286Y804588D01*
X810415D01*
X809436Y803609D01*
X803449D01*
G01D02*
X799099D01*
G01X833149Y833727D02*
X833148Y833728D01*
X826882D01*
X825183Y832029D01*
X823569D01*
G01X814848Y832054D02*
X813491D01*
X813026Y832519D01*
Y833966D01*
X812286Y834706D01*
X810415D01*
X809436Y833727D01*
X803449D01*
G01D02*
X799099D01*
G01Y823688D02*
X803449D01*
G01D02*
X805609D01*
X806718Y824797D01*
X809615D01*
X811247Y826429D01*
X813301D01*
X814369Y825361D01*
X814950D01*
G01X823569Y825340D02*
X824845D01*
X825756Y826251D01*
X826957D01*
X828573Y824635D01*
X829882D01*
X830829Y823688D01*
X833149D01*
G01X799099Y827034D02*
X803449D01*
G01D02*
X805769D01*
X806716Y826087D01*
X809080D01*
X810712Y827719D01*
X813412D01*
X814401Y828708D01*
X814950D01*
G01X823569Y828732D02*
X824842D01*
X826033Y827541D01*
X827492D01*
X829108Y825925D01*
X829880D01*
X830989Y827034D01*
X833149D01*
G01Y847113D02*
X833148Y847114D01*
X826882D01*
X825183Y845415D01*
X823569D01*
G01X814848Y845440D02*
X813491D01*
X813026Y845905D01*
Y847352D01*
X812286Y848092D01*
X810415D01*
X809436Y847113D01*
X803449D01*
G01D02*
X799099D01*
G01X833149Y840420D02*
X833148Y840421D01*
X826882D01*
X825183Y838722D01*
X823569D01*
G01X814848Y838747D02*
X813491D01*
X813026Y839212D01*
Y840659D01*
X812286Y841399D01*
X810415D01*
X809436Y840420D01*
X803449D01*
G01D02*
X799099D01*
G01X833149Y853806D02*
X833148Y853807D01*
X826882D01*
X825183Y852108D01*
X823569D01*
G01X814848Y852133D02*
X813491D01*
X813026Y852598D01*
Y854045D01*
X812286Y854785D01*
X810415D01*
X809436Y853806D01*
X803449D01*
G01D02*
X799099D01*
G01Y860499D02*
X803449D01*
G01D02*
X805609D01*
X806718Y861608D01*
X809615D01*
X811247Y863240D01*
X813301D01*
X814369Y862172D01*
X814950D01*
G01X823569Y862151D02*
X824845D01*
X825756Y863062D01*
X826957D01*
X828573Y861446D01*
X829882D01*
X830829Y860499D01*
X833149D01*
G01X799099Y863845D02*
X803449D01*
G01D02*
X805769D01*
X806716Y862898D01*
X809080D01*
X810712Y864530D01*
X813412D01*
X814401Y865519D01*
X814950D01*
G01X823569Y865543D02*
X824842D01*
X826033Y864352D01*
X827492D01*
X829108Y862736D01*
X829880D01*
X830989Y863845D01*
X833149D01*
G01Y883924D02*
X833148Y883925D01*
X826882D01*
X825183Y882226D01*
X823569D01*
G01X814848Y882251D02*
X813491D01*
X813026Y882716D01*
Y884163D01*
X812286Y884903D01*
X810415D01*
X809436Y883924D01*
X803449D01*
G01D02*
X799099D01*
G01X833149Y877231D02*
X833148Y877232D01*
X826882D01*
X825183Y875533D01*
X823569D01*
G01X814848Y875558D02*
X813491D01*
X813026Y876023D01*
Y877470D01*
X812286Y878210D01*
X810415D01*
X809436Y877231D01*
X803449D01*
G01D02*
X799099D01*
G01X833149Y870538D02*
X833148Y870539D01*
X826882D01*
X825183Y868840D01*
X823569D01*
G01X814848Y868865D02*
X813491D01*
X813026Y869330D01*
Y870777D01*
X812286Y871517D01*
X810415D01*
X809436Y870538D01*
X803449D01*
G01D02*
X799099D01*
G01X833149Y890617D02*
X833148Y890618D01*
X826882D01*
X825183Y888919D01*
X823569D01*
G01X814848Y888944D02*
X813491D01*
X813026Y889409D01*
Y890856D01*
X812286Y891596D01*
X810415D01*
X809436Y890617D01*
X803449D01*
G01D02*
X799099D01*
G01Y897310D02*
X803449D01*
G01D02*
X805609D01*
X806718Y898419D01*
X809615D01*
X811247Y900051D01*
X813301D01*
X814369Y898983D01*
X814950D01*
G01X823569Y898962D02*
X824845D01*
X825756Y899873D01*
X826957D01*
X828573Y898257D01*
X829882D01*
X830829Y897310D01*
X833149D01*
G01X799099Y900656D02*
X803449D01*
G01D02*
X805769D01*
X806716Y899709D01*
X809080D01*
X810712Y901341D01*
X813412D01*
X814401Y902330D01*
X814950D01*
G01X823569Y902354D02*
X824842D01*
X826033Y901163D01*
X827492D01*
X829108Y899547D01*
X829880D01*
X830989Y900656D01*
X833149D01*
G01Y914042D02*
X833148Y914043D01*
X826882D01*
X825183Y912344D01*
X823569D01*
G01X814848Y912369D02*
X813491D01*
X813026Y912834D01*
Y914281D01*
X812286Y915021D01*
X810415D01*
X809436Y914042D01*
X803449D01*
G01D02*
X799099D01*
G01X833149Y907349D02*
X833148Y907350D01*
X826882D01*
X825183Y905651D01*
X823569D01*
G01X814848Y905676D02*
X813491D01*
X813026Y906141D01*
Y907588D01*
X812286Y908328D01*
X810415D01*
X809436Y907349D01*
X803449D01*
G01D02*
X799099D01*
G01X833149Y927428D02*
X833148Y927429D01*
X826882D01*
X825183Y925730D01*
X823569D01*
G01X814848Y925755D02*
X813491D01*
X813026Y926220D01*
Y927667D01*
X812286Y928407D01*
X810415D01*
X809436Y927428D01*
X803449D01*
G01D02*
X799099D01*
G01X833149Y920735D02*
X833148Y920736D01*
X826882D01*
X825183Y919037D01*
X823569D01*
G01X814848Y919062D02*
X813491D01*
X813026Y919527D01*
Y920974D01*
X812286Y921714D01*
X810415D01*
X809436Y920735D01*
X803449D01*
G01D02*
X799099D01*
G01X833149Y944160D02*
X833148Y944161D01*
X826882D01*
X825183Y942462D01*
X823569D01*
G01X814848Y942487D02*
X813491D01*
X813026Y942952D01*
Y944399D01*
X812286Y945139D01*
X810415D01*
X809436Y944160D01*
X803449D01*
G01D02*
X799099D01*
G01Y934121D02*
X803449D01*
G01D02*
X805609D01*
X806718Y935230D01*
X809615D01*
X811247Y936862D01*
X813301D01*
X814369Y935794D01*
X814950D01*
G01X823569Y935773D02*
X824845D01*
X825756Y936684D01*
X826957D01*
X828573Y935068D01*
X829882D01*
X830829Y934121D01*
X833149D01*
G01X799099Y937467D02*
X803449D01*
G01D02*
X805769D01*
X806716Y936520D01*
X809080D01*
X810712Y938152D01*
X813412D01*
X814401Y939141D01*
X814950D01*
G01X823569Y939165D02*
X824842D01*
X826033Y937974D01*
X827492D01*
X829108Y936358D01*
X829880D01*
X830989Y937467D01*
X833149D01*
G01X799099Y960892D02*
X803449D01*
G01X833149Y950853D02*
X833148Y950854D01*
X826882D01*
X825183Y949155D01*
X823569D01*
G01X814848Y949180D02*
X813491D01*
X813026Y949645D01*
Y951092D01*
X812286Y951832D01*
X810415D01*
X809436Y950853D01*
X803449D01*
G01D02*
X799099D01*
G01X803449Y957546D02*
X799099D01*
G01Y980971D02*
X803449D01*
G01D02*
X807644D01*
X809590Y979025D01*
X810871D01*
X814490Y982644D01*
X814913D01*
G01X823569Y982693D02*
X825207D01*
X826930Y980970D01*
X833148D01*
X833149Y980971D01*
G01X799099Y974278D02*
X803449D01*
G01D02*
X807644D01*
X809590Y972332D01*
X810871D01*
X814490Y975951D01*
X814913D01*
G01X823569Y976000D02*
X825207D01*
X826930Y974277D01*
X833148D01*
X833149Y974278D01*
G01X799099Y967585D02*
X803449D01*
G01X799099Y994357D02*
X803449D01*
G01D02*
X808261D01*
X809460Y993158D01*
X811610D01*
X815222Y996770D01*
X826401D01*
X828814Y994357D01*
X833149D01*
G01X799099Y987664D02*
X803449D01*
G01D02*
X807644D01*
X809590Y985718D01*
X810871D01*
X814490Y989337D01*
X814913D01*
G01X823569Y989386D02*
X825207D01*
X826930Y987663D01*
X833148D01*
X833149Y987664D01*
G01X799099Y1027822D02*
X803449D01*
G01D02*
X807644D01*
X809590Y1025876D01*
X810871D01*
X814490Y1029495D01*
X814913D01*
G01X823569Y1029544D02*
X825207D01*
X826930Y1027821D01*
X833148D01*
X833149Y1027822D01*
G01X799099Y1021129D02*
X803449D01*
G01D02*
X806944D01*
X810457Y1017616D01*
X811939D01*
X813779Y1019456D01*
X814877D01*
G01X823569Y1019505D02*
X825752D01*
X827376Y1021129D01*
X833149D01*
G01X803449Y1047900D02*
X807098D01*
X809044Y1045954D01*
X810311D01*
X813930Y1049573D01*
X814542D01*
G01X823569Y1049622D02*
X825207D01*
X826930Y1047899D01*
X833148D01*
X833149Y1047900D01*
G01X799099Y1041207D02*
X803449D01*
G01D02*
X807644D01*
X809590Y1039261D01*
X810871D01*
X814490Y1042880D01*
X814913D01*
G01X823569Y1042929D02*
X825207D01*
X826930Y1041206D01*
X833148D01*
X833149Y1041207D01*
G01X799099Y1034515D02*
X803449D01*
G01D02*
X807644D01*
X809590Y1032569D01*
X810871D01*
X814490Y1036188D01*
X814913D01*
G01X823569Y1036237D02*
X825207D01*
X826930Y1034514D01*
X833148D01*
X833149Y1034515D01*
G01Y1061286D02*
X833148Y1061287D01*
X829705D01*
X829367Y1061625D01*
X828016D01*
X825841Y1059450D01*
X823569D01*
G01X814765Y1059613D02*
X814296D01*
X813146Y1060763D01*
Y1061464D01*
X812446Y1062164D01*
X810146D01*
X809646Y1062664D01*
X806916D01*
X805538Y1061286D01*
X803449D01*
G01D02*
X799099D01*
G01Y1047900D02*
X803449D01*
G01X799099Y1054593D02*
X803449D01*
G01X833149Y1074672D02*
X833148Y1074673D01*
X826882D01*
X825183Y1072974D01*
X823569D01*
G01X814848Y1072999D02*
X813491D01*
X813026Y1073464D01*
Y1074911D01*
X812286Y1075651D01*
X810415D01*
X809436Y1074672D01*
X803449D01*
G01D02*
X799099D01*
G01X833149Y1067979D02*
X833148Y1067980D01*
X826882D01*
X825183Y1066281D01*
X823569D01*
G01X814848Y1066306D02*
X813491D01*
X813026Y1066771D01*
Y1068218D01*
X812286Y1068958D01*
X810415D01*
X809436Y1067979D01*
X803449D01*
G01D02*
X799099D01*
G01X833149Y1091404D02*
X833148Y1091405D01*
X826882D01*
X825183Y1089706D01*
X823569D01*
G01X814848Y1089731D02*
X813491D01*
X813026Y1090196D01*
Y1091643D01*
X812286Y1092383D01*
X810415D01*
X809436Y1091404D01*
X803449D01*
G01D02*
X799099D01*
G01Y1081365D02*
X803449D01*
G01D02*
X805609D01*
X806718Y1082474D01*
X809615D01*
X811247Y1084106D01*
X813301D01*
X814369Y1083038D01*
X814950D01*
G01X823569Y1083017D02*
X824845D01*
X825756Y1083928D01*
X826957D01*
X828573Y1082312D01*
X829882D01*
X830829Y1081365D01*
X833149D01*
G01X799099Y1084711D02*
X803449D01*
G01D02*
X805769D01*
X806716Y1083764D01*
X809080D01*
X810712Y1085396D01*
X813412D01*
X814401Y1086385D01*
X814950D01*
G01X823569Y1086409D02*
X824842D01*
X826033Y1085218D01*
X827492D01*
X829108Y1083602D01*
X829880D01*
X830989Y1084711D01*
X833149D01*
G01Y1098097D02*
X833148Y1098098D01*
X826882D01*
X825183Y1096399D01*
X823569D01*
G01X814848Y1096424D02*
X813491D01*
X813026Y1096889D01*
Y1098336D01*
X812286Y1099076D01*
X810415D01*
X809436Y1098097D01*
X803449D01*
G01D02*
X799099D01*
G01X833149Y1111483D02*
X833148Y1111484D01*
X826882D01*
X825183Y1109785D01*
X823569D01*
G01X814848Y1109810D02*
X813491D01*
X813026Y1110275D01*
Y1111722D01*
X812286Y1112462D01*
X810415D01*
X809436Y1111483D01*
X803449D01*
G01D02*
X799099D01*
G01X833149Y1104790D02*
X833148Y1104791D01*
X826882D01*
X825183Y1103092D01*
X823569D01*
G01X814848Y1103117D02*
X813491D01*
X813026Y1103582D01*
Y1105029D01*
X812286Y1105769D01*
X810415D01*
X809436Y1104790D01*
X803449D01*
G01D02*
X799099D01*
G01X833149Y1128215D02*
X833148Y1128216D01*
X826882D01*
X825183Y1126517D01*
X823569D01*
G01X814848Y1126542D02*
X813491D01*
X813026Y1127007D01*
Y1128454D01*
X812286Y1129194D01*
X810415D01*
X809436Y1128215D01*
X803449D01*
G01D02*
X799099D01*
G01Y1118176D02*
X803449D01*
G01D02*
X805609D01*
X806718Y1119285D01*
X809615D01*
X811247Y1120917D01*
X813301D01*
X814369Y1119849D01*
X814950D01*
G01X823569Y1119828D02*
X824845D01*
X825756Y1120739D01*
X826957D01*
X828573Y1119123D01*
X829882D01*
X830829Y1118176D01*
X833149D01*
G01X799099Y1121522D02*
X803449D01*
G01D02*
X805769D01*
X806716Y1120575D01*
X809080D01*
X810712Y1122207D01*
X813412D01*
X814401Y1123196D01*
X814950D01*
G01X823569Y1123220D02*
X824842D01*
X826033Y1122029D01*
X827492D01*
X829108Y1120413D01*
X829880D01*
X830989Y1121522D01*
X833149D01*
G01Y1141601D02*
X833148Y1141602D01*
X826882D01*
X825183Y1139903D01*
X823569D01*
G01X814848Y1139928D02*
X813491D01*
X813026Y1140393D01*
Y1141840D01*
X812286Y1142580D01*
X810415D01*
X809436Y1141601D01*
X803449D01*
G01D02*
X799099D01*
G01X833149Y1134908D02*
X833148Y1134909D01*
X826882D01*
X825183Y1133210D01*
X823569D01*
G01X814848Y1133235D02*
X813491D01*
X813026Y1133700D01*
Y1135147D01*
X812286Y1135887D01*
X810415D01*
X809436Y1134908D01*
X803449D01*
G01D02*
X799099D01*
G01X833149Y1148294D02*
X833148Y1148295D01*
X826882D01*
X825183Y1146596D01*
X823569D01*
G01X814848Y1146621D02*
X813491D01*
X813026Y1147086D01*
Y1148533D01*
X812286Y1149273D01*
X810415D01*
X809436Y1148294D01*
X803449D01*
G01D02*
X799099D01*
G01Y1154987D02*
X803449D01*
G01D02*
X805609D01*
X806718Y1156096D01*
X809615D01*
X811247Y1157728D01*
X813301D01*
X814369Y1156660D01*
X814950D01*
G01X823569Y1156639D02*
X824845D01*
X825756Y1157550D01*
X826957D01*
X828573Y1155934D01*
X829882D01*
X830829Y1154987D01*
X833149D01*
G01X799099Y1158333D02*
X803449D01*
G01D02*
X805769D01*
X806716Y1157386D01*
X809080D01*
X810712Y1159018D01*
X813412D01*
X814401Y1160007D01*
X814950D01*
G01X823569Y1160031D02*
X824842D01*
X826033Y1158840D01*
X827492D01*
X829108Y1157224D01*
X829880D01*
X830989Y1158333D01*
X833149D01*
G01Y1171719D02*
X833148Y1171720D01*
X826882D01*
X825183Y1170021D01*
X823569D01*
G01X814848Y1170046D02*
X813491D01*
X813026Y1170511D01*
Y1171958D01*
X812286Y1172698D01*
X810415D01*
X809436Y1171719D01*
X803449D01*
G01D02*
X799099D01*
G01X833149Y1165026D02*
X833148Y1165027D01*
X826882D01*
X825183Y1163328D01*
X823569D01*
G01X814848Y1163353D02*
X813491D01*
X813026Y1163818D01*
Y1165265D01*
X812286Y1166005D01*
X810415D01*
X809436Y1165026D01*
X803449D01*
G01D02*
X799099D01*
G01X833149Y1185105D02*
X833148Y1185106D01*
X826882D01*
X825183Y1183407D01*
X823569D01*
G01X814848Y1183432D02*
X813491D01*
X813026Y1183897D01*
Y1185344D01*
X812286Y1186084D01*
X810415D01*
X809436Y1185105D01*
X803449D01*
G01D02*
X799099D01*
G01X833149Y1178412D02*
X833148Y1178413D01*
X826882D01*
X825183Y1176714D01*
X823569D01*
G01X814848Y1176739D02*
X813491D01*
X813026Y1177204D01*
Y1178651D01*
X812286Y1179391D01*
X810415D01*
X809436Y1178412D01*
X803449D01*
G01D02*
X799099D01*
G01Y1191798D02*
X803449D01*
G01D02*
X805609D01*
X806718Y1192907D01*
X809615D01*
X811247Y1194539D01*
X813301D01*
X814369Y1193471D01*
X814950D01*
G01X823569Y1193450D02*
X824845D01*
X825756Y1194361D01*
X826957D01*
X828573Y1192745D01*
X829882D01*
X830829Y1191798D01*
X833149D01*
G01Y1208530D02*
X833148Y1208531D01*
X826882D01*
X825183Y1206832D01*
X823569D01*
G01X814848Y1206857D02*
X813491D01*
X813026Y1207322D01*
Y1208769D01*
X812286Y1209509D01*
X810415D01*
X809436Y1208530D01*
X803449D01*
G01D02*
X799099D01*
G01X833149Y1201837D02*
X833148Y1201838D01*
X826882D01*
X825183Y1200139D01*
X823569D01*
G01X814848Y1200164D02*
X813491D01*
X813026Y1200629D01*
Y1202076D01*
X812286Y1202816D01*
X810415D01*
X809436Y1201837D01*
X803449D01*
G01D02*
X799099D01*
G01Y1195144D02*
X803449D01*
G01D02*
X805769D01*
X806716Y1194197D01*
X809080D01*
X810712Y1195829D01*
X813412D01*
X814401Y1196818D01*
X814950D01*
G01X823569Y1196842D02*
X824842D01*
X826033Y1195651D01*
X827492D01*
X829108Y1194035D01*
X829880D01*
X830989Y1195144D01*
X833149D01*
G01Y1221916D02*
X833148Y1221917D01*
X826882D01*
X825183Y1220218D01*
X823569D01*
G01X814848Y1220243D02*
X813491D01*
X813026Y1220708D01*
Y1222155D01*
X812286Y1222895D01*
X810415D01*
X809436Y1221916D01*
X803449D01*
G01D02*
X799099D01*
G01X833149Y1215223D02*
X833148Y1215224D01*
X826882D01*
X825183Y1213525D01*
X823569D01*
G01X814848Y1213550D02*
X813491D01*
X813026Y1214015D01*
Y1215462D01*
X812286Y1216202D01*
X810415D01*
X809436Y1215223D01*
X803449D01*
G01D02*
X799099D01*
G01X833149Y1238648D02*
X833148Y1238649D01*
X826882D01*
X825183Y1236950D01*
X823569D01*
G01X814848Y1236975D02*
X813491D01*
X813026Y1237440D01*
Y1238887D01*
X812286Y1239627D01*
X810415D01*
X809436Y1238648D01*
X803449D01*
G01D02*
X799099D01*
G01Y1228609D02*
X803449D01*
G01D02*
X805609D01*
X806718Y1229718D01*
X809615D01*
X811247Y1231350D01*
X813301D01*
X814369Y1230282D01*
X814950D01*
G01X823569Y1230261D02*
X824845D01*
X825756Y1231172D01*
X826957D01*
X828573Y1229556D01*
X829882D01*
X830829Y1228609D01*
X833149D01*
G01X799099Y1231955D02*
X803449D01*
G01D02*
X805769D01*
X806716Y1231008D01*
X809080D01*
X810712Y1232640D01*
X813412D01*
X814401Y1233629D01*
X814950D01*
G01X823569Y1233653D02*
X824842D01*
X826033Y1232462D01*
X827492D01*
X829108Y1230846D01*
X829880D01*
X830989Y1231955D01*
X833149D01*
G01Y1245341D02*
X833148Y1245342D01*
X826882D01*
X825183Y1243643D01*
X823569D01*
G01X814848Y1243668D02*
X813491D01*
X813026Y1244133D01*
Y1245580D01*
X812286Y1246320D01*
X810415D01*
X809436Y1245341D01*
X803449D01*
G01D02*
X799099D01*
G01X819591Y770144D02*
X826277D01*
X827978Y771845D01*
X829127D01*
G01X837127Y771865D02*
X839809D01*
X840612Y771062D01*
Y770074D01*
X841534Y769152D01*
X843046D01*
X844038Y770144D01*
X849291D01*
G01X815241D02*
X819591D01*
G01X815241Y776837D02*
X819591D01*
G01D02*
X826277D01*
X827978Y778538D01*
X829127D01*
G01X837127Y778558D02*
X839809D01*
X840612Y777755D01*
Y776767D01*
X841534Y775845D01*
X843046D01*
X844038Y776837D01*
X849291D01*
G01X815241Y786877D02*
X819591D01*
G01D02*
X821680D01*
X822748Y785809D01*
X824651D01*
X826324Y784136D01*
X826806D01*
X827898Y785228D01*
X829127D01*
G01X837127Y785247D02*
X838382D01*
X839507Y784122D01*
X841436D01*
X843190Y785876D01*
X846307D01*
X847308Y786877D01*
X849291D01*
G01X815241Y783530D02*
X819591D01*
G01D02*
X821927D01*
X822916Y784519D01*
X824116D01*
X825789Y782846D01*
X826885D01*
X827902Y781829D01*
X829127D01*
G01X837127Y781828D02*
X838394D01*
X839398Y782832D01*
X841971D01*
X843725Y784586D01*
X845999D01*
X847055Y783530D01*
X849291D01*
G01X815241Y800263D02*
X819591D01*
G01D02*
X826277D01*
X827978Y801964D01*
X829127D01*
G01X837127Y801984D02*
X839809D01*
X840612Y801181D01*
Y800193D01*
X841534Y799271D01*
X843046D01*
X844038Y800263D01*
X849291D01*
G01X815241Y793570D02*
X819591D01*
G01D02*
X826277D01*
X827978Y795271D01*
X829127D01*
G01X837127Y795291D02*
X839809D01*
X840612Y794488D01*
Y793500D01*
X841534Y792578D01*
X843046D01*
X844038Y793570D01*
X849291D01*
G01X815241Y813648D02*
X819591D01*
G01D02*
X826277D01*
X827978Y815349D01*
X829127D01*
G01X837127Y815369D02*
X839809D01*
X840612Y814566D01*
Y813578D01*
X841534Y812656D01*
X843046D01*
X844038Y813648D01*
X849291D01*
G01X815241Y806955D02*
X819591D01*
G01D02*
X826277D01*
X827978Y808656D01*
X829127D01*
G01X837127Y808676D02*
X839809D01*
X840612Y807873D01*
Y806885D01*
X841534Y805963D01*
X843046D01*
X844038Y806955D01*
X849291D01*
G01X819591Y820341D02*
X821927D01*
X822916Y821330D01*
X824116D01*
X825789Y819657D01*
X826885D01*
X827902Y818640D01*
X829127D01*
G01X837127Y818639D02*
X838394D01*
X839398Y819643D01*
X841971D01*
X843725Y821397D01*
X845999D01*
X847055Y820341D01*
X849291D01*
G01X815241Y830381D02*
X819591D01*
G01D02*
X826277D01*
X827978Y832082D01*
X829127D01*
G01X837127Y832102D02*
X839809D01*
X840612Y831299D01*
Y830311D01*
X841534Y829389D01*
X843046D01*
X844038Y830381D01*
X849291D01*
G01X815241Y823688D02*
X819591D01*
G01D02*
X821680D01*
X822748Y822620D01*
X824651D01*
X826324Y820947D01*
X826806D01*
X827898Y822039D01*
X829127D01*
G01X837127Y822058D02*
X838382D01*
X839507Y820933D01*
X841436D01*
X843190Y822687D01*
X846307D01*
X847308Y823688D01*
X849291D01*
G01X815241Y820341D02*
X819591D01*
G01X815241Y850459D02*
X819591D01*
G01D02*
X826277D01*
X827978Y852160D01*
X829127D01*
G01X837127Y852180D02*
X839809D01*
X840612Y851377D01*
Y850389D01*
X841534Y849467D01*
X843046D01*
X844038Y850459D01*
X849291D01*
G01X815241Y843766D02*
X819591D01*
G01D02*
X826277D01*
X827978Y845467D01*
X829127D01*
G01X837127Y845487D02*
X839809D01*
X840612Y844684D01*
Y843696D01*
X841534Y842774D01*
X843046D01*
X844038Y843766D01*
X849291D01*
G01X815241Y837074D02*
X819591D01*
G01D02*
X826277D01*
X827978Y838775D01*
X829127D01*
G01X837127Y838795D02*
X839809D01*
X840612Y837992D01*
Y837004D01*
X841534Y836082D01*
X843046D01*
X844038Y837074D01*
X849291D01*
G01X815241Y867192D02*
X819591D01*
G01D02*
X826277D01*
X827978Y868893D01*
X829127D01*
G01X837127Y868913D02*
X839809D01*
X840612Y868110D01*
Y867122D01*
X841534Y866200D01*
X843046D01*
X844038Y867192D01*
X849291D01*
G01X815241Y860499D02*
X819591D01*
G01D02*
X821680D01*
X822748Y859431D01*
X824651D01*
X826324Y857758D01*
X826806D01*
X827898Y858850D01*
X829127D01*
G01X837127Y858869D02*
X838382D01*
X839507Y857744D01*
X841436D01*
X843190Y859498D01*
X846307D01*
X847308Y860499D01*
X849291D01*
G01X815241Y857152D02*
X819591D01*
G01D02*
X821927D01*
X822916Y858141D01*
X824116D01*
X825789Y856468D01*
X826885D01*
X827902Y855451D01*
X829127D01*
G01X837127Y855450D02*
X838394D01*
X839398Y856454D01*
X841971D01*
X843725Y858208D01*
X845999D01*
X847055Y857152D01*
X849291D01*
G01X815241Y873885D02*
X819591D01*
G01D02*
X826277D01*
X827978Y875586D01*
X829127D01*
G01X837127Y875606D02*
X839809D01*
X840612Y874803D01*
Y873815D01*
X841534Y872893D01*
X843046D01*
X844038Y873885D01*
X849291D01*
G01X815241Y880577D02*
X819591D01*
G01D02*
X826277D01*
X827978Y882278D01*
X829127D01*
G01X837127Y882298D02*
X839809D01*
X840612Y881495D01*
Y880507D01*
X841534Y879585D01*
X843046D01*
X844038Y880577D01*
X849291D01*
G01X815241Y887270D02*
X819591D01*
G01D02*
X826277D01*
X827978Y888971D01*
X829127D01*
G01X837127Y888991D02*
X839809D01*
X840612Y888188D01*
Y887200D01*
X841534Y886278D01*
X843046D01*
X844038Y887270D01*
X849291D01*
G01X815241Y897310D02*
X819591D01*
G01D02*
X821680D01*
X822748Y896242D01*
X824651D01*
X826324Y894569D01*
X826806D01*
X827898Y895661D01*
X829127D01*
G01X837127Y895680D02*
X838382D01*
X839507Y894555D01*
X841436D01*
X843190Y896309D01*
X846307D01*
X847308Y897310D01*
X849291D01*
G01X815241Y893963D02*
X819591D01*
G01D02*
X821927D01*
X822916Y894952D01*
X824116D01*
X825789Y893279D01*
X826885D01*
X827902Y892262D01*
X829127D01*
G01X837127Y892261D02*
X838394D01*
X839398Y893265D01*
X841971D01*
X843725Y895019D01*
X845999D01*
X847055Y893963D01*
X849291D01*
G01X815241Y910696D02*
X819591D01*
G01D02*
X826277D01*
X827978Y912397D01*
X829127D01*
G01X837127Y912417D02*
X839809D01*
X840612Y911614D01*
Y910626D01*
X841534Y909704D01*
X843046D01*
X844038Y910696D01*
X849291D01*
G01X815241Y904003D02*
X819591D01*
G01D02*
X826277D01*
X827978Y905704D01*
X829127D01*
G01X837127Y905724D02*
X839809D01*
X840612Y904921D01*
Y903933D01*
X841534Y903011D01*
X843046D01*
X844038Y904003D01*
X849291D01*
G01X815241Y924081D02*
X819591D01*
G01D02*
X826277D01*
X827978Y925782D01*
X829127D01*
G01X837127Y925802D02*
X839809D01*
X840612Y924999D01*
Y924011D01*
X841534Y923089D01*
X843046D01*
X844038Y924081D01*
X849291D01*
G01X815241Y917389D02*
X819591D01*
G01D02*
X826277D01*
X827978Y919090D01*
X829127D01*
G01X837127Y919110D02*
X839809D01*
X840612Y918307D01*
Y917319D01*
X841534Y916397D01*
X843046D01*
X844038Y917389D01*
X849291D01*
G01X819591Y934121D02*
X821680D01*
X822748Y933053D01*
X824651D01*
X826324Y931380D01*
X826806D01*
X827898Y932472D01*
X829127D01*
G01X837127Y932491D02*
X838382D01*
X839507Y931366D01*
X841436D01*
X843190Y933120D01*
X846307D01*
X847308Y934121D01*
X849291D01*
G01X815241Y930774D02*
X819591D01*
G01D02*
X821927D01*
X822916Y931763D01*
X824116D01*
X825789Y930090D01*
X826885D01*
X827902Y929073D01*
X829127D01*
G01X837127Y929072D02*
X838394D01*
X839398Y930076D01*
X841971D01*
X843725Y931830D01*
X845999D01*
X847055Y930774D01*
X849291D01*
G01X815241Y947507D02*
X819591D01*
G01D02*
X826277D01*
X827978Y949208D01*
X829127D01*
G01X837127Y949228D02*
X839809D01*
X840612Y948425D01*
Y947437D01*
X841534Y946515D01*
X843046D01*
X844038Y947507D01*
X849291D01*
G01X815241Y940814D02*
X819591D01*
G01D02*
X826277D01*
X827978Y942515D01*
X829127D01*
G01X837127Y942535D02*
X839809D01*
X840612Y941732D01*
Y940744D01*
X841534Y939822D01*
X843046D01*
X844038Y940814D01*
X849291D01*
G01X815241Y934121D02*
X819591D01*
G01Y964239D02*
X815241D01*
G01Y977625D02*
X819591D01*
G01D02*
X826031D01*
X827746Y979340D01*
X829127D01*
G01X837127Y979327D02*
X838206D01*
X841611Y975922D01*
X843200D01*
X844903Y977625D01*
X849291D01*
G01X815241Y970932D02*
X819591D01*
G01D02*
X826031D01*
X827746Y972647D01*
X829127D01*
G01X837127Y972634D02*
X838206D01*
X841611Y969229D01*
X843200D01*
X844903Y970932D01*
X849291D01*
G01X815241Y991011D02*
X819591D01*
G01D02*
X826031D01*
X827746Y992726D01*
X829127D01*
G01X837127Y992713D02*
X838206D01*
X841611Y989308D01*
X843200D01*
X844903Y991011D01*
X849291D01*
G01X815241Y984318D02*
X819591D01*
G01D02*
X826031D01*
X827746Y986033D01*
X829127D01*
G01X837127Y986020D02*
X838206D01*
X841611Y982615D01*
X843200D01*
X844903Y984318D01*
X849291D01*
G01X815241Y1021129D02*
X819591D01*
G01Y1024475D02*
X815241D01*
G01Y1044554D02*
X819591D01*
G01D02*
X826031D01*
X827746Y1046269D01*
X829127D01*
G01X837127Y1046256D02*
X838206D01*
X841611Y1042851D01*
X843200D01*
X844903Y1044554D01*
X849291D01*
G01X815241Y1037861D02*
X819591D01*
G01D02*
X826031D01*
X827746Y1039576D01*
X829127D01*
G01X837127Y1039563D02*
X838206D01*
X841611Y1036158D01*
X843200D01*
X844903Y1037861D01*
X849291D01*
G01X815241Y1031168D02*
X819591D01*
G01D02*
X826031D01*
X827746Y1032883D01*
X829127D01*
G01X837127Y1032870D02*
X838206D01*
X841611Y1029465D01*
X843200D01*
X844903Y1031168D01*
X849291D01*
G01X819591Y1051247D02*
X814941D01*
G01X815241Y1071325D02*
X815242Y1071326D01*
X819591D01*
G01D02*
X826277D01*
X827978Y1073027D01*
X829127D01*
G01X837127Y1073047D02*
X839809D01*
X840612Y1072244D01*
Y1071256D01*
X841534Y1070334D01*
X843046D01*
X844038Y1071326D01*
X849291D01*
G01X815241Y1064633D02*
X819591D01*
G01D02*
X826277D01*
X827978Y1066334D01*
X829127D01*
G01X837127Y1066354D02*
X839809D01*
X840612Y1065551D01*
Y1064563D01*
X841534Y1063641D01*
X843046D01*
X844038Y1064633D01*
X849291D01*
G01X819591Y1081365D02*
X821680D01*
X822748Y1080297D01*
X824651D01*
X826324Y1078624D01*
X826806D01*
X827898Y1079716D01*
X829127D01*
G01X837127Y1079735D02*
X838382D01*
X839507Y1078610D01*
X841436D01*
X843190Y1080364D01*
X846307D01*
X847308Y1081365D01*
X849291D01*
G01X815241Y1078018D02*
X819591D01*
G01D02*
X821927D01*
X822916Y1079007D01*
X824116D01*
X825789Y1077334D01*
X826885D01*
X827902Y1076317D01*
X829127D01*
G01X837127Y1076316D02*
X838394D01*
X839398Y1077320D01*
X841971D01*
X843725Y1079074D01*
X845999D01*
X847055Y1078018D01*
X849291D01*
G01X815241Y1094751D02*
X819591D01*
G01D02*
X826277D01*
X827978Y1096452D01*
X829127D01*
G01X837127Y1096472D02*
X839809D01*
X840612Y1095669D01*
Y1094681D01*
X841534Y1093759D01*
X843046D01*
X844038Y1094751D01*
X849291D01*
G01X815241Y1088058D02*
X819591D01*
G01D02*
X826277D01*
X827978Y1089759D01*
X829127D01*
G01X837127Y1089779D02*
X839809D01*
X840612Y1088976D01*
Y1087988D01*
X841534Y1087066D01*
X843046D01*
X844038Y1088058D01*
X849291D01*
G01X815241Y1081365D02*
X819591D01*
G01X815241Y1108136D02*
X815242Y1108137D01*
X819591D01*
G01D02*
X826277D01*
X827978Y1109838D01*
X829127D01*
G01X837127Y1109858D02*
X839809D01*
X840612Y1109055D01*
Y1108067D01*
X841534Y1107145D01*
X843046D01*
X844038Y1108137D01*
X849291D01*
G01X815241Y1101444D02*
X819591D01*
G01D02*
X826277D01*
X827978Y1103145D01*
X829127D01*
G01X837127Y1103165D02*
X839809D01*
X840612Y1102362D01*
Y1101374D01*
X841534Y1100452D01*
X843046D01*
X844038Y1101444D01*
X849291D01*
G01X815241Y1124869D02*
X819591D01*
G01D02*
X826277D01*
X827978Y1126570D01*
X829127D01*
G01X837127Y1126590D02*
X839809D01*
X840612Y1125787D01*
Y1124799D01*
X841534Y1123877D01*
X843046D01*
X844038Y1124869D01*
X849291D01*
G01X815241Y1118176D02*
X819591D01*
G01D02*
X821680D01*
X822748Y1117108D01*
X824651D01*
X826324Y1115435D01*
X826806D01*
X827898Y1116527D01*
X829127D01*
G01X837127Y1116546D02*
X838382D01*
X839507Y1115421D01*
X841436D01*
X843190Y1117175D01*
X846307D01*
X847308Y1118176D01*
X849291D01*
G01X815241Y1114829D02*
X819591D01*
G01D02*
X821927D01*
X822916Y1115818D01*
X824116D01*
X825789Y1114145D01*
X826885D01*
X827902Y1113128D01*
X829127D01*
G01X837127Y1113127D02*
X838394D01*
X839398Y1114131D01*
X841971D01*
X843725Y1115885D01*
X845999D01*
X847055Y1114829D01*
X849291D01*
G01X815241Y1144947D02*
X815242Y1144948D01*
X819591D01*
G01X815241Y1138255D02*
X819591D01*
G01D02*
X826277D01*
X827978Y1139956D01*
X829127D01*
G01X837127Y1139976D02*
X839809D01*
X840612Y1139173D01*
Y1138185D01*
X841534Y1137263D01*
X843046D01*
X844038Y1138255D01*
X849291D01*
G01X815241Y1131562D02*
X819591D01*
G01D02*
X826277D01*
X827978Y1133263D01*
X829127D01*
G01X837127Y1133283D02*
X839809D01*
X840612Y1132480D01*
Y1131492D01*
X841534Y1130570D01*
X843046D01*
X844038Y1131562D01*
X849291D01*
G01X819591Y1144948D02*
X826277D01*
X827978Y1146649D01*
X829127D01*
G01X837127Y1146669D02*
X839809D01*
X840612Y1145866D01*
Y1144878D01*
X841534Y1143956D01*
X843046D01*
X844038Y1144948D01*
X849291D01*
G01X815241Y1154987D02*
X819591D01*
G01D02*
X821680D01*
X822748Y1153919D01*
X824651D01*
X826324Y1152246D01*
X826806D01*
X827898Y1153338D01*
X829127D01*
G01X837127Y1153357D02*
X838382D01*
X839507Y1152232D01*
X841436D01*
X843190Y1153986D01*
X846307D01*
X847308Y1154987D01*
X849291D01*
G01X815241Y1151640D02*
X815242Y1151641D01*
X819591D01*
G01D02*
X821928D01*
X822916Y1152629D01*
X824116D01*
X825789Y1150956D01*
X826885D01*
X827901Y1149940D01*
X829127D01*
G01X837127Y1149939D02*
X838395D01*
X839398Y1150942D01*
X841971D01*
X843725Y1152696D01*
X845999D01*
X847054Y1151641D01*
X849291D01*
G01X815241Y1175066D02*
X819591D01*
G01D02*
X826277D01*
X827978Y1176767D01*
X829127D01*
G01X837127Y1176787D02*
X839809D01*
X840612Y1175984D01*
Y1174996D01*
X841534Y1174074D01*
X843046D01*
X844038Y1175066D01*
X849291D01*
G01X815241Y1168373D02*
X819591D01*
G01D02*
X826277D01*
X827978Y1170074D01*
X829127D01*
G01X837127Y1170094D02*
X839809D01*
X840612Y1169291D01*
Y1168303D01*
X841534Y1167381D01*
X843046D01*
X844038Y1168373D01*
X849291D01*
G01X815241Y1161680D02*
X819591D01*
G01D02*
X826277D01*
X827978Y1163381D01*
X829127D01*
G01X837127Y1163401D02*
X839809D01*
X840612Y1162598D01*
Y1161610D01*
X841534Y1160688D01*
X843046D01*
X844038Y1161680D01*
X849291D01*
G01X815241Y1181758D02*
X819590D01*
X819591Y1181759D01*
G01D02*
X826277D01*
X827978Y1183460D01*
X829127D01*
G01X837127Y1183480D02*
X839809D01*
X840612Y1182677D01*
Y1181689D01*
X841534Y1180767D01*
X843046D01*
X844038Y1181759D01*
X849291D01*
G01X815241Y1191798D02*
X819591D01*
G01D02*
X821680D01*
X822748Y1190730D01*
X824651D01*
X826324Y1189057D01*
X826806D01*
X827898Y1190149D01*
X829127D01*
G01X837127Y1190168D02*
X838382D01*
X839507Y1189043D01*
X841436D01*
X843190Y1190797D01*
X846307D01*
X847308Y1191798D01*
X849291D01*
G01X815241Y1188451D02*
X815242Y1188452D01*
X819591D01*
G01D02*
X821928D01*
X822916Y1189440D01*
X824116D01*
X825789Y1187767D01*
X826885D01*
X827901Y1186751D01*
X829127D01*
G01X837127Y1186750D02*
X838395D01*
X839398Y1187753D01*
X841971D01*
X843725Y1189507D01*
X845999D01*
X847054Y1188452D01*
X849291D01*
G01X815241Y1205184D02*
X819591D01*
G01D02*
X826277D01*
X827978Y1206885D01*
X829127D01*
G01X837127Y1206905D02*
X839809D01*
X840612Y1206102D01*
Y1205114D01*
X841534Y1204192D01*
X843046D01*
X844038Y1205184D01*
X849291D01*
G01X815241Y1198491D02*
X819591D01*
G01D02*
X826277D01*
X827978Y1200192D01*
X829127D01*
G01X837127Y1200212D02*
X839809D01*
X840612Y1199409D01*
Y1198421D01*
X841534Y1197499D01*
X843046D01*
X844038Y1198491D01*
X849291D01*
G01X815241Y1218570D02*
X819591D01*
G01D02*
X826277D01*
X827978Y1220271D01*
X829127D01*
G01X837127Y1220291D02*
X839809D01*
X840612Y1219488D01*
Y1218500D01*
X841534Y1217578D01*
X843046D01*
X844038Y1218570D01*
X849291D01*
G01X815241Y1211877D02*
X819591D01*
G01D02*
X826277D01*
X827978Y1213578D01*
X829127D01*
G01X837127Y1213598D02*
X839809D01*
X840612Y1212795D01*
Y1211807D01*
X841534Y1210885D01*
X843046D01*
X844038Y1211877D01*
X849291D01*
G01X819591Y1228609D02*
X821680D01*
X822748Y1227541D01*
X824651D01*
X826324Y1225868D01*
X826806D01*
X827898Y1226960D01*
X829127D01*
G01X837127Y1226979D02*
X838382D01*
X839507Y1225854D01*
X841436D01*
X843190Y1227608D01*
X846307D01*
X847308Y1228609D01*
X849291D01*
G01X815241Y1225263D02*
X819591D01*
G01D02*
X821928D01*
X822916Y1226251D01*
X824116D01*
X825789Y1224578D01*
X826885D01*
X827901Y1223562D01*
X829127D01*
G01X837127Y1223561D02*
X838395D01*
X839398Y1224564D01*
X841971D01*
X843725Y1226318D01*
X845999D01*
X847054Y1225263D01*
X849291D01*
G01X815241Y1241995D02*
X819591D01*
G01D02*
X826277D01*
X827978Y1243696D01*
X829127D01*
G01X837127Y1243716D02*
X839809D01*
X840612Y1242913D01*
Y1241925D01*
X841534Y1241003D01*
X843046D01*
X844038Y1241995D01*
X849291D01*
G01X815241Y1235302D02*
X819591D01*
G01D02*
X826277D01*
X827978Y1237003D01*
X829127D01*
G01X837127Y1237023D02*
X839809D01*
X840612Y1236220D01*
Y1235232D01*
X841534Y1234310D01*
X843046D01*
X844038Y1235302D01*
X849291D01*
G01X815241Y1228609D02*
X819591D01*
G01X828799Y960892D02*
X833149D01*
G01Y957546D02*
X828799D01*
G01X833149Y967585D02*
X828799D01*
G01X833149Y1054593D02*
X828799D01*
G01X849291Y964239D02*
X844941D01*
G01Y1021129D02*
X849291D01*
G01Y1024475D02*
X844941D01*
G01X849291Y1051247D02*
X844941D01*
G01X1037891Y780184D02*
X1032501D01*
X1030828Y778511D01*
X1029061D01*
G01X1019907Y778479D02*
X1017695D01*
X1016870Y779304D01*
Y780444D01*
X1016190Y781124D01*
X1014384D01*
X1013444Y780184D01*
X1008191D01*
G01X1037891Y773491D02*
X1031437D01*
X1029764Y771818D01*
X1029061D01*
G01X1019907Y771783D02*
X1017510D01*
X1016870Y772423D01*
Y773715D01*
X1016262Y774323D01*
X1014276D01*
X1013444Y773491D01*
X1008191D01*
G01X1037891Y786877D02*
X1035739D01*
X1034711Y787905D01*
X1033110D01*
X1031436Y789579D01*
X1030701D01*
X1029672Y788550D01*
X1029061D01*
G01X1019907Y788508D02*
X1019103D01*
X1018032Y789579D01*
X1015906D01*
X1013402Y787905D01*
X1011379D01*
X1010351Y786877D01*
X1008191D01*
G01X1037891Y803609D02*
X1032501D01*
X1030828Y801936D01*
X1029061D01*
G01X1019907Y801904D02*
X1017695D01*
X1016870Y802729D01*
Y803869D01*
X1016190Y804549D01*
X1014384D01*
X1013444Y803609D01*
X1008191D01*
G01X1037891Y796916D02*
X1031437D01*
X1029764Y795243D01*
X1029061D01*
G01X1019907Y795208D02*
X1017510D01*
X1016870Y795848D01*
Y797140D01*
X1016262Y797748D01*
X1014276D01*
X1013444Y796916D01*
X1008191D01*
G01X1037891Y790223D02*
X1035731D01*
X1034703Y789195D01*
X1033645D01*
X1031971Y790869D01*
X1030688D01*
X1029660Y791897D01*
X1029061D01*
G01X1019907Y791934D02*
X1019048D01*
X1017983Y790869D01*
X1015514D01*
X1013010Y789195D01*
X1011337D01*
X1010309Y790223D01*
X1008191D01*
G01X1037891Y816995D02*
X1032501D01*
X1030828Y815322D01*
X1029061D01*
G01X1019907Y815290D02*
X1017695D01*
X1016870Y816115D01*
Y817255D01*
X1016190Y817935D01*
X1014384D01*
X1013444Y816995D01*
X1008191D01*
G01X1037891Y810302D02*
X1031437D01*
X1029764Y808629D01*
X1029061D01*
G01X1019907Y808594D02*
X1017510D01*
X1016870Y809234D01*
Y810526D01*
X1016262Y811134D01*
X1014276D01*
X1013444Y810302D01*
X1008191D01*
G01X1037891Y833727D02*
X1031437D01*
X1029764Y832054D01*
X1029061D01*
G01X1019907Y832019D02*
X1017510D01*
X1016870Y832659D01*
Y833951D01*
X1016262Y834559D01*
X1014276D01*
X1013444Y833727D01*
X1008191D01*
G01X1037891Y823688D02*
X1035739D01*
X1034711Y824716D01*
X1033110D01*
X1031436Y826390D01*
X1030701D01*
X1029672Y825361D01*
X1029061D01*
G01X1019907Y825319D02*
X1019103D01*
X1018032Y826390D01*
X1015906D01*
X1013402Y824716D01*
X1011379D01*
X1010351Y823688D01*
X1008191D01*
G01X1037891Y827034D02*
X1035731D01*
X1034703Y826006D01*
X1033645D01*
X1031971Y827680D01*
X1030688D01*
X1029660Y828708D01*
X1029061D01*
G01X1019907Y828745D02*
X1019048D01*
X1017983Y827680D01*
X1015514D01*
X1013010Y826006D01*
X1011337D01*
X1010309Y827034D01*
X1008191D01*
G01X1037891Y853806D02*
X1032501D01*
X1030828Y852133D01*
X1029061D01*
G01X1019907Y852101D02*
X1017695D01*
X1016870Y852926D01*
Y854066D01*
X1016190Y854746D01*
X1014384D01*
X1013444Y853806D01*
X1008191D01*
G01X1037891Y847113D02*
X1031437D01*
X1029764Y845440D01*
X1029061D01*
G01X1019907Y845405D02*
X1017510D01*
X1016870Y846045D01*
Y847337D01*
X1016262Y847945D01*
X1014276D01*
X1013444Y847113D01*
X1008191D01*
G01X1037891Y840420D02*
X1032501D01*
X1030828Y838747D01*
X1029061D01*
G01X1019907Y838715D02*
X1017695D01*
X1016870Y839540D01*
Y840680D01*
X1016190Y841360D01*
X1014384D01*
X1013444Y840420D01*
X1008191D01*
G01X1037891Y860499D02*
X1035739D01*
X1034711Y861527D01*
X1033110D01*
X1031436Y863201D01*
X1030701D01*
X1029672Y862172D01*
X1029061D01*
G01X1019907Y862130D02*
X1019103D01*
X1018032Y863201D01*
X1015906D01*
X1013402Y861527D01*
X1011379D01*
X1010351Y860499D01*
X1008191D01*
G01X1037891Y863845D02*
X1035731D01*
X1034703Y862817D01*
X1033645D01*
X1031971Y864491D01*
X1030688D01*
X1029660Y865519D01*
X1029061D01*
G01X1019907Y865556D02*
X1019048D01*
X1017983Y864491D01*
X1015514D01*
X1013010Y862817D01*
X1011337D01*
X1010309Y863845D01*
X1008191D01*
G01X1037891Y883924D02*
X1031437D01*
X1029764Y882251D01*
X1029061D01*
G01X1019907Y882216D02*
X1017510D01*
X1016870Y882856D01*
Y884148D01*
X1016262Y884756D01*
X1014276D01*
X1013444Y883924D01*
X1008191D01*
G01X1037891Y877231D02*
X1032501D01*
X1030828Y875558D01*
X1029061D01*
G01X1019907Y875526D02*
X1017695D01*
X1016870Y876351D01*
Y877491D01*
X1016190Y878171D01*
X1014384D01*
X1013444Y877231D01*
X1008191D01*
G01X1037891Y870538D02*
X1031437D01*
X1029764Y868865D01*
X1029061D01*
G01X1019907Y868830D02*
X1017510D01*
X1016870Y869470D01*
Y870762D01*
X1016262Y871370D01*
X1014276D01*
X1013444Y870538D01*
X1008191D01*
G01X1037891Y890617D02*
X1032501D01*
X1030828Y888944D01*
X1029061D01*
G01X1019907Y888912D02*
X1017695D01*
X1016870Y889737D01*
Y890877D01*
X1016190Y891557D01*
X1014384D01*
X1013444Y890617D01*
X1008191D01*
G01X1037891Y897310D02*
X1035739D01*
X1034711Y898338D01*
X1033110D01*
X1031436Y900012D01*
X1030701D01*
X1029672Y898983D01*
X1029061D01*
G01X1019907Y898941D02*
X1019103D01*
X1018032Y900012D01*
X1015906D01*
X1013402Y898338D01*
X1011379D01*
X1010351Y897310D01*
X1008191D01*
G01X1037891Y900656D02*
X1035731D01*
X1034703Y899628D01*
X1033645D01*
X1031971Y901302D01*
X1030688D01*
X1029660Y902330D01*
X1029061D01*
G01X1019907Y902367D02*
X1019048D01*
X1017983Y901302D01*
X1015514D01*
X1013010Y899628D01*
X1011337D01*
X1010309Y900656D01*
X1008191D01*
G01X1037891Y914042D02*
X1032501D01*
X1030828Y912369D01*
X1029061D01*
G01X1019907Y912337D02*
X1017695D01*
X1016870Y913162D01*
Y914302D01*
X1016190Y914982D01*
X1014384D01*
X1013444Y914042D01*
X1008191D01*
G01X1037891Y907349D02*
X1031437D01*
X1029764Y905676D01*
X1029061D01*
G01X1019907Y905641D02*
X1017510D01*
X1016870Y906281D01*
Y907573D01*
X1016262Y908181D01*
X1014276D01*
X1013444Y907349D01*
X1008191D01*
G01X1037891Y927428D02*
X1032501D01*
X1030828Y925755D01*
X1029061D01*
G01X1019907Y925723D02*
X1017695D01*
X1016870Y926548D01*
Y927688D01*
X1016190Y928368D01*
X1014384D01*
X1013444Y927428D01*
X1008191D01*
G01X1037891Y920735D02*
X1031437D01*
X1029764Y919062D01*
X1029061D01*
G01X1019907Y919027D02*
X1017510D01*
X1016870Y919667D01*
Y920959D01*
X1016262Y921567D01*
X1014276D01*
X1013444Y920735D01*
X1008191D01*
G01X1037891Y950853D02*
X1032501D01*
X1030828Y949180D01*
X1029061D01*
G01X1019907Y949148D02*
X1017695D01*
X1016870Y949973D01*
Y951113D01*
X1016190Y951793D01*
X1014384D01*
X1013444Y950853D01*
X1008191D01*
G01X1037891Y944160D02*
X1031437D01*
X1029764Y942487D01*
X1029061D01*
G01X1019907Y942452D02*
X1017510D01*
X1016870Y943092D01*
Y944384D01*
X1016262Y944992D01*
X1014276D01*
X1013444Y944160D01*
X1008191D01*
G01X1037891Y934121D02*
X1035739D01*
X1034711Y935149D01*
X1033110D01*
X1031436Y936823D01*
X1030701D01*
X1029672Y935794D01*
X1029061D01*
G01X1019907Y935752D02*
X1019103D01*
X1018032Y936823D01*
X1015906D01*
X1013402Y935149D01*
X1011379D01*
X1010351Y934121D01*
X1008191D01*
G01X1037891Y937467D02*
X1035731D01*
X1034703Y936439D01*
X1033645D01*
X1031971Y938113D01*
X1030688D01*
X1029660Y939141D01*
X1029061D01*
G01X1019907Y939178D02*
X1019048D01*
X1017983Y938113D01*
X1015514D01*
X1013010Y936439D01*
X1011337D01*
X1010309Y937467D01*
X1008191D01*
G01X1012541Y960892D02*
X1008191D01*
G01X1012541Y957546D02*
X1008191D01*
G01X1037891Y980971D02*
X1031437D01*
X1029764Y979298D01*
X1029061D01*
G01X1019907Y979263D02*
X1017510D01*
X1016870Y979903D01*
Y981195D01*
X1016262Y981803D01*
X1014276D01*
X1013444Y980971D01*
X1008191D01*
G01X1037891Y974278D02*
X1031437D01*
X1029764Y972605D01*
X1029061D01*
G01X1019907Y972570D02*
X1017510D01*
X1016870Y973210D01*
Y974502D01*
X1016262Y975110D01*
X1014276D01*
X1013444Y974278D01*
X1008191D01*
G01X1012541Y967585D02*
X1008191D01*
G01X1037891Y994357D02*
X1031437D01*
X1029764Y992684D01*
X1029061D01*
G01X1019907Y992649D02*
X1017510D01*
X1016870Y993289D01*
Y994581D01*
X1016262Y995189D01*
X1014276D01*
X1013444Y994357D01*
X1008191D01*
G01X1037891Y987664D02*
X1031437D01*
X1029764Y985991D01*
X1029061D01*
G01X1019907Y985956D02*
X1017510D01*
X1016870Y986596D01*
Y987888D01*
X1016262Y988496D01*
X1014276D01*
X1013444Y987664D01*
X1008191D01*
G01X1037891Y1027822D02*
X1031437D01*
X1029764Y1026149D01*
X1029061D01*
G01X1019907Y1026114D02*
X1017510D01*
X1016870Y1026754D01*
Y1028046D01*
X1016262Y1028654D01*
X1014276D01*
X1013444Y1027822D01*
X1008191D01*
G01X1037891Y1021129D02*
X1031173D01*
X1029500Y1019456D01*
X1029061D01*
G01X1019907Y1019510D02*
X1017423D01*
X1017422Y1019509D01*
X1016870Y1020061D01*
Y1021269D01*
X1016069Y1022070D01*
X1014385D01*
X1013444Y1021129D01*
X1008191D01*
G01X1037891Y1047900D02*
X1031437D01*
X1029764Y1046227D01*
X1029061D01*
G01X1019907Y1046192D02*
X1017510D01*
X1016870Y1046832D01*
Y1048124D01*
X1016262Y1048732D01*
X1014276D01*
X1013444Y1047900D01*
X1008191D01*
G01X1037891Y1041207D02*
X1031437D01*
X1029764Y1039534D01*
X1029061D01*
G01X1019907Y1039499D02*
X1017510D01*
X1016870Y1040139D01*
Y1041431D01*
X1016262Y1042039D01*
X1014276D01*
X1013444Y1041207D01*
X1008191D01*
G01X1037891Y1034515D02*
X1031437D01*
X1029764Y1032842D01*
X1029061D01*
G01X1019907Y1032807D02*
X1017510D01*
X1016870Y1033447D01*
Y1034739D01*
X1016262Y1035347D01*
X1014276D01*
X1013444Y1034515D01*
X1008191D01*
G01X1037891Y1061286D02*
X1031537D01*
X1029864Y1059613D01*
X1029061D01*
G01X1019907Y1059578D02*
X1017510D01*
X1016870Y1060218D01*
Y1061510D01*
X1016262Y1062118D01*
X1014276D01*
X1013444Y1061286D01*
X1008191D01*
G01X1012541Y1054593D02*
X1008191D01*
G01X1037891Y1074672D02*
X1032501D01*
X1030828Y1072999D01*
X1029061D01*
G01X1019907Y1072967D02*
X1017695D01*
X1016870Y1073792D01*
Y1074932D01*
X1016190Y1075612D01*
X1014384D01*
X1013444Y1074672D01*
X1008191D01*
G01X1037891Y1067979D02*
X1031437D01*
X1029764Y1066306D01*
X1029061D01*
G01X1019907Y1066271D02*
X1017510D01*
X1016870Y1066911D01*
Y1068203D01*
X1016262Y1068811D01*
X1014276D01*
X1013444Y1067979D01*
X1008191D01*
G01X1037891Y1091404D02*
X1031437D01*
X1029764Y1089731D01*
X1029061D01*
G01X1019907Y1089696D02*
X1017510D01*
X1016870Y1090336D01*
Y1091628D01*
X1016262Y1092236D01*
X1014276D01*
X1013444Y1091404D01*
X1008191D01*
G01X1037891Y1081365D02*
X1035739D01*
X1034711Y1082393D01*
X1033110D01*
X1031436Y1084067D01*
X1030701D01*
X1029672Y1083038D01*
X1029061D01*
G01X1019907Y1082996D02*
X1019103D01*
X1018032Y1084067D01*
X1015906D01*
X1013402Y1082393D01*
X1011379D01*
X1010351Y1081365D01*
X1008191D01*
G01X1037891Y1084711D02*
X1035731D01*
X1034703Y1083683D01*
X1033645D01*
X1031971Y1085357D01*
X1030688D01*
X1029660Y1086385D01*
X1029061D01*
G01X1019907Y1086422D02*
X1019048D01*
X1017983Y1085357D01*
X1015514D01*
X1013010Y1083683D01*
X1011337D01*
X1010309Y1084711D01*
X1008191D01*
G01X1037891Y1098097D02*
X1032501D01*
X1030828Y1096424D01*
X1029061D01*
G01X1019907Y1096392D02*
X1017695D01*
X1016870Y1097217D01*
Y1098357D01*
X1016190Y1099037D01*
X1014384D01*
X1013444Y1098097D01*
X1008191D01*
G01X1037891Y1111483D02*
X1032501D01*
X1030828Y1109810D01*
X1029061D01*
G01X1019907Y1109778D02*
X1017695D01*
X1016870Y1110603D01*
Y1111743D01*
X1016190Y1112423D01*
X1014384D01*
X1013444Y1111483D01*
X1008191D01*
G01X1037891Y1104790D02*
X1031437D01*
X1029764Y1103117D01*
X1029061D01*
G01X1019907Y1103082D02*
X1017510D01*
X1016870Y1103722D01*
Y1105014D01*
X1016262Y1105622D01*
X1014276D01*
X1013444Y1104790D01*
X1008191D01*
G01X1037891Y1128215D02*
X1031437D01*
X1029764Y1126542D01*
X1029061D01*
G01X1019907Y1126507D02*
X1017510D01*
X1016870Y1127147D01*
Y1128439D01*
X1016262Y1129047D01*
X1014276D01*
X1013444Y1128215D01*
X1008191D01*
G01X1037891Y1118176D02*
X1035739D01*
X1034711Y1119204D01*
X1033110D01*
X1031436Y1120878D01*
X1030701D01*
X1029672Y1119849D01*
X1029061D01*
G01X1019907Y1119807D02*
X1019103D01*
X1018032Y1120878D01*
X1015906D01*
X1013402Y1119204D01*
X1011379D01*
X1010351Y1118176D01*
X1008191D01*
G01X1037891Y1121522D02*
X1035731D01*
X1034703Y1120494D01*
X1033645D01*
X1031971Y1122168D01*
X1030688D01*
X1029660Y1123196D01*
X1029061D01*
G01X1019907Y1123233D02*
X1019048D01*
X1017983Y1122168D01*
X1015514D01*
X1013010Y1120494D01*
X1011337D01*
X1010309Y1121522D01*
X1008191D01*
G01X1037891Y1141601D02*
X1031437D01*
X1029764Y1139928D01*
X1029061D01*
G01X1019907Y1139893D02*
X1017510D01*
X1016870Y1140533D01*
Y1141825D01*
X1016262Y1142433D01*
X1014276D01*
X1013444Y1141601D01*
X1008191D01*
G01X1037891Y1134908D02*
X1032501D01*
X1030828Y1133235D01*
X1029061D01*
G01X1019907Y1133203D02*
X1017695D01*
X1016870Y1134028D01*
Y1135168D01*
X1016190Y1135848D01*
X1014384D01*
X1013444Y1134908D01*
X1008191D01*
G01X1037891Y1148294D02*
X1032501D01*
X1030828Y1146621D01*
X1029061D01*
G01X1019907Y1146589D02*
X1017695D01*
X1016870Y1147414D01*
Y1148554D01*
X1016190Y1149234D01*
X1014384D01*
X1013444Y1148294D01*
X1008191D01*
G01X1037891Y1154987D02*
X1035739D01*
X1034711Y1156015D01*
X1033110D01*
X1031436Y1157689D01*
X1030701D01*
X1029672Y1156660D01*
X1029061D01*
G01X1019907Y1156618D02*
X1019103D01*
X1018032Y1157689D01*
X1015906D01*
X1013402Y1156015D01*
X1011379D01*
X1010351Y1154987D01*
X1008191D01*
G01X1037891Y1158333D02*
X1035731D01*
X1034703Y1157305D01*
X1033645D01*
X1031971Y1158979D01*
X1030688D01*
X1029660Y1160007D01*
X1029061D01*
G01X1019907Y1160044D02*
X1019048D01*
X1017983Y1158979D01*
X1015514D01*
X1013010Y1157305D01*
X1011337D01*
X1010309Y1158333D01*
X1008191D01*
G01X1037891Y1178412D02*
X1031437D01*
X1029764Y1176739D01*
X1029061D01*
G01X1019907Y1176704D02*
X1017510D01*
X1016870Y1177344D01*
Y1178636D01*
X1016262Y1179244D01*
X1014276D01*
X1013444Y1178412D01*
X1008191D01*
G01X1037891Y1171719D02*
X1032501D01*
X1030828Y1170046D01*
X1029061D01*
G01X1019907Y1170014D02*
X1017695D01*
X1016870Y1170839D01*
Y1171979D01*
X1016190Y1172659D01*
X1014384D01*
X1013444Y1171719D01*
X1008191D01*
G01X1037891Y1165026D02*
X1031437D01*
X1029764Y1163353D01*
X1029061D01*
G01X1019907Y1163318D02*
X1017510D01*
X1016870Y1163958D01*
Y1165250D01*
X1016262Y1165858D01*
X1014276D01*
X1013444Y1165026D01*
X1008191D01*
G01X1037891Y1185105D02*
X1032501D01*
X1030828Y1183432D01*
X1029061D01*
G01X1019907Y1183400D02*
X1017695D01*
X1016870Y1184225D01*
Y1185365D01*
X1016190Y1186045D01*
X1014384D01*
X1013444Y1185105D01*
X1008191D01*
G01X1037891Y1191798D02*
X1035739D01*
X1034711Y1192826D01*
X1033110D01*
X1031436Y1194500D01*
X1030701D01*
X1029672Y1193471D01*
X1029061D01*
G01X1019907Y1193429D02*
X1019103D01*
X1018032Y1194500D01*
X1015906D01*
X1013402Y1192826D01*
X1011379D01*
X1010351Y1191798D01*
X1008191D01*
G01X1037891Y1208530D02*
X1032501D01*
X1030828Y1206857D01*
X1029061D01*
G01X1019907Y1206825D02*
X1017695D01*
X1016870Y1207650D01*
Y1208790D01*
X1016190Y1209470D01*
X1014384D01*
X1013444Y1208530D01*
X1008191D01*
G01X1037891Y1201837D02*
X1031437D01*
X1029764Y1200164D01*
X1029061D01*
G01X1019907Y1200129D02*
X1017510D01*
X1016870Y1200769D01*
Y1202061D01*
X1016262Y1202669D01*
X1014276D01*
X1013444Y1201837D01*
X1008191D01*
G01X1037891Y1195144D02*
X1035731D01*
X1034703Y1194116D01*
X1033645D01*
X1031971Y1195790D01*
X1030688D01*
X1029660Y1196818D01*
X1029061D01*
G01X1019907Y1196855D02*
X1019048D01*
X1017983Y1195790D01*
X1015514D01*
X1013010Y1194116D01*
X1011337D01*
X1010309Y1195144D01*
X1008191D01*
G01X1037891Y1221916D02*
X1032501D01*
X1030828Y1220243D01*
X1029061D01*
G01X1019907Y1220211D02*
X1017695D01*
X1016870Y1221036D01*
Y1222176D01*
X1016190Y1222856D01*
X1014384D01*
X1013444Y1221916D01*
X1008191D01*
G01X1037891Y1215223D02*
X1031437D01*
X1029764Y1213550D01*
X1029061D01*
G01X1019907Y1213515D02*
X1017510D01*
X1016870Y1214155D01*
Y1215447D01*
X1016262Y1216055D01*
X1014276D01*
X1013444Y1215223D01*
X1008191D01*
G01X1037891Y1238648D02*
X1031437D01*
X1029764Y1236975D01*
X1029061D01*
G01X1019907Y1236940D02*
X1017510D01*
X1016870Y1237580D01*
Y1238872D01*
X1016262Y1239480D01*
X1014276D01*
X1013444Y1238648D01*
X1008191D01*
G01X1037891Y1228609D02*
X1035739D01*
X1034711Y1229637D01*
X1033110D01*
X1031436Y1231311D01*
X1030701D01*
X1029672Y1230282D01*
X1029061D01*
G01X1019907Y1230240D02*
X1019103D01*
X1018032Y1231311D01*
X1015906D01*
X1013402Y1229637D01*
X1011379D01*
X1010351Y1228609D01*
X1008191D01*
G01X1037891Y1231955D02*
X1035731D01*
X1034703Y1230927D01*
X1033645D01*
X1031971Y1232601D01*
X1030688D01*
X1029660Y1233629D01*
X1029061D01*
G01X1019907Y1233666D02*
X1019048D01*
X1017983Y1232601D01*
X1015514D01*
X1013010Y1230927D01*
X1011337D01*
X1010309Y1231955D01*
X1008191D01*
G01X1037891Y1245341D02*
X1032501D01*
X1030828Y1243668D01*
X1029061D01*
G01X1019907Y1243636D02*
X1017695D01*
X1016870Y1244461D01*
Y1245601D01*
X1016129Y1246342D01*
X1014445D01*
X1013444Y1245341D01*
X1008191D01*
G01X1054033Y770144D02*
X1050820D01*
X1050003Y770961D01*
X1048245D01*
X1047411Y770127D01*
X1045855D01*
X1045349Y770633D01*
Y771230D01*
X1044762Y771817D01*
X1042619D01*
G01X1033465Y771873D02*
X1032072D01*
X1031511Y771312D01*
Y770640D01*
X1031015Y770144D01*
X1024333D01*
G01X1054033Y776837D02*
X1048857D01*
X1048023Y777671D01*
X1046336D01*
X1045677Y777012D01*
Y775730D01*
X1045111Y775164D01*
X1042619D01*
G01X1033465Y775124D02*
X1030562D01*
X1028849Y776837D01*
X1024333D01*
G01X1054033Y786877D02*
X1052102D01*
X1051074Y785849D01*
X1048304D01*
X1045800Y784176D01*
X1044207D01*
X1043179Y785204D01*
X1042619D01*
G01X1033465Y785235D02*
X1032737D01*
X1031688Y784186D01*
X1030744D01*
X1029081Y785849D01*
X1027218D01*
X1026190Y786877D01*
X1024333D01*
G01X1054033Y783530D02*
X1052105D01*
X1051076Y784559D01*
X1048696D01*
X1046192Y782886D01*
X1044204D01*
X1043176Y781858D01*
X1042619D01*
G01X1033465Y781835D02*
X1032688D01*
X1031627Y782896D01*
X1030209D01*
X1028546Y784559D01*
X1027230D01*
X1026201Y783530D01*
X1024333D01*
G01X1054033Y800263D02*
X1048857D01*
X1048023Y801097D01*
X1046336D01*
X1045677Y800438D01*
Y799156D01*
X1045111Y798590D01*
X1042619D01*
G01X1033465Y798550D02*
X1030562D01*
X1028849Y800263D01*
X1024333D01*
G01X1054033Y793570D02*
X1050820D01*
X1050003Y794387D01*
X1048245D01*
X1047411Y793553D01*
X1045855D01*
X1045349Y794059D01*
Y794656D01*
X1044762Y795243D01*
X1042619D01*
G01X1033465Y795299D02*
X1032072D01*
X1031511Y794738D01*
Y794066D01*
X1031015Y793570D01*
X1024333D01*
G01X1054033Y813648D02*
X1048857D01*
X1048023Y814482D01*
X1046336D01*
X1045677Y813823D01*
Y812541D01*
X1045111Y811975D01*
X1042619D01*
G01X1033465Y811935D02*
X1030562D01*
X1028849Y813648D01*
X1024333D01*
G01X1054033Y806955D02*
X1050820D01*
X1050003Y807772D01*
X1048245D01*
X1047411Y806938D01*
X1045855D01*
X1045349Y807444D01*
Y808041D01*
X1044762Y808628D01*
X1042619D01*
G01X1033465Y808684D02*
X1032072D01*
X1031511Y808123D01*
Y807451D01*
X1031015Y806955D01*
X1024333D01*
G01X1054033Y820341D02*
X1052105D01*
X1051076Y821370D01*
X1048696D01*
X1046192Y819697D01*
X1044204D01*
X1043176Y818669D01*
X1042619D01*
G01X1033465Y818646D02*
X1032688D01*
X1031627Y819707D01*
X1030209D01*
X1028546Y821370D01*
X1027230D01*
X1026201Y820341D01*
X1024333D01*
G01X1054033Y837074D02*
X1048857D01*
X1048023Y837908D01*
X1046336D01*
X1045677Y837249D01*
Y835967D01*
X1045111Y835401D01*
X1042619D01*
G01X1033465Y835361D02*
X1030562D01*
X1028849Y837074D01*
X1024333D01*
G01X1054033Y830381D02*
X1050820D01*
X1050003Y831198D01*
X1048245D01*
X1047411Y830364D01*
X1045855D01*
X1045349Y830870D01*
Y831467D01*
X1044762Y832054D01*
X1042619D01*
G01X1033465Y832110D02*
X1032072D01*
X1031511Y831549D01*
Y830877D01*
X1031015Y830381D01*
X1024333D01*
G01X1054033Y823688D02*
X1052102D01*
X1051074Y822660D01*
X1048304D01*
X1045800Y820987D01*
X1044207D01*
X1043179Y822015D01*
X1042619D01*
G01X1033465Y822046D02*
X1032737D01*
X1031688Y820997D01*
X1030744D01*
X1029081Y822660D01*
X1027218D01*
X1026190Y823688D01*
X1024333D01*
G01X1054033Y850459D02*
X1048857D01*
X1048023Y851293D01*
X1046336D01*
X1045677Y850634D01*
Y849352D01*
X1045111Y848786D01*
X1042619D01*
G01X1033465Y848746D02*
X1030562D01*
X1028849Y850459D01*
X1024333D01*
G01X1054033Y843766D02*
X1050820D01*
X1050003Y844583D01*
X1048245D01*
X1047411Y843749D01*
X1045855D01*
X1045349Y844255D01*
Y844852D01*
X1044762Y845439D01*
X1042619D01*
G01X1033465Y845495D02*
X1032072D01*
X1031511Y844934D01*
Y844262D01*
X1031015Y843766D01*
X1024333D01*
G01X1054033Y867192D02*
X1050820D01*
X1050003Y868009D01*
X1048245D01*
X1047411Y867175D01*
X1045855D01*
X1045349Y867681D01*
Y868278D01*
X1044762Y868865D01*
X1042619D01*
G01X1033465Y868921D02*
X1032072D01*
X1031511Y868360D01*
Y867688D01*
X1031015Y867192D01*
X1024333D01*
G01X1054033Y860499D02*
X1052102D01*
X1051074Y859471D01*
X1048304D01*
X1045800Y857798D01*
X1044207D01*
X1043179Y858826D01*
X1042619D01*
G01X1033465Y858857D02*
X1032737D01*
X1031688Y857808D01*
X1030744D01*
X1029081Y859471D01*
X1027218D01*
X1026190Y860499D01*
X1024333D01*
G01X1054033Y857152D02*
X1052105D01*
X1051076Y858181D01*
X1048696D01*
X1046192Y856508D01*
X1044204D01*
X1043176Y855480D01*
X1042619D01*
G01X1033465Y855457D02*
X1032688D01*
X1031627Y856518D01*
X1030209D01*
X1028546Y858181D01*
X1027230D01*
X1026201Y857152D01*
X1024333D01*
G01X1054033Y873885D02*
X1048857D01*
X1048023Y874719D01*
X1046336D01*
X1045677Y874060D01*
Y872778D01*
X1045111Y872212D01*
X1042619D01*
G01X1033465Y872172D02*
X1030562D01*
X1028849Y873885D01*
X1024333D01*
G01X1054033Y880577D02*
X1050820D01*
X1050003Y881394D01*
X1048245D01*
X1047411Y880560D01*
X1045855D01*
X1045349Y881066D01*
Y881663D01*
X1044762Y882250D01*
X1042619D01*
G01X1033465Y882306D02*
X1032072D01*
X1031511Y881745D01*
Y881073D01*
X1031015Y880577D01*
X1024333D01*
G01X1054033Y887270D02*
X1048857D01*
X1048023Y888104D01*
X1046336D01*
X1045677Y887445D01*
Y886163D01*
X1045111Y885597D01*
X1042619D01*
G01X1033465Y885557D02*
X1030562D01*
X1028849Y887270D01*
X1024333D01*
G01X1054033Y897310D02*
X1052102D01*
X1051074Y896282D01*
X1048304D01*
X1045800Y894609D01*
X1044207D01*
X1043179Y895637D01*
X1042619D01*
G01X1033465Y895668D02*
X1032737D01*
X1031688Y894619D01*
X1030744D01*
X1029081Y896282D01*
X1027218D01*
X1026190Y897310D01*
X1024333D01*
G01X1054033Y893963D02*
X1052105D01*
X1051076Y894992D01*
X1048696D01*
X1046192Y893319D01*
X1044204D01*
X1043176Y892291D01*
X1042619D01*
G01X1033465Y892268D02*
X1032688D01*
X1031627Y893329D01*
X1030209D01*
X1028546Y894992D01*
X1027230D01*
X1026201Y893963D01*
X1024333D01*
G01X1054033Y910696D02*
X1048857D01*
X1048023Y911530D01*
X1046336D01*
X1045677Y910871D01*
Y909589D01*
X1045111Y909023D01*
X1042619D01*
G01X1033465Y908983D02*
X1030562D01*
X1028849Y910696D01*
X1024333D01*
G01X1054033Y904003D02*
X1050820D01*
X1050003Y904820D01*
X1048245D01*
X1047411Y903986D01*
X1045855D01*
X1045349Y904492D01*
Y905089D01*
X1044762Y905676D01*
X1042619D01*
G01X1033465Y905732D02*
X1032072D01*
X1031511Y905171D01*
Y904499D01*
X1031015Y904003D01*
X1024333D01*
G01X1054033Y924081D02*
X1048857D01*
X1048023Y924915D01*
X1046336D01*
X1045677Y924256D01*
Y922974D01*
X1045111Y922408D01*
X1042619D01*
G01X1033465Y922368D02*
X1030562D01*
X1028849Y924081D01*
X1024333D01*
G01X1054033Y917389D02*
X1050820D01*
X1050003Y918206D01*
X1048245D01*
X1047411Y917372D01*
X1045855D01*
X1045349Y917878D01*
Y918475D01*
X1044762Y919062D01*
X1042619D01*
G01X1033465Y919118D02*
X1032072D01*
X1031511Y918557D01*
Y917885D01*
X1031015Y917389D01*
X1024333D01*
G01X1054033Y934121D02*
X1052102D01*
X1051074Y933093D01*
X1048304D01*
X1045800Y931420D01*
X1044207D01*
X1043179Y932448D01*
X1042619D01*
G01X1033465Y932479D02*
X1032737D01*
X1031688Y931430D01*
X1030744D01*
X1029081Y933093D01*
X1027218D01*
X1026190Y934121D01*
X1024333D01*
G01X1054033Y930774D02*
X1052105D01*
X1051076Y931803D01*
X1048696D01*
X1046192Y930130D01*
X1044204D01*
X1043176Y929102D01*
X1042619D01*
G01X1033465Y929079D02*
X1032688D01*
X1031627Y930140D01*
X1030209D01*
X1028546Y931803D01*
X1027230D01*
X1026201Y930774D01*
X1024333D01*
G01X1054033Y947507D02*
X1048857D01*
X1048023Y948341D01*
X1046336D01*
X1045677Y947682D01*
Y946400D01*
X1045111Y945834D01*
X1042619D01*
G01X1033465Y945794D02*
X1030562D01*
X1028849Y947507D01*
X1024333D01*
G01X1054033Y940814D02*
X1050820D01*
X1050003Y941631D01*
X1048245D01*
X1047411Y940797D01*
X1045855D01*
X1045349Y941303D01*
Y941900D01*
X1044762Y942487D01*
X1042619D01*
G01X1033465Y942543D02*
X1032072D01*
X1031511Y941982D01*
Y941310D01*
X1031015Y940814D01*
X1024333D01*
G01X1028683Y964239D02*
X1024333D01*
G01X1054033Y977625D02*
X1050820D01*
X1050003Y978442D01*
X1048245D01*
X1047411Y977608D01*
X1045855D01*
X1045349Y978114D01*
Y978711D01*
X1044762Y979298D01*
X1042619D01*
G01X1033465Y979354D02*
X1032072D01*
X1031511Y978793D01*
Y978121D01*
X1031015Y977625D01*
X1024333D01*
G01X1054033Y970932D02*
X1050820D01*
X1050003Y971749D01*
X1048245D01*
X1047411Y970915D01*
X1045855D01*
X1045349Y971421D01*
Y972018D01*
X1044762Y972605D01*
X1042619D01*
G01X1033465Y972661D02*
X1032072D01*
X1031511Y972100D01*
Y971428D01*
X1031015Y970932D01*
X1024333D01*
G01X1054033Y991011D02*
X1050820D01*
X1050003Y991828D01*
X1048245D01*
X1047411Y990994D01*
X1045855D01*
X1045349Y991500D01*
Y992097D01*
X1044762Y992684D01*
X1042619D01*
G01X1033465Y992740D02*
X1032072D01*
X1031511Y992179D01*
Y991507D01*
X1031015Y991011D01*
X1024333D01*
G01X1054033Y984318D02*
X1050820D01*
X1050003Y985135D01*
X1048245D01*
X1047411Y984301D01*
X1045855D01*
X1045349Y984807D01*
Y985404D01*
X1044762Y985991D01*
X1042619D01*
G01X1033465Y986047D02*
X1032072D01*
X1031511Y985486D01*
Y984814D01*
X1031015Y984318D01*
X1024333D01*
G01X1028683Y1021129D02*
X1024333D01*
G01X1028683Y1024475D02*
X1024333D01*
G01X1054033Y1031168D02*
X1050820D01*
X1050003Y1031985D01*
X1048245D01*
X1047411Y1031151D01*
X1045855D01*
X1045349Y1031657D01*
Y1032254D01*
X1044762Y1032841D01*
X1042619D01*
G01X1033465Y1032897D02*
X1032072D01*
X1031511Y1032336D01*
Y1031664D01*
X1031015Y1031168D01*
X1024333D01*
G01X1054033Y1044554D02*
X1050820D01*
X1050003Y1045371D01*
X1048245D01*
X1047411Y1044537D01*
X1045855D01*
X1045349Y1045043D01*
Y1045640D01*
X1044762Y1046227D01*
X1042619D01*
G01X1033465Y1046283D02*
X1032072D01*
X1031511Y1045722D01*
Y1045050D01*
X1031015Y1044554D01*
X1024333D01*
G01X1054033Y1037861D02*
X1050820D01*
X1050003Y1038678D01*
X1048245D01*
X1047411Y1037844D01*
X1045855D01*
X1045349Y1038350D01*
Y1038947D01*
X1044762Y1039534D01*
X1042619D01*
G01X1033465Y1039590D02*
X1032072D01*
X1031511Y1039029D01*
Y1038357D01*
X1031015Y1037861D01*
X1024333D01*
G01X1028683Y1051247D02*
X1024333D01*
G01X1054033Y1071326D02*
X1048857D01*
X1048023Y1072160D01*
X1046336D01*
X1045677Y1071501D01*
Y1070219D01*
X1045111Y1069653D01*
X1042619D01*
G01X1033465Y1069613D02*
X1030562D01*
X1028849Y1071326D01*
X1024333D01*
G01X1054033Y1064633D02*
X1050820D01*
X1050003Y1065450D01*
X1048245D01*
X1047411Y1064616D01*
X1045855D01*
X1045349Y1065122D01*
Y1065719D01*
X1044762Y1066306D01*
X1042619D01*
G01X1033465Y1066362D02*
X1032072D01*
X1031511Y1065801D01*
Y1065129D01*
X1031015Y1064633D01*
X1024333D01*
G01X1054033Y1081365D02*
X1052102D01*
X1051074Y1080337D01*
X1048304D01*
X1045800Y1078664D01*
X1044207D01*
X1043179Y1079692D01*
X1042620D01*
G01X1033466Y1079730D02*
X1032744D01*
X1031688Y1078674D01*
X1030744D01*
X1029081Y1080337D01*
X1027218D01*
X1026190Y1081365D01*
X1024333D01*
G01X1054033Y1078018D02*
X1052105D01*
X1051076Y1079047D01*
X1048696D01*
X1046192Y1077374D01*
X1044204D01*
X1043176Y1076346D01*
X1042619D01*
G01X1033465Y1076323D02*
X1032688D01*
X1031627Y1077384D01*
X1030209D01*
X1028546Y1079047D01*
X1027230D01*
X1026201Y1078018D01*
X1024333D01*
G01X1054033Y1094751D02*
X1048857D01*
X1048023Y1095585D01*
X1046336D01*
X1045677Y1094926D01*
Y1093644D01*
X1045111Y1093078D01*
X1042619D01*
G01X1033465Y1093038D02*
X1030562D01*
X1028849Y1094751D01*
X1024333D01*
G01X1054033Y1088058D02*
X1050820D01*
X1050003Y1088875D01*
X1048245D01*
X1047411Y1088041D01*
X1045855D01*
X1045349Y1088547D01*
Y1089144D01*
X1044762Y1089731D01*
X1042619D01*
G01X1033465Y1089787D02*
X1032072D01*
X1031511Y1089226D01*
Y1088554D01*
X1031015Y1088058D01*
X1024333D01*
G01X1054033Y1108137D02*
X1048857D01*
X1048023Y1108971D01*
X1046336D01*
X1045677Y1108312D01*
Y1107030D01*
X1045111Y1106464D01*
X1042619D01*
G01X1033465Y1106424D02*
X1030562D01*
X1028849Y1108137D01*
X1024333D01*
G01X1054033Y1101444D02*
X1050820D01*
X1050003Y1102261D01*
X1048245D01*
X1047411Y1101427D01*
X1045855D01*
X1045349Y1101933D01*
Y1102530D01*
X1044762Y1103117D01*
X1042619D01*
G01X1033465Y1103173D02*
X1032072D01*
X1031511Y1102612D01*
Y1101940D01*
X1031015Y1101444D01*
X1024333D01*
G01X1054033Y1124869D02*
X1050820D01*
X1050003Y1125686D01*
X1048245D01*
X1047411Y1124852D01*
X1045855D01*
X1045349Y1125358D01*
Y1125955D01*
X1044762Y1126542D01*
X1042619D01*
G01X1033465Y1126598D02*
X1032072D01*
X1031511Y1126037D01*
Y1125365D01*
X1031015Y1124869D01*
X1024333D01*
G01X1054033Y1118176D02*
X1052102D01*
X1051074Y1117148D01*
X1048304D01*
X1045800Y1115475D01*
X1044207D01*
X1043179Y1116503D01*
X1042619D01*
G01X1033465Y1116541D02*
X1032744D01*
X1031688Y1115485D01*
X1030744D01*
X1029081Y1117148D01*
X1027218D01*
X1026190Y1118176D01*
X1024333D01*
G01X1054033Y1114829D02*
X1052105D01*
X1051076Y1115858D01*
X1048696D01*
X1046192Y1114185D01*
X1044204D01*
X1043176Y1113157D01*
X1042619D01*
G01X1033465Y1113134D02*
X1032688D01*
X1031627Y1114195D01*
X1030209D01*
X1028546Y1115858D01*
X1027230D01*
X1026201Y1114829D01*
X1024333D01*
G01X1054033Y1144948D02*
X1048857D01*
X1048023Y1145782D01*
X1046336D01*
X1045677Y1145123D01*
Y1143841D01*
X1045111Y1143275D01*
X1042619D01*
G01X1033465Y1143235D02*
X1030562D01*
X1028849Y1144948D01*
X1024333D01*
G01X1054033Y1138255D02*
X1050820D01*
X1050003Y1139072D01*
X1048245D01*
X1047411Y1138238D01*
X1045855D01*
X1045349Y1138744D01*
Y1139341D01*
X1044762Y1139928D01*
X1042619D01*
G01X1033465Y1139984D02*
X1032072D01*
X1031511Y1139423D01*
Y1138751D01*
X1031015Y1138255D01*
X1024333D01*
G01X1054033Y1131562D02*
X1048857D01*
X1048023Y1132396D01*
X1046336D01*
X1045677Y1131737D01*
Y1130455D01*
X1045111Y1129889D01*
X1042619D01*
G01X1033465Y1129849D02*
X1030562D01*
X1028849Y1131562D01*
X1024333D01*
G01X1054033Y1154987D02*
X1052102D01*
X1051074Y1153959D01*
X1048304D01*
X1045800Y1152286D01*
X1044207D01*
X1043179Y1153314D01*
X1042619D01*
G01X1033465Y1153352D02*
X1032744D01*
X1031688Y1152296D01*
X1030744D01*
X1029081Y1153959D01*
X1027218D01*
X1026190Y1154987D01*
X1024333D01*
G01X1054033Y1151641D02*
X1052104D01*
X1051076Y1152669D01*
X1048696D01*
X1046192Y1150996D01*
X1044204D01*
X1043176Y1149968D01*
X1042619D01*
G01X1033465Y1149945D02*
X1032688D01*
X1031627Y1151006D01*
X1030209D01*
X1028546Y1152669D01*
X1027230D01*
X1026202Y1151641D01*
X1024333D01*
G01X1054033Y1175066D02*
X1050820D01*
X1050003Y1175883D01*
X1048245D01*
X1047411Y1175049D01*
X1045855D01*
X1045349Y1175555D01*
Y1176152D01*
X1044762Y1176739D01*
X1042619D01*
G01X1033465Y1176795D02*
X1032072D01*
X1031511Y1176234D01*
Y1175562D01*
X1031015Y1175066D01*
X1024333D01*
G01X1054033Y1168373D02*
X1048857D01*
X1048023Y1169207D01*
X1046336D01*
X1045677Y1168548D01*
Y1167266D01*
X1045111Y1166700D01*
X1042619D01*
G01X1033465Y1166660D02*
X1030562D01*
X1028849Y1168373D01*
X1024333D01*
G01X1054033Y1161680D02*
X1050820D01*
X1050003Y1162497D01*
X1048245D01*
X1047411Y1161663D01*
X1045855D01*
X1045349Y1162169D01*
Y1162766D01*
X1044762Y1163353D01*
X1042619D01*
G01X1033465Y1163409D02*
X1032072D01*
X1031511Y1162848D01*
Y1162176D01*
X1031015Y1161680D01*
X1024333D01*
G01X1054033Y1181759D02*
X1048857D01*
X1048023Y1182593D01*
X1046336D01*
X1045677Y1181934D01*
Y1180652D01*
X1045111Y1180086D01*
X1042619D01*
G01X1033465Y1180046D02*
X1030562D01*
X1028849Y1181759D01*
X1024333D01*
G01X1054033Y1191798D02*
X1052102D01*
X1051074Y1190770D01*
X1048304D01*
X1045800Y1189097D01*
X1044207D01*
X1043179Y1190125D01*
X1042619D01*
G01X1033465Y1190163D02*
X1032744D01*
X1031688Y1189107D01*
X1030744D01*
X1029081Y1190770D01*
X1027218D01*
X1026190Y1191798D01*
X1024333D01*
G01X1054033Y1188452D02*
X1052104D01*
X1051076Y1189480D01*
X1048696D01*
X1046192Y1187807D01*
X1044204D01*
X1043176Y1186779D01*
X1042619D01*
G01X1033465Y1186756D02*
X1032688D01*
X1031627Y1187817D01*
X1030209D01*
X1028546Y1189480D01*
X1027230D01*
X1026202Y1188452D01*
X1024333D01*
G01X1054033Y1205184D02*
X1048857D01*
X1048023Y1206018D01*
X1046336D01*
X1045677Y1205359D01*
Y1204077D01*
X1045111Y1203511D01*
X1042619D01*
G01X1033465Y1203471D02*
X1030562D01*
X1028849Y1205184D01*
X1024333D01*
G01X1054033Y1198491D02*
X1050820D01*
X1050003Y1199308D01*
X1048245D01*
X1047411Y1198474D01*
X1045855D01*
X1045349Y1198980D01*
Y1199577D01*
X1044762Y1200164D01*
X1042619D01*
G01X1033465Y1200220D02*
X1032072D01*
X1031511Y1199659D01*
Y1198987D01*
X1031015Y1198491D01*
X1024333D01*
G01X1054033Y1218570D02*
X1048857D01*
X1048023Y1219404D01*
X1046336D01*
X1045677Y1218745D01*
Y1217463D01*
X1045111Y1216897D01*
X1042619D01*
G01X1033465Y1216857D02*
X1030562D01*
X1028849Y1218570D01*
X1024333D01*
G01X1054033Y1211877D02*
X1050820D01*
X1050003Y1212694D01*
X1048245D01*
X1047411Y1211860D01*
X1045855D01*
X1045349Y1212366D01*
Y1212963D01*
X1044762Y1213550D01*
X1042619D01*
G01X1033465Y1213606D02*
X1032072D01*
X1031511Y1213045D01*
Y1212373D01*
X1031015Y1211877D01*
X1024333D01*
G01X1054033Y1228609D02*
X1052102D01*
X1051074Y1227581D01*
X1048304D01*
X1045800Y1225908D01*
X1044207D01*
X1043179Y1226936D01*
X1042619D01*
G01X1033465Y1226974D02*
X1032744D01*
X1031688Y1225918D01*
X1030744D01*
X1029081Y1227581D01*
X1027218D01*
X1026190Y1228609D01*
X1024333D01*
G01X1054033Y1225263D02*
X1052104D01*
X1051076Y1226291D01*
X1048696D01*
X1046192Y1224618D01*
X1044204D01*
X1043176Y1223590D01*
X1042619D01*
G01X1033465Y1223567D02*
X1032688D01*
X1031627Y1224628D01*
X1030209D01*
X1028546Y1226291D01*
X1027230D01*
X1026202Y1225263D01*
X1024333D01*
G01X1054033Y1241995D02*
X1048857D01*
X1048023Y1242829D01*
X1046336D01*
X1045677Y1242170D01*
Y1240888D01*
X1045111Y1240322D01*
X1042619D01*
G01X1033465Y1240282D02*
X1030562D01*
X1028849Y1241995D01*
X1024333D01*
G01X1054033Y1235302D02*
X1050820D01*
X1050003Y1236119D01*
X1048245D01*
X1047411Y1235285D01*
X1045855D01*
X1045349Y1235791D01*
Y1236388D01*
X1044762Y1236975D01*
X1042619D01*
G01X1033465Y1237031D02*
X1032072D01*
X1031511Y1236470D01*
Y1235798D01*
X1031015Y1235302D01*
X1024333D01*
G01X1058383Y770144D02*
X1054033D01*
G01X1042241Y780184D02*
X1037891D01*
G01X1042241Y773491D02*
X1037891D01*
G01X1058383Y776837D02*
X1054033D01*
G01X1042241Y786877D02*
X1037891D01*
G01X1058383D02*
X1054033D01*
G01X1058383Y783530D02*
X1054033D01*
G01X1042241Y796916D02*
X1037891D01*
G01X1058383Y800263D02*
X1054033D01*
G01X1058383Y793570D02*
X1054033D01*
G01X1042241Y790223D02*
X1037891D01*
G01X1042241Y816995D02*
X1037891D01*
G01X1042241Y810302D02*
X1037891D01*
G01X1058383Y813648D02*
X1054033D01*
G01X1058383Y806955D02*
X1054033D01*
G01X1042241Y803609D02*
X1037891D01*
G01X1042241Y833727D02*
X1037891D01*
G01X1058383Y830381D02*
X1054033D01*
G01X1042241Y823688D02*
X1037891D01*
G01X1058383D02*
X1054033D01*
G01X1042241Y827034D02*
X1037891D01*
G01X1058383Y820341D02*
X1054033D01*
G01X1042241Y847113D02*
X1037891D01*
G01X1058383Y850459D02*
X1054033D01*
G01X1058383Y843766D02*
X1054033D01*
G01X1042241Y840420D02*
X1037891D01*
G01X1058383Y837074D02*
X1054033D01*
G01X1058383Y867192D02*
X1054033D01*
G01X1042241Y853806D02*
X1037891D01*
G01X1042241Y860499D02*
X1037891D01*
G01X1058383D02*
X1054033D01*
G01X1042241Y863845D02*
X1037891D01*
G01X1058383Y857152D02*
X1054033D01*
G01X1058383Y873885D02*
X1054033D01*
G01X1042241Y883924D02*
X1037891D01*
G01X1058383Y880577D02*
X1054033D01*
G01X1042241Y877231D02*
X1037891D01*
G01X1042241Y870538D02*
X1037891D01*
G01X1042241Y890617D02*
X1037891D01*
G01X1058383Y887270D02*
X1054033D01*
G01X1042241Y897310D02*
X1037891D01*
G01X1058383D02*
X1054033D01*
G01X1042241Y900656D02*
X1037891D01*
G01X1058383Y893963D02*
X1054033D01*
G01X1042241Y914042D02*
X1037891D01*
G01X1042241Y907349D02*
X1037891D01*
G01X1058383Y910696D02*
X1054033D01*
G01X1058383Y904003D02*
X1054033D01*
G01X1042241Y927428D02*
X1037891D01*
G01X1042241Y920735D02*
X1037891D01*
G01X1058383Y924081D02*
X1054033D01*
G01X1058383Y917389D02*
X1054033D01*
G01X1058383Y930774D02*
X1054033D01*
G01X1042241Y944160D02*
X1037891D01*
G01X1058383Y947507D02*
X1054033D01*
G01X1058383Y940814D02*
X1054033D01*
G01X1058383Y934121D02*
X1054033D01*
G01X1042241D02*
X1037891D01*
G01X1042241Y937467D02*
X1037891D01*
G01X1042241Y960892D02*
X1037891D01*
G01X1042241Y950853D02*
X1037891D01*
G01X1058383Y964239D02*
X1054033D01*
G01X1042241Y957546D02*
X1037891D01*
G01X1042241Y980971D02*
X1037891D01*
G01X1058383Y977625D02*
X1054033D01*
G01X1042241Y974278D02*
X1037891D01*
G01X1042241Y967585D02*
X1037891D01*
G01X1058383Y970932D02*
X1054033D01*
G01X1042241Y994357D02*
X1037891D01*
G01X1058383Y991011D02*
X1054033D01*
G01X1042241Y987664D02*
X1037891D01*
G01X1058383Y984318D02*
X1054033D01*
G01X1058383Y1021129D02*
X1054033D01*
G01X1058383Y1024475D02*
X1054033D01*
G01X1042241Y1027822D02*
X1037891D01*
G01X1042241Y1021129D02*
X1037891D01*
G01X1058383Y1044554D02*
X1054033D01*
G01X1042241Y1041207D02*
X1037891D01*
G01X1058383Y1037861D02*
X1054033D01*
G01X1042241Y1034515D02*
X1037891D01*
G01X1058383Y1031168D02*
X1054033D01*
G01X1042241Y1061286D02*
X1037891D01*
G01X1042241Y1047900D02*
X1037891D01*
G01X1042241Y1054593D02*
X1037891D01*
G01X1058383Y1051247D02*
X1054033D01*
G01X1042241Y1074672D02*
X1037891D01*
G01X1042241Y1067979D02*
X1037891D01*
G01X1058383Y1071326D02*
X1054033D01*
G01X1058383Y1064633D02*
X1054033D01*
G01X1058383Y1078018D02*
X1054033D01*
G01X1042241Y1091404D02*
X1037891D01*
G01X1058383Y1094751D02*
X1054033D01*
G01X1058383Y1088058D02*
X1054033D01*
G01X1042241Y1081365D02*
X1037891D01*
G01X1058383D02*
X1054033D01*
G01X1042241Y1084711D02*
X1037891D01*
G01X1042241Y1098097D02*
X1037891D01*
G01X1042241Y1111483D02*
X1037891D01*
G01X1042241Y1104790D02*
X1037891D01*
G01X1058383Y1108137D02*
X1054033D01*
G01X1058383Y1101444D02*
X1054033D01*
G01X1042241Y1128215D02*
X1037891D01*
G01X1058383Y1124869D02*
X1054033D01*
G01X1042241Y1118176D02*
X1037891D01*
G01X1058383D02*
X1054033D01*
G01X1042241Y1121522D02*
X1037891D01*
G01X1058383Y1114829D02*
X1054033D01*
G01X1042241Y1141601D02*
X1037891D01*
G01X1058383Y1138255D02*
X1054033D01*
G01X1042241Y1134908D02*
X1037891D01*
G01X1058383Y1131562D02*
X1054033D01*
G01X1042241Y1148294D02*
X1037891D01*
G01X1058383Y1144948D02*
X1054033D01*
G01X1042241Y1154987D02*
X1037891D01*
G01X1058383D02*
X1054033D01*
G01X1042241Y1158333D02*
X1037891D01*
G01X1058383Y1151641D02*
X1054033D01*
G01X1058383Y1175066D02*
X1054033D01*
G01X1042241Y1171719D02*
X1037891D01*
G01X1042241Y1165026D02*
X1037891D01*
G01X1058383Y1168373D02*
X1054033D01*
G01X1058383Y1161680D02*
X1054033D01*
G01X1042241Y1185105D02*
X1037891D01*
G01X1042241Y1178412D02*
X1037891D01*
G01X1058383Y1181759D02*
X1054033D01*
G01X1042241Y1191798D02*
X1037891D01*
G01X1058383D02*
X1054033D01*
G01X1058383Y1188452D02*
X1054033D01*
G01X1058383Y1205184D02*
X1054033D01*
G01X1058383Y1198491D02*
X1054033D01*
G01X1042241Y1208530D02*
X1037891D01*
G01X1042241Y1201837D02*
X1037891D01*
G01X1042241Y1195144D02*
X1037891D01*
G01X1042241Y1221916D02*
X1037891D01*
G01X1042241Y1215223D02*
X1037891D01*
G01X1058383Y1218570D02*
X1054033D01*
G01X1058383Y1211877D02*
X1054033D01*
G01X1058383Y1225263D02*
X1054033D01*
G01X1042241Y1238648D02*
X1037891D01*
G01X1058383Y1241995D02*
X1054033D01*
G01X1058383Y1235302D02*
X1054033D01*
G01X1042241Y1228609D02*
X1037891D01*
G01X1058383D02*
X1054033D01*
G01X1042241Y1231955D02*
X1037891D01*
G01X1042241Y1245341D02*
X1037891D01*
G01X1097291Y780184D02*
X1091901D01*
X1090228Y778511D01*
X1088461D01*
G01X1079307Y778479D02*
X1077095D01*
X1076270Y779304D01*
Y780444D01*
X1075590Y781124D01*
X1073784D01*
X1072844Y780184D01*
X1067591D01*
G01X1097291Y773491D02*
X1090837D01*
X1089164Y771818D01*
X1088461D01*
G01X1079307Y771783D02*
X1076910D01*
X1076270Y772423D01*
Y773715D01*
X1075662Y774323D01*
X1073676D01*
X1072844Y773491D01*
X1067591D01*
G01X1097291Y786877D02*
X1095139D01*
X1094111Y787905D01*
X1092510D01*
X1090836Y789579D01*
X1090101D01*
X1089072Y788550D01*
X1088461D01*
G01X1079307Y788508D02*
X1078503D01*
X1077432Y789579D01*
X1075306D01*
X1072802Y787905D01*
X1070779D01*
X1069751Y786877D01*
X1067591D01*
G01X1097291Y796916D02*
X1090837D01*
X1089164Y795243D01*
X1088461D01*
G01X1079307Y795208D02*
X1076910D01*
X1076270Y795848D01*
Y797140D01*
X1075662Y797748D01*
X1073676D01*
X1072844Y796916D01*
X1067591D01*
G01X1097291Y790223D02*
X1095131D01*
X1094103Y789195D01*
X1093045D01*
X1091371Y790869D01*
X1090088D01*
X1089060Y791897D01*
X1088461D01*
G01X1079307Y791934D02*
X1078448D01*
X1077383Y790869D01*
X1074914D01*
X1072410Y789195D01*
X1070737D01*
X1069709Y790223D01*
X1067591D01*
G01X1097291Y816995D02*
X1091901D01*
X1090228Y815322D01*
X1088461D01*
G01X1079307Y815290D02*
X1077095D01*
X1076270Y816115D01*
Y817255D01*
X1075590Y817935D01*
X1073784D01*
X1072844Y816995D01*
X1067591D01*
G01X1097291Y810302D02*
X1090837D01*
X1089164Y808629D01*
X1088461D01*
G01X1079307Y808594D02*
X1076910D01*
X1076270Y809234D01*
Y810526D01*
X1075662Y811134D01*
X1073676D01*
X1072844Y810302D01*
X1067591D01*
G01X1097291Y803609D02*
X1091901D01*
X1090228Y801936D01*
X1088461D01*
G01X1079307Y801904D02*
X1077095D01*
X1076270Y802729D01*
Y803869D01*
X1075590Y804549D01*
X1073784D01*
X1072844Y803609D01*
X1067591D01*
G01X1097291Y833727D02*
X1090837D01*
X1089164Y832054D01*
X1088461D01*
G01X1079307Y832019D02*
X1076910D01*
X1076270Y832659D01*
Y833951D01*
X1075662Y834559D01*
X1073676D01*
X1072844Y833727D01*
X1067591D01*
G01X1097291Y823688D02*
X1095139D01*
X1094111Y824716D01*
X1092510D01*
X1090836Y826390D01*
X1090101D01*
X1089072Y825361D01*
X1088461D01*
G01X1079307Y825319D02*
X1078503D01*
X1077432Y826390D01*
X1075306D01*
X1072802Y824716D01*
X1070779D01*
X1069751Y823688D01*
X1067591D01*
G01X1097291Y827034D02*
X1095131D01*
X1094103Y826006D01*
X1093045D01*
X1091371Y827680D01*
X1090088D01*
X1089060Y828708D01*
X1088461D01*
G01X1079307Y828745D02*
X1078448D01*
X1077383Y827680D01*
X1074914D01*
X1072410Y826006D01*
X1070737D01*
X1069709Y827034D01*
X1067591D01*
G01X1097291Y847113D02*
X1090837D01*
X1089164Y845440D01*
X1088461D01*
G01X1079307Y845405D02*
X1076910D01*
X1076270Y846045D01*
Y847337D01*
X1075662Y847945D01*
X1073676D01*
X1072844Y847113D01*
X1067591D01*
G01X1097291Y840420D02*
X1091901D01*
X1090228Y838747D01*
X1088461D01*
G01X1079307Y838715D02*
X1077095D01*
X1076270Y839540D01*
Y840680D01*
X1075590Y841360D01*
X1073784D01*
X1072844Y840420D01*
X1067591D01*
G01X1097291Y853806D02*
X1091901D01*
X1090228Y852133D01*
X1088461D01*
G01X1079307Y852101D02*
X1077095D01*
X1076270Y852926D01*
Y854066D01*
X1075590Y854746D01*
X1073784D01*
X1072844Y853806D01*
X1067591D01*
G01X1097291Y860499D02*
X1095139D01*
X1094111Y861527D01*
X1092510D01*
X1090836Y863201D01*
X1090101D01*
X1089072Y862172D01*
X1088461D01*
G01X1079307Y862130D02*
X1078503D01*
X1077432Y863201D01*
X1075306D01*
X1072802Y861527D01*
X1070779D01*
X1069751Y860499D01*
X1067591D01*
G01X1097291Y863845D02*
X1095131D01*
X1094103Y862817D01*
X1093045D01*
X1091371Y864491D01*
X1090088D01*
X1089060Y865519D01*
X1088461D01*
G01X1079307Y865556D02*
X1078448D01*
X1077383Y864491D01*
X1074914D01*
X1072410Y862817D01*
X1070737D01*
X1069709Y863845D01*
X1067591D01*
G01X1097291Y883924D02*
X1090837D01*
X1089164Y882251D01*
X1088461D01*
G01X1079307Y882216D02*
X1076910D01*
X1076270Y882856D01*
Y884148D01*
X1075662Y884756D01*
X1073676D01*
X1072844Y883924D01*
X1067591D01*
G01X1097291Y877231D02*
X1091901D01*
X1090228Y875558D01*
X1088461D01*
G01X1079307Y875526D02*
X1077095D01*
X1076270Y876351D01*
Y877491D01*
X1075590Y878171D01*
X1073784D01*
X1072844Y877231D01*
X1067591D01*
G01X1097291Y870538D02*
X1090837D01*
X1089164Y868865D01*
X1088461D01*
G01X1079307Y868830D02*
X1076910D01*
X1076270Y869470D01*
Y870762D01*
X1075662Y871370D01*
X1073676D01*
X1072844Y870538D01*
X1067591D01*
G01X1097291Y890617D02*
X1091901D01*
X1090228Y888944D01*
X1088461D01*
G01X1079307Y888912D02*
X1077095D01*
X1076270Y889737D01*
Y890877D01*
X1075590Y891557D01*
X1073784D01*
X1072844Y890617D01*
X1067591D01*
G01X1097291Y897310D02*
X1095139D01*
X1094111Y898338D01*
X1092510D01*
X1090836Y900012D01*
X1090101D01*
X1089072Y898983D01*
X1088461D01*
G01X1079307Y898941D02*
X1078503D01*
X1077432Y900012D01*
X1075306D01*
X1072806Y898338D01*
X1070779D01*
X1069751Y897310D01*
X1067591D01*
G01X1097291Y900656D02*
X1095131D01*
X1094103Y899628D01*
X1093045D01*
X1091371Y901302D01*
X1090088D01*
X1089060Y902330D01*
X1088462D01*
G01X1079308Y902366D02*
X1079307Y902367D01*
X1078448D01*
X1077383Y901302D01*
X1074913D01*
X1072413Y899628D01*
X1070737D01*
X1069709Y900656D01*
X1067591D01*
G01X1097291Y914042D02*
X1091901D01*
X1090228Y912369D01*
X1088461D01*
G01X1079307Y912337D02*
X1077095D01*
X1076270Y913162D01*
Y914302D01*
X1075590Y914982D01*
X1073784D01*
X1072844Y914042D01*
X1067591D01*
G01X1097291Y907349D02*
X1090837D01*
X1089164Y905676D01*
X1088461D01*
G01X1079307Y905641D02*
X1076910D01*
X1076270Y906281D01*
Y907573D01*
X1075662Y908181D01*
X1073676D01*
X1072844Y907349D01*
X1067591D01*
G01X1097291Y927428D02*
X1091901D01*
X1090228Y925755D01*
X1088735D01*
G01X1078779D02*
X1077063D01*
X1076270Y926548D01*
Y927688D01*
X1075590Y928368D01*
X1073784D01*
X1072844Y927428D01*
X1067591D01*
G01X1097291Y920735D02*
X1090837D01*
X1089164Y919062D01*
X1088703D01*
G01X1078763D02*
X1076910D01*
X1076270Y919702D01*
Y920959D01*
X1075662Y921567D01*
X1073676D01*
X1072844Y920735D01*
X1067591D01*
G01X1097291Y944160D02*
X1090837D01*
X1089164Y942487D01*
X1088703D01*
G01X1078795D02*
X1076910D01*
X1076270Y943127D01*
Y944384D01*
X1075662Y944992D01*
X1073676D01*
X1072844Y944160D01*
X1067591D01*
G01X1097291Y934121D02*
X1095139D01*
X1094111Y935149D01*
X1092510D01*
X1090836Y936823D01*
X1090101D01*
X1089072Y935794D01*
X1088703D01*
G01X1078763D02*
X1078503D01*
X1077474Y936823D01*
X1075306D01*
X1072802Y935149D01*
X1070779D01*
X1069751Y934121D01*
X1067591D01*
G01X1097291Y937467D02*
X1095131D01*
X1094103Y936439D01*
X1093045D01*
X1091371Y938113D01*
X1090088D01*
X1089060Y939141D01*
X1088703D01*
G01X1078763D02*
X1078411D01*
X1077383Y938113D01*
X1074914D01*
X1072410Y936439D01*
X1070737D01*
X1069709Y937467D01*
X1067591D01*
G01X1071941Y960892D02*
X1067591D01*
G01X1097291Y950853D02*
X1091901D01*
X1090228Y949180D01*
X1088735D01*
G01X1078779D02*
X1077063D01*
X1076270Y949973D01*
Y951113D01*
X1075590Y951793D01*
X1073784D01*
X1072844Y950853D01*
X1067591D01*
G01X1071941Y957546D02*
X1067591D01*
G01X1097291Y980971D02*
X1090837D01*
X1089164Y979298D01*
X1088461D01*
G01X1079307Y979263D02*
X1076910D01*
X1076270Y979903D01*
Y981195D01*
X1075662Y981803D01*
X1073676D01*
X1072844Y980971D01*
X1067591D01*
G01X1097291Y974278D02*
X1090837D01*
X1089164Y972605D01*
X1088461D01*
G01X1079307Y972570D02*
X1076910D01*
X1076270Y973210D01*
Y974502D01*
X1075662Y975110D01*
X1073676D01*
X1072844Y974278D01*
X1067591D01*
G01X1071941Y967585D02*
X1067591D01*
G01X1097291Y994357D02*
X1090837D01*
X1089164Y992684D01*
X1088461D01*
G01X1079307Y992649D02*
X1076910D01*
X1076270Y993289D01*
Y994581D01*
X1075662Y995189D01*
X1073676D01*
X1072844Y994357D01*
X1067591D01*
G01X1097291Y987664D02*
X1090837D01*
X1089164Y985991D01*
X1088461D01*
G01X1079307Y985956D02*
X1076910D01*
X1076270Y986596D01*
Y987888D01*
X1075662Y988496D01*
X1073676D01*
X1072844Y987664D01*
X1067591D01*
G01X1097291Y1027822D02*
X1090837D01*
X1089164Y1026149D01*
X1088461D01*
G01X1079307Y1026114D02*
X1076910D01*
X1076270Y1026754D01*
Y1028046D01*
X1075662Y1028654D01*
X1073676D01*
X1072844Y1027822D01*
X1067591D01*
G01X1097291Y1021129D02*
X1090573D01*
X1088900Y1019456D01*
X1088461D01*
G01X1079307Y1019510D02*
X1076823D01*
X1076822Y1019509D01*
X1076270Y1020061D01*
Y1021199D01*
X1075399Y1022070D01*
X1073785D01*
X1072844Y1021129D01*
X1067591D01*
G01X1097291Y1041207D02*
X1090837D01*
X1089164Y1039534D01*
X1088461D01*
G01X1079307Y1039499D02*
X1076910D01*
X1076270Y1040139D01*
Y1041431D01*
X1075662Y1042039D01*
X1073676D01*
X1072844Y1041207D01*
X1067591D01*
G01X1097291Y1034515D02*
X1090837D01*
X1089164Y1032842D01*
X1088461D01*
G01X1079307Y1032807D02*
X1076910D01*
X1076270Y1033447D01*
Y1034739D01*
X1075662Y1035347D01*
X1073676D01*
X1072844Y1034515D01*
X1067591D01*
G01X1097291Y1061286D02*
X1090837D01*
X1089164Y1059613D01*
X1088461D01*
G01X1079307Y1059578D02*
X1076910D01*
X1076270Y1060218D01*
Y1061510D01*
X1075662Y1062118D01*
X1073676D01*
X1072844Y1061286D01*
X1067591D01*
G01X1097291Y1047900D02*
X1090837D01*
X1089164Y1046227D01*
X1088461D01*
G01X1079307Y1046192D02*
X1076910D01*
X1076270Y1046832D01*
Y1048124D01*
X1075662Y1048732D01*
X1073676D01*
X1072844Y1047900D01*
X1067591D01*
G01X1071941Y1054593D02*
X1067591D01*
G01X1097291Y1074672D02*
X1091901D01*
X1090228Y1072999D01*
X1088736D01*
G01X1078844D02*
X1077063D01*
X1076270Y1073792D01*
Y1074932D01*
X1075590Y1075612D01*
X1073784D01*
X1072844Y1074672D01*
X1067591D01*
G01X1097291Y1067979D02*
X1090837D01*
X1089164Y1066306D01*
X1088753D01*
G01X1078829D02*
X1076910D01*
X1076270Y1066946D01*
Y1068203D01*
X1075662Y1068811D01*
X1073676D01*
X1072844Y1067979D01*
X1067591D01*
G01X1097291Y1091404D02*
X1090837D01*
X1089164Y1089731D01*
X1088720D01*
G01X1078780D02*
X1076910D01*
X1076270Y1090371D01*
Y1091628D01*
X1075662Y1092236D01*
X1073676D01*
X1072844Y1091404D01*
X1067591D01*
G01X1097291Y1081365D02*
X1095139D01*
X1094111Y1082393D01*
X1092510D01*
X1090836Y1084067D01*
X1090101D01*
X1089072Y1083038D01*
X1088720D01*
G01X1078796D02*
X1078461D01*
X1077432Y1084067D01*
X1075306D01*
X1072802Y1082393D01*
X1070779D01*
X1069751Y1081365D01*
X1067591D01*
G01X1097291Y1084711D02*
X1095131D01*
X1094103Y1083683D01*
X1093045D01*
X1091371Y1085357D01*
X1090088D01*
X1089060Y1086385D01*
X1088720D01*
G01X1078796D02*
X1078411D01*
X1077383Y1085357D01*
X1074914D01*
X1072410Y1083683D01*
X1070737D01*
X1069709Y1084711D01*
X1067591D01*
G01X1097291Y1098097D02*
X1091901D01*
X1090228Y1096424D01*
X1088719D01*
G01X1078779D02*
X1077063D01*
X1076270Y1097217D01*
Y1098357D01*
X1075590Y1099037D01*
X1073784D01*
X1072844Y1098097D01*
X1067591D01*
G01X1097291Y1111483D02*
X1091901D01*
X1090228Y1109810D01*
X1088461D01*
G01X1079307Y1109778D02*
X1077095D01*
X1076270Y1110603D01*
Y1111743D01*
X1075590Y1112423D01*
X1073784D01*
X1072844Y1111483D01*
X1067591D01*
G01X1097291Y1104790D02*
X1090837D01*
X1089164Y1103117D01*
X1088461D01*
G01X1079307Y1103082D02*
X1076910D01*
X1076270Y1103722D01*
Y1105014D01*
X1075662Y1105622D01*
X1073676D01*
X1072844Y1104790D01*
X1067591D01*
G01X1097291Y1128215D02*
X1090837D01*
X1089164Y1126542D01*
X1088461D01*
G01X1079307Y1126507D02*
X1076910D01*
X1076270Y1127147D01*
Y1128439D01*
X1075662Y1129047D01*
X1073676D01*
X1072844Y1128215D01*
X1067591D01*
G01X1097291Y1118176D02*
X1095139D01*
X1094111Y1119204D01*
X1092510D01*
X1090836Y1120878D01*
X1090101D01*
X1089072Y1119849D01*
X1088461D01*
G01X1079307Y1119807D02*
X1078503D01*
X1077432Y1120878D01*
X1075306D01*
X1072802Y1119204D01*
X1070779D01*
X1069751Y1118176D01*
X1067591D01*
G01X1097291Y1121522D02*
X1095131D01*
X1094103Y1120494D01*
X1093045D01*
X1091371Y1122168D01*
X1090088D01*
X1089060Y1123196D01*
X1088461D01*
G01X1079307Y1123233D02*
X1078448D01*
X1077383Y1122168D01*
X1074914D01*
X1072410Y1120494D01*
X1070737D01*
X1069709Y1121522D01*
X1067591D01*
G01X1097291Y1141601D02*
X1090837D01*
X1089164Y1139928D01*
X1088461D01*
G01X1079307Y1139893D02*
X1076910D01*
X1076270Y1140533D01*
Y1141825D01*
X1075662Y1142433D01*
X1073676D01*
X1072844Y1141601D01*
X1067591D01*
G01X1097291Y1134908D02*
X1091901D01*
X1090228Y1133235D01*
X1088461D01*
G01X1079307Y1133203D02*
X1077095D01*
X1076270Y1134028D01*
Y1135168D01*
X1075590Y1135848D01*
X1073784D01*
X1072844Y1134908D01*
X1067591D01*
G01X1097291Y1148294D02*
X1091901D01*
X1090228Y1146621D01*
X1088461D01*
G01X1079307Y1146589D02*
X1077095D01*
X1076270Y1147414D01*
Y1148554D01*
X1075590Y1149234D01*
X1073784D01*
X1072844Y1148294D01*
X1067591D01*
G01X1097291Y1154987D02*
X1095139D01*
X1094111Y1156015D01*
X1092510D01*
X1090836Y1157689D01*
X1090101D01*
X1089072Y1156660D01*
X1088461D01*
G01X1079307Y1156618D02*
X1078503D01*
X1077432Y1157689D01*
X1075306D01*
X1072802Y1156015D01*
X1070779D01*
X1069751Y1154987D01*
X1067591D01*
G01X1097291Y1158333D02*
X1095131D01*
X1094103Y1157305D01*
X1093045D01*
X1091371Y1158979D01*
X1090088D01*
X1089060Y1160007D01*
X1088461D01*
G01X1079307Y1160044D02*
X1078448D01*
X1077383Y1158979D01*
X1074914D01*
X1072410Y1157305D01*
X1070737D01*
X1069709Y1158333D01*
X1067591D01*
G01X1097291Y1171719D02*
X1091901D01*
X1090228Y1170046D01*
X1088461D01*
G01X1079307Y1170014D02*
X1077095D01*
X1076270Y1170839D01*
Y1171979D01*
X1075590Y1172659D01*
X1073784D01*
X1072844Y1171719D01*
X1067591D01*
G01X1097291Y1165026D02*
X1090837D01*
X1089164Y1163353D01*
X1088461D01*
G01X1079307Y1163318D02*
X1076910D01*
X1076270Y1163958D01*
Y1165250D01*
X1075662Y1165858D01*
X1073676D01*
X1072844Y1165026D01*
X1067591D01*
G01X1097291Y1185105D02*
X1091901D01*
X1090228Y1183432D01*
X1088461D01*
G01X1079307Y1183400D02*
X1077095D01*
X1076270Y1184225D01*
Y1185365D01*
X1075590Y1186045D01*
X1073784D01*
X1072844Y1185105D01*
X1067591D01*
G01X1097291Y1178412D02*
X1090837D01*
X1089164Y1176739D01*
X1088461D01*
G01X1079307Y1176704D02*
X1076910D01*
X1076270Y1177344D01*
Y1178636D01*
X1075662Y1179244D01*
X1073676D01*
X1072844Y1178412D01*
X1067591D01*
G01X1097291Y1191798D02*
X1095139D01*
X1094111Y1192826D01*
X1092510D01*
X1090836Y1194500D01*
X1090101D01*
X1089072Y1193471D01*
X1088461D01*
G01X1079307Y1193429D02*
X1078503D01*
X1077432Y1194500D01*
X1075306D01*
X1072802Y1192826D01*
X1070779D01*
X1069751Y1191798D01*
X1067591D01*
G01X1097291Y1208530D02*
X1091901D01*
X1090228Y1206857D01*
X1088461D01*
G01X1079307Y1206825D02*
X1077095D01*
X1076270Y1207650D01*
Y1208790D01*
X1075590Y1209470D01*
X1073784D01*
X1072844Y1208530D01*
X1067591D01*
G01X1097291Y1201837D02*
X1090837D01*
X1089164Y1200164D01*
X1088461D01*
G01X1079307Y1200129D02*
X1076910D01*
X1076270Y1200769D01*
Y1202061D01*
X1075662Y1202669D01*
X1073676D01*
X1072844Y1201837D01*
X1067591D01*
G01X1097291Y1195144D02*
X1095131D01*
X1094103Y1194116D01*
X1093045D01*
X1091371Y1195790D01*
X1090088D01*
X1089060Y1196818D01*
X1088461D01*
G01X1079307Y1196855D02*
X1078448D01*
X1077383Y1195790D01*
X1074914D01*
X1072410Y1194116D01*
X1070737D01*
X1069709Y1195144D01*
X1067591D01*
G01X1097291Y1221916D02*
X1091901D01*
X1090228Y1220243D01*
X1088461D01*
G01X1079307Y1220211D02*
X1077095D01*
X1076270Y1221036D01*
Y1222176D01*
X1075590Y1222856D01*
X1073784D01*
X1072844Y1221916D01*
X1067591D01*
G01X1097291Y1215223D02*
X1090837D01*
X1089164Y1213550D01*
X1088461D01*
G01X1079307Y1213515D02*
X1076910D01*
X1076270Y1214155D01*
Y1215447D01*
X1075662Y1216055D01*
X1073676D01*
X1072844Y1215223D01*
X1067591D01*
G01X1097291Y1238648D02*
X1090837D01*
X1089164Y1236975D01*
X1088461D01*
G01X1079307Y1236940D02*
X1076910D01*
X1076270Y1237580D01*
Y1238872D01*
X1075662Y1239480D01*
X1073676D01*
X1072844Y1238648D01*
X1067591D01*
G01X1097291Y1228609D02*
X1095139D01*
X1094111Y1229637D01*
X1092510D01*
X1090836Y1231311D01*
X1090101D01*
X1089072Y1230282D01*
X1088461D01*
G01X1079307Y1230240D02*
X1078503D01*
X1077432Y1231311D01*
X1075306D01*
X1072802Y1229637D01*
X1070779D01*
X1069751Y1228609D01*
X1067591D01*
G01X1097291Y1231955D02*
X1095131D01*
X1094103Y1230927D01*
X1093045D01*
X1091371Y1232601D01*
X1090088D01*
X1089060Y1233629D01*
X1088461D01*
G01X1079307Y1233666D02*
X1078448D01*
X1077383Y1232601D01*
X1074914D01*
X1072410Y1230927D01*
X1070737D01*
X1069709Y1231955D01*
X1067591D01*
G01X1097291Y1245341D02*
X1091901D01*
X1090228Y1243668D01*
X1088461D01*
G01X1079307Y1243636D02*
X1077095D01*
X1076270Y1244461D01*
Y1245601D01*
X1075590Y1246281D01*
X1073784D01*
X1072844Y1245341D01*
X1067591D01*
G01X1113433Y770144D02*
X1110220D01*
X1109403Y770961D01*
X1107645D01*
X1106811Y770127D01*
X1105255D01*
X1104749Y770633D01*
Y771230D01*
X1104162Y771817D01*
X1102019D01*
G01X1092865Y771873D02*
X1091472D01*
X1090911Y771312D01*
Y770640D01*
X1090415Y770144D01*
X1083733D01*
G01X1113433Y776837D02*
X1108257D01*
X1107423Y777671D01*
X1105736D01*
X1105077Y777012D01*
Y775730D01*
X1104511Y775164D01*
X1102019D01*
G01X1092865Y775124D02*
X1089962D01*
X1088249Y776837D01*
X1083733D01*
G01X1113433Y786877D02*
X1111502D01*
X1110474Y785849D01*
X1107704D01*
X1105200Y784176D01*
X1103607D01*
X1102579Y785204D01*
X1102019D01*
G01X1092865Y785235D02*
X1092137D01*
X1091088Y784186D01*
X1090144D01*
X1088481Y785849D01*
X1086618D01*
X1085590Y786877D01*
X1083733D01*
G01X1113433Y783530D02*
X1111505D01*
X1110476Y784559D01*
X1108096D01*
X1105592Y782886D01*
X1103604D01*
X1102576Y781858D01*
X1102019D01*
G01X1092865Y781835D02*
X1092088D01*
X1091027Y782896D01*
X1089609D01*
X1087946Y784559D01*
X1086630D01*
X1085601Y783530D01*
X1083733D01*
G01X1113433Y800263D02*
X1108257D01*
X1107423Y801097D01*
X1105736D01*
X1105077Y800438D01*
Y799156D01*
X1104511Y798590D01*
X1102019D01*
G01X1092865Y798550D02*
X1089962D01*
X1088249Y800263D01*
X1083733D01*
G01X1113433Y793570D02*
X1110220D01*
X1109403Y794387D01*
X1107645D01*
X1106811Y793553D01*
X1105255D01*
X1104749Y794059D01*
Y794656D01*
X1104162Y795243D01*
X1102019D01*
G01X1092865Y795299D02*
X1091472D01*
X1090911Y794738D01*
Y794066D01*
X1090415Y793570D01*
X1083733D01*
G01X1113433Y813648D02*
X1108257D01*
X1107423Y814482D01*
X1105736D01*
X1105077Y813823D01*
Y812541D01*
X1104511Y811975D01*
X1102019D01*
G01X1092865Y811935D02*
X1089962D01*
X1088249Y813648D01*
X1083733D01*
G01X1113433Y806955D02*
X1110220D01*
X1109403Y807772D01*
X1107645D01*
X1106811Y806938D01*
X1105255D01*
X1104749Y807444D01*
Y808041D01*
X1104162Y808628D01*
X1102019D01*
G01X1092865Y808684D02*
X1091472D01*
X1090911Y808123D01*
Y807451D01*
X1090415Y806955D01*
X1083733D01*
G01X1113433Y830381D02*
X1110220D01*
X1109403Y831198D01*
X1107645D01*
X1106811Y830364D01*
X1105255D01*
X1104749Y830870D01*
Y831467D01*
X1104162Y832054D01*
X1102019D01*
G01X1092865Y832110D02*
X1091472D01*
X1090911Y831549D01*
Y830877D01*
X1090415Y830381D01*
X1083733D01*
G01X1113433Y823688D02*
X1111502D01*
X1110474Y822660D01*
X1107704D01*
X1105200Y820987D01*
X1103607D01*
X1102579Y822015D01*
X1102019D01*
G01X1092865Y822046D02*
X1092137D01*
X1091088Y820997D01*
X1090144D01*
X1088481Y822660D01*
X1086618D01*
X1085590Y823688D01*
X1083733D01*
G01X1113433Y820341D02*
X1111505D01*
X1110476Y821370D01*
X1108096D01*
X1105592Y819697D01*
X1103604D01*
X1102576Y818669D01*
X1102019D01*
G01X1092865Y818646D02*
X1092088D01*
X1091027Y819707D01*
X1089609D01*
X1087946Y821370D01*
X1086630D01*
X1085601Y820341D01*
X1083733D01*
G01X1113433Y850459D02*
X1108257D01*
X1107423Y851293D01*
X1105736D01*
X1105077Y850634D01*
Y849352D01*
X1104511Y848786D01*
X1102019D01*
G01X1092865Y848746D02*
X1089962D01*
X1088249Y850459D01*
X1083733D01*
G01X1113433Y843766D02*
X1110220D01*
X1109403Y844583D01*
X1107645D01*
X1106811Y843749D01*
X1105255D01*
X1104749Y844255D01*
Y844852D01*
X1104162Y845439D01*
X1102019D01*
G01X1092865Y845495D02*
X1091472D01*
X1090911Y844934D01*
Y844262D01*
X1090415Y843766D01*
X1083733D01*
G01X1113433Y837074D02*
X1108257D01*
X1107423Y837908D01*
X1105736D01*
X1105077Y837249D01*
Y835967D01*
X1104511Y835401D01*
X1102019D01*
G01X1092865Y835361D02*
X1089962D01*
X1088249Y837074D01*
X1083733D01*
G01X1113433Y867192D02*
X1110220D01*
X1109403Y868009D01*
X1107645D01*
X1106811Y867175D01*
X1105255D01*
X1104749Y867681D01*
Y868278D01*
X1104162Y868865D01*
X1102019D01*
G01X1092865Y868921D02*
X1091472D01*
X1090911Y868360D01*
Y867688D01*
X1090415Y867192D01*
X1083733D01*
G01X1113433Y860499D02*
X1111502D01*
X1110474Y859471D01*
X1107704D01*
X1105200Y857798D01*
X1103607D01*
X1102579Y858826D01*
X1102019D01*
G01X1092865Y858857D02*
X1092137D01*
X1091088Y857808D01*
X1090144D01*
X1088481Y859471D01*
X1086618D01*
X1085590Y860499D01*
X1083733D01*
G01X1113433Y857152D02*
X1111505D01*
X1110476Y858181D01*
X1108096D01*
X1105592Y856508D01*
X1103604D01*
X1102576Y855480D01*
X1102019D01*
G01X1092865Y855457D02*
X1092088D01*
X1091027Y856518D01*
X1089609D01*
X1087946Y858181D01*
X1086630D01*
X1085601Y857152D01*
X1083733D01*
G01X1113433Y873885D02*
X1108257D01*
X1107423Y874719D01*
X1105736D01*
X1105077Y874060D01*
Y872778D01*
X1104511Y872212D01*
X1102019D01*
G01X1092865Y872172D02*
X1089962D01*
X1088249Y873885D01*
X1083733D01*
G01X1113433Y880577D02*
X1110220D01*
X1109403Y881394D01*
X1107645D01*
X1106811Y880560D01*
X1105255D01*
X1104749Y881066D01*
Y881663D01*
X1104162Y882250D01*
X1102019D01*
G01X1092865Y882306D02*
X1091472D01*
X1090911Y881745D01*
Y881073D01*
X1090415Y880577D01*
X1083733D01*
G01X1113433Y887270D02*
X1108257D01*
X1107423Y888104D01*
X1105736D01*
X1105077Y887445D01*
Y886163D01*
X1104511Y885597D01*
X1102019D01*
G01X1092865Y885557D02*
X1089962D01*
X1088249Y887270D01*
X1083733D01*
G01X1113433Y897310D02*
X1111502D01*
X1110474Y896282D01*
X1107704D01*
X1105200Y894609D01*
X1103607D01*
X1102579Y895637D01*
X1102019D01*
G01X1092865Y895668D02*
X1092137D01*
X1091088Y894619D01*
X1090144D01*
X1088481Y896282D01*
X1086618D01*
X1085590Y897310D01*
X1083733D01*
G01X1113433Y893963D02*
X1111505D01*
X1110476Y894992D01*
X1108096D01*
X1105592Y893319D01*
X1103604D01*
X1102576Y892291D01*
X1102019D01*
G01X1092865Y892268D02*
X1092088D01*
X1091027Y893329D01*
X1089609D01*
X1087946Y894992D01*
X1086630D01*
X1085601Y893963D01*
X1083733D01*
G01X1113433Y910696D02*
X1108257D01*
X1107423Y911530D01*
X1105736D01*
X1105077Y910871D01*
Y909589D01*
X1104511Y909023D01*
X1102019D01*
G01X1092865Y908983D02*
X1089962D01*
X1088249Y910696D01*
X1083733D01*
G01X1113433Y904003D02*
X1110220D01*
X1109403Y904820D01*
X1107645D01*
X1106811Y903986D01*
X1105255D01*
X1104749Y904492D01*
Y905089D01*
X1104162Y905676D01*
X1102019D01*
G01X1092865Y905732D02*
X1091472D01*
X1090911Y905171D01*
Y904499D01*
X1090415Y904003D01*
X1083733D01*
G01X1113433Y924081D02*
X1108257D01*
X1107423Y924915D01*
X1105736D01*
X1105077Y924256D01*
Y922974D01*
X1104511Y922408D01*
X1102305D01*
G01X1092317D02*
X1089922D01*
X1088249Y924081D01*
X1083733D01*
G01X1113433Y917389D02*
X1109820D01*
X1109324Y917885D01*
X1107524D01*
X1106632Y916993D01*
X1105514D01*
X1104749Y917758D01*
Y918475D01*
X1104162Y919062D01*
X1102273D01*
G01X1092349D02*
X1091472D01*
X1090911Y918501D01*
Y917885D01*
X1090415Y917389D01*
X1083733D01*
G01X1113433Y934121D02*
X1111502D01*
X1110474Y933093D01*
X1107704D01*
X1105200Y931420D01*
X1103607D01*
X1102579Y932448D01*
X1102226D01*
G01X1092302D02*
X1092106D01*
X1091088Y931430D01*
X1090144D01*
X1088481Y933093D01*
X1086618D01*
X1085590Y934121D01*
X1083733D01*
G01X1113433Y930774D02*
X1111505D01*
X1110476Y931803D01*
X1108096D01*
X1105592Y930130D01*
X1103604D01*
X1102575Y929101D01*
X1102226D01*
G01X1092302D02*
X1092066D01*
X1091027Y930140D01*
X1089609D01*
X1087946Y931803D01*
X1086630D01*
X1085601Y930774D01*
X1083733D01*
G01X1113433Y947507D02*
X1108257D01*
X1107156Y948608D01*
X1106003D01*
X1105077Y947682D01*
Y946480D01*
X1104431Y945834D01*
X1102289D01*
G01X1092334D02*
X1089922D01*
X1088249Y947507D01*
X1083733D01*
G01X1113433Y940814D02*
X1109880D01*
X1109443Y941251D01*
X1107625D01*
X1106779Y940405D01*
X1105539D01*
X1104749Y941195D01*
Y941900D01*
X1104162Y942487D01*
X1102290D01*
G01X1092335D02*
X1091472D01*
X1090911Y941926D01*
Y941310D01*
X1090415Y940814D01*
X1083733D01*
G01X1088083Y964239D02*
X1083733D01*
G01X1113433Y977625D02*
X1110220D01*
X1109403Y978442D01*
X1107645D01*
X1106811Y977608D01*
X1105255D01*
X1104749Y978114D01*
Y978711D01*
X1104162Y979298D01*
X1102019D01*
G01X1092865Y979354D02*
X1091472D01*
X1090911Y978793D01*
Y978121D01*
X1090415Y977625D01*
X1083733D01*
G01X1113433Y970932D02*
X1110220D01*
X1109403Y971749D01*
X1107645D01*
X1106811Y970915D01*
X1105255D01*
X1104749Y971421D01*
Y972018D01*
X1104162Y972605D01*
X1102019D01*
G01X1092865Y972661D02*
X1091472D01*
X1090911Y972100D01*
Y971428D01*
X1090415Y970932D01*
X1083733D01*
G01X1113433Y991011D02*
X1110220D01*
X1109403Y991828D01*
X1107645D01*
X1106811Y990994D01*
X1105255D01*
X1104749Y991500D01*
Y992097D01*
X1104162Y992684D01*
X1102019D01*
G01X1092865Y992740D02*
X1091472D01*
X1090911Y992179D01*
Y991507D01*
X1090415Y991011D01*
X1083733D01*
G01X1113433Y984318D02*
X1110220D01*
X1109403Y985135D01*
X1107645D01*
X1106811Y984301D01*
X1105255D01*
X1104749Y984807D01*
Y985404D01*
X1104162Y985991D01*
X1102019D01*
G01X1092865Y986047D02*
X1091472D01*
X1090911Y985486D01*
Y984814D01*
X1090415Y984318D01*
X1083733D01*
G01X1088083Y1021129D02*
X1083733D01*
G01X1088083Y1024475D02*
X1083733D01*
G01X1113433Y1044554D02*
X1110220D01*
X1109403Y1045371D01*
X1107645D01*
X1106811Y1044537D01*
X1105255D01*
X1104749Y1045043D01*
Y1045640D01*
X1104162Y1046227D01*
X1102019D01*
G01X1092865Y1046283D02*
X1091472D01*
X1090911Y1045722D01*
Y1045050D01*
X1090415Y1044554D01*
X1083733D01*
G01X1113433Y1037861D02*
X1110220D01*
X1109403Y1038678D01*
X1107645D01*
X1106811Y1037844D01*
X1105255D01*
X1104749Y1038350D01*
Y1038947D01*
X1104162Y1039534D01*
X1102019D01*
G01X1092865Y1039590D02*
X1091472D01*
X1090911Y1039029D01*
Y1038357D01*
X1090415Y1037861D01*
X1083733D01*
G01X1113433Y1031168D02*
X1110220D01*
X1109403Y1031985D01*
X1107645D01*
X1106811Y1031151D01*
X1105255D01*
X1104749Y1031657D01*
Y1032254D01*
X1104162Y1032841D01*
X1102019D01*
G01X1092865Y1032897D02*
X1091472D01*
X1090911Y1032336D01*
Y1031664D01*
X1090415Y1031168D01*
X1083733D01*
G01X1088083Y1051247D02*
X1083733D01*
G01X1113433Y1071326D02*
X1108257D01*
X1107423Y1072160D01*
X1105736D01*
X1105077Y1071501D01*
Y1070219D01*
X1104511Y1069653D01*
X1102288D01*
G01X1092364D02*
X1089922D01*
X1088249Y1071326D01*
X1083733D01*
G01X1113433Y1064633D02*
X1110220D01*
X1109804Y1065049D01*
X1107728D01*
X1106766Y1064087D01*
X1105539D01*
X1104749Y1064877D01*
Y1065516D01*
X1103959Y1066306D01*
X1102240D01*
G01X1092348D02*
X1091472D01*
X1090911Y1065745D01*
Y1065129D01*
X1090415Y1064633D01*
X1083733D01*
G01X1113433Y1078018D02*
X1111505D01*
X1110476Y1079047D01*
X1108096D01*
X1105592Y1077374D01*
X1103604D01*
X1102575Y1076345D01*
X1102225D01*
G01X1092348D02*
X1092066D01*
X1091027Y1077384D01*
X1089609D01*
X1087946Y1079047D01*
X1086630D01*
X1085601Y1078018D01*
X1083733D01*
G01X1113433Y1094751D02*
X1108257D01*
X1107303Y1095705D01*
X1105856D01*
X1105077Y1094926D01*
Y1093738D01*
X1104417Y1093078D01*
X1102302D01*
G01X1092347D02*
X1089922D01*
X1088249Y1094751D01*
X1083733D01*
G01X1113433Y1088058D02*
X1110220D01*
X1109773Y1088505D01*
X1107859D01*
X1106909Y1087555D01*
X1105539D01*
X1104749Y1088345D01*
Y1089144D01*
X1104162Y1089731D01*
X1102306D01*
G01X1092366D02*
X1091472D01*
X1090911Y1089170D01*
Y1088554D01*
X1090415Y1088058D01*
X1083733D01*
G01X1113433Y1081365D02*
X1111502D01*
X1110474Y1080337D01*
X1107704D01*
X1105200Y1078664D01*
X1103607D01*
X1102579Y1079692D01*
X1102225D01*
G01X1092348D02*
X1092140D01*
X1091133Y1078685D01*
X1090133D01*
X1088481Y1080337D01*
X1086618D01*
X1085590Y1081365D01*
X1083733D01*
G01X1113433Y1108137D02*
X1108257D01*
X1107423Y1108971D01*
X1105736D01*
X1105077Y1108312D01*
Y1107030D01*
X1104511Y1106464D01*
X1102019D01*
G01X1092865Y1106424D02*
X1089962D01*
X1088249Y1108137D01*
X1083733D01*
G01X1113433Y1101444D02*
X1110220D01*
X1109403Y1102261D01*
X1107645D01*
X1106811Y1101427D01*
X1105255D01*
X1104749Y1101933D01*
Y1102530D01*
X1104162Y1103117D01*
X1102019D01*
G01X1092865Y1103173D02*
X1091472D01*
X1090911Y1102612D01*
Y1101940D01*
X1090415Y1101444D01*
X1083733D01*
G01X1113433Y1124869D02*
X1110220D01*
X1109403Y1125686D01*
X1107645D01*
X1106811Y1124852D01*
X1105255D01*
X1104749Y1125358D01*
Y1125955D01*
X1104162Y1126542D01*
X1102019D01*
G01X1092865Y1126598D02*
X1091472D01*
X1090911Y1126037D01*
Y1125365D01*
X1090415Y1124869D01*
X1083733D01*
G01X1113433Y1118176D02*
X1111502D01*
X1110474Y1117148D01*
X1107704D01*
X1105200Y1115475D01*
X1103607D01*
X1102579Y1116503D01*
X1102019D01*
G01X1092865Y1116541D02*
X1092144D01*
X1091088Y1115485D01*
X1090144D01*
X1088481Y1117148D01*
X1086618D01*
X1085590Y1118176D01*
X1083733D01*
G01X1113433Y1114829D02*
X1111505D01*
X1110476Y1115858D01*
X1108096D01*
X1105592Y1114185D01*
X1103604D01*
X1102576Y1113157D01*
X1102019D01*
G01X1092865Y1113134D02*
X1092088D01*
X1091027Y1114195D01*
X1089609D01*
X1087946Y1115858D01*
X1086630D01*
X1085601Y1114829D01*
X1083733D01*
G01X1113433Y1138255D02*
X1110220D01*
X1109403Y1139072D01*
X1107645D01*
X1106811Y1138238D01*
X1105255D01*
X1104749Y1138744D01*
Y1139341D01*
X1104162Y1139928D01*
X1102019D01*
G01X1092865Y1139984D02*
X1091472D01*
X1090911Y1139423D01*
Y1138751D01*
X1090415Y1138255D01*
X1083733D01*
G01X1113433Y1131562D02*
X1108257D01*
X1107423Y1132396D01*
X1105736D01*
X1105077Y1131737D01*
Y1130455D01*
X1104511Y1129889D01*
X1102019D01*
G01X1092865Y1129849D02*
X1089962D01*
X1088249Y1131562D01*
X1083733D01*
G01X1113433Y1144948D02*
X1108257D01*
X1107423Y1145782D01*
X1105736D01*
X1105077Y1145123D01*
Y1143841D01*
X1104511Y1143275D01*
X1102019D01*
G01X1092865Y1143235D02*
X1089962D01*
X1088249Y1144948D01*
X1083733D01*
G01X1113433Y1154987D02*
X1111502D01*
X1110474Y1153959D01*
X1107704D01*
X1105200Y1152286D01*
X1103607D01*
X1102579Y1153314D01*
X1102019D01*
G01X1092865Y1153352D02*
X1092144D01*
X1091088Y1152296D01*
X1090144D01*
X1088481Y1153959D01*
X1086618D01*
X1085590Y1154987D01*
X1083733D01*
G01X1113433Y1151641D02*
X1111504D01*
X1110476Y1152669D01*
X1108096D01*
X1105592Y1150996D01*
X1103604D01*
X1102576Y1149968D01*
X1102019D01*
G01X1092865Y1149945D02*
X1092088D01*
X1091027Y1151006D01*
X1089609D01*
X1087946Y1152669D01*
X1086630D01*
X1085602Y1151641D01*
X1083733D01*
G01X1113433Y1175066D02*
X1110220D01*
X1109403Y1175883D01*
X1107645D01*
X1106811Y1175049D01*
X1105255D01*
X1104749Y1175555D01*
Y1176152D01*
X1104162Y1176739D01*
X1102019D01*
G01X1092865Y1176795D02*
X1091472D01*
X1090911Y1176234D01*
Y1175562D01*
X1090415Y1175066D01*
X1083733D01*
G01X1113433Y1168373D02*
X1108257D01*
X1107423Y1169207D01*
X1105736D01*
X1105077Y1168548D01*
Y1167266D01*
X1104511Y1166700D01*
X1102019D01*
G01X1092865Y1166660D02*
X1089962D01*
X1088249Y1168373D01*
X1083733D01*
G01X1113433Y1161680D02*
X1110220D01*
X1109403Y1162497D01*
X1107645D01*
X1106811Y1161663D01*
X1105255D01*
X1104749Y1162169D01*
Y1162766D01*
X1104162Y1163353D01*
X1102019D01*
G01X1092865Y1163409D02*
X1091472D01*
X1090911Y1162848D01*
Y1162176D01*
X1090415Y1161680D01*
X1083733D01*
G01X1113433Y1181759D02*
X1108257D01*
X1107423Y1182593D01*
X1105736D01*
X1105077Y1181934D01*
Y1180652D01*
X1104511Y1180086D01*
X1102019D01*
G01X1092865Y1180046D02*
X1089962D01*
X1088249Y1181759D01*
X1083733D01*
G01X1113433Y1191798D02*
X1111502D01*
X1110474Y1190770D01*
X1107704D01*
X1105200Y1189097D01*
X1103607D01*
X1102579Y1190125D01*
X1102019D01*
G01X1092865Y1190163D02*
X1092144D01*
X1091088Y1189107D01*
X1090144D01*
X1088481Y1190770D01*
X1086618D01*
X1085590Y1191798D01*
X1083733D01*
G01X1113433Y1188452D02*
X1111504D01*
X1110476Y1189480D01*
X1108096D01*
X1105592Y1187807D01*
X1103604D01*
X1102576Y1186779D01*
X1102019D01*
G01X1092865Y1186756D02*
X1092088D01*
X1091027Y1187817D01*
X1089609D01*
X1087946Y1189480D01*
X1086630D01*
X1085602Y1188452D01*
X1083733D01*
G01X1113433Y1205184D02*
X1108257D01*
X1107423Y1206018D01*
X1105736D01*
X1105077Y1205359D01*
Y1204077D01*
X1104511Y1203511D01*
X1102019D01*
G01X1092865Y1203471D02*
X1089962D01*
X1088249Y1205184D01*
X1083733D01*
G01X1113433Y1198491D02*
X1110220D01*
X1109403Y1199308D01*
X1107645D01*
X1106811Y1198474D01*
X1105255D01*
X1104749Y1198980D01*
Y1199577D01*
X1104162Y1200164D01*
X1102019D01*
G01X1092865Y1200220D02*
X1091472D01*
X1090911Y1199659D01*
Y1198987D01*
X1090415Y1198491D01*
X1083733D01*
G01X1113433Y1218570D02*
X1108257D01*
X1107423Y1219404D01*
X1105736D01*
X1105077Y1218745D01*
Y1217463D01*
X1104511Y1216897D01*
X1102019D01*
G01X1092865Y1216857D02*
X1089962D01*
X1088249Y1218570D01*
X1083733D01*
G01X1113433Y1211877D02*
X1110220D01*
X1109403Y1212694D01*
X1107645D01*
X1106811Y1211860D01*
X1105255D01*
X1104749Y1212366D01*
Y1212963D01*
X1104162Y1213550D01*
X1102019D01*
G01X1092865Y1213606D02*
X1091472D01*
X1090911Y1213045D01*
Y1212373D01*
X1090415Y1211877D01*
X1083733D01*
G01X1113433Y1225263D02*
X1111504D01*
X1110476Y1226291D01*
X1108096D01*
X1105592Y1224618D01*
X1103604D01*
X1102576Y1223590D01*
X1102019D01*
G01X1092865Y1223567D02*
X1092088D01*
X1091027Y1224628D01*
X1089609D01*
X1087946Y1226291D01*
X1086630D01*
X1085602Y1225263D01*
X1083733D01*
G01X1113433Y1241995D02*
X1108257D01*
X1107423Y1242829D01*
X1105736D01*
X1105077Y1242170D01*
Y1240888D01*
X1104511Y1240322D01*
X1102019D01*
G01X1092865Y1240282D02*
X1089962D01*
X1088249Y1241995D01*
X1083733D01*
G01X1113433Y1235302D02*
X1110220D01*
X1109403Y1236119D01*
X1107645D01*
X1106811Y1235285D01*
X1105255D01*
X1104749Y1235791D01*
Y1236388D01*
X1104162Y1236975D01*
X1102019D01*
G01X1092865Y1237031D02*
X1091472D01*
X1090911Y1236470D01*
Y1235798D01*
X1090415Y1235302D01*
X1083733D01*
G01X1113433Y1228609D02*
X1111502D01*
X1110474Y1227581D01*
X1107704D01*
X1105200Y1225908D01*
X1103607D01*
X1102579Y1226936D01*
X1102019D01*
G01X1092865Y1226974D02*
X1092144D01*
X1091088Y1225918D01*
X1090144D01*
X1088481Y1227581D01*
X1086618D01*
X1085590Y1228609D01*
X1083733D01*
G01X1101641Y780184D02*
X1097291D01*
G01X1101641Y773491D02*
X1097291D01*
G01X1101641Y786877D02*
X1097291D01*
G01X1101641Y796916D02*
X1097291D01*
G01X1101641Y790223D02*
X1097291D01*
G01X1101641Y816995D02*
X1097291D01*
G01X1101641Y810302D02*
X1097291D01*
G01X1101641Y803609D02*
X1097291D01*
G01X1101641Y833727D02*
X1097291D01*
G01X1101641Y823688D02*
X1097291D01*
G01X1101641Y827034D02*
X1097291D01*
G01X1101641Y847113D02*
X1097291D01*
G01X1101641Y840420D02*
X1097291D01*
G01X1101641Y853806D02*
X1097291D01*
G01X1101641Y860499D02*
X1097291D01*
G01X1101641Y863845D02*
X1097291D01*
G01X1101641Y883924D02*
X1097291D01*
G01X1101641Y877231D02*
X1097291D01*
G01X1101641Y870538D02*
X1097291D01*
G01X1101641Y890617D02*
X1097291D01*
G01X1101641Y897310D02*
X1097291D01*
G01X1101641Y900656D02*
X1097291D01*
G01X1101641Y914042D02*
X1097291D01*
G01X1101641Y907349D02*
X1097291D01*
G01X1101641Y927428D02*
X1097291D01*
G01X1101641Y920735D02*
X1097291D01*
G01X1101641Y944160D02*
X1097291D01*
G01X1101641Y934121D02*
X1097291D01*
G01X1101641Y937467D02*
X1097291D01*
G01X1101641Y960892D02*
X1097291D01*
G01X1101641Y950853D02*
X1097291D01*
G01X1101641Y957546D02*
X1097291D01*
G01X1101641Y980971D02*
X1097291D01*
G01X1101641Y974278D02*
X1097291D01*
G01X1101641Y967585D02*
X1097291D01*
G01X1101641Y994357D02*
X1097291D01*
G01X1101641Y987664D02*
X1097291D01*
G01X1101641Y1027822D02*
X1097291D01*
G01X1101641Y1021129D02*
X1097291D01*
G01X1101641Y1041207D02*
X1097291D01*
G01X1101641Y1034515D02*
X1097291D01*
G01X1101641Y1061286D02*
X1097291D01*
G01X1101641Y1047900D02*
X1097291D01*
G01X1101641Y1054593D02*
X1097291D01*
G01X1101641Y1074672D02*
X1097291D01*
G01X1101641Y1067979D02*
X1097291D01*
G01X1101641Y1091404D02*
X1097291D01*
G01X1101641Y1081365D02*
X1097291D01*
G01X1101641Y1084711D02*
X1097291D01*
G01X1101641Y1098097D02*
X1097291D01*
G01X1101641Y1111483D02*
X1097291D01*
G01X1101641Y1104790D02*
X1097291D01*
G01X1101641Y1128215D02*
X1097291D01*
G01X1101641Y1118176D02*
X1097291D01*
G01X1101641Y1121522D02*
X1097291D01*
G01X1101641Y1141601D02*
X1097291D01*
G01X1101641Y1134908D02*
X1097291D01*
G01X1101641Y1148294D02*
X1097291D01*
G01X1101641Y1154987D02*
X1097291D01*
G01X1101641Y1158333D02*
X1097291D01*
G01X1101641Y1171719D02*
X1097291D01*
G01X1101641Y1165026D02*
X1097291D01*
G01X1101641Y1185105D02*
X1097291D01*
G01X1101641Y1178412D02*
X1097291D01*
G01X1101641Y1191798D02*
X1097291D01*
G01X1101641Y1208530D02*
X1097291D01*
G01X1101641Y1201837D02*
X1097291D01*
G01X1101641Y1195144D02*
X1097291D01*
G01X1101641Y1221916D02*
X1097291D01*
G01X1101641Y1215223D02*
X1097291D01*
G01X1101641Y1238648D02*
X1097291D01*
G01X1101641Y1228609D02*
X1097291D01*
G01X1101641Y1231955D02*
X1097291D01*
G01X1101641Y1245341D02*
X1097291D01*
G01X1117783Y770144D02*
X1113433D01*
G01X1117783Y776837D02*
X1113433D01*
G01X1117783Y786877D02*
X1113433D01*
G01X1117783Y783530D02*
X1113433D01*
G01X1117783Y800263D02*
X1113433D01*
G01X1117783Y793570D02*
X1113433D01*
G01X1117783Y813648D02*
X1113433D01*
G01X1117783Y806955D02*
X1113433D01*
G01X1117783Y830381D02*
X1113433D01*
G01X1117783Y823688D02*
X1113433D01*
G01X1117783Y820341D02*
X1113433D01*
G01X1117783Y850459D02*
X1113433D01*
G01X1117783Y843766D02*
X1113433D01*
G01X1117783Y837074D02*
X1113433D01*
G01X1117783Y867192D02*
X1113433D01*
G01X1117783Y860499D02*
X1113433D01*
G01X1117783Y857152D02*
X1113433D01*
G01X1117783Y873885D02*
X1113433D01*
G01X1117783Y880577D02*
X1113433D01*
G01X1117783Y887270D02*
X1113433D01*
G01X1117783Y897310D02*
X1113433D01*
G01X1117783Y893963D02*
X1113433D01*
G01X1117783Y910696D02*
X1113433D01*
G01X1117783Y904003D02*
X1113433D01*
G01X1117783Y924081D02*
X1113433D01*
G01X1117783Y917389D02*
X1113433D01*
G01X1117783Y930774D02*
X1113433D01*
G01X1117783Y947507D02*
X1113433D01*
G01X1117783Y940814D02*
X1113433D01*
G01X1117783Y934121D02*
X1113433D01*
G01X1117783Y964239D02*
X1113433D01*
G01X1117783Y977625D02*
X1113433D01*
G01X1117783Y970932D02*
X1113433D01*
G01X1117783Y991011D02*
X1113433D01*
G01X1117783Y984318D02*
X1113433D01*
G01X1117783Y1021129D02*
X1113433D01*
G01X1117783Y1024475D02*
X1113433D01*
G01X1117783Y1044554D02*
X1113433D01*
G01X1117783Y1037861D02*
X1113433D01*
G01X1117783Y1031168D02*
X1113433D01*
G01X1117783Y1051247D02*
X1113433D01*
G01X1117783Y1071326D02*
X1113433D01*
G01X1117783Y1064633D02*
X1113433D01*
G01X1117783Y1078018D02*
X1113433D01*
G01X1117783Y1094751D02*
X1113433D01*
G01X1117783Y1088058D02*
X1113433D01*
G01X1117783Y1081365D02*
X1113433D01*
G01X1117783Y1108137D02*
X1113433D01*
G01X1117783Y1101444D02*
X1113433D01*
G01X1117783Y1124869D02*
X1113433D01*
G01X1117783Y1118176D02*
X1113433D01*
G01X1117783Y1114829D02*
X1113433D01*
G01X1117783Y1138255D02*
X1113433D01*
G01X1117783Y1131562D02*
X1113433D01*
G01X1117783Y1144948D02*
X1113433D01*
G01X1117783Y1154987D02*
X1113433D01*
G01X1117783Y1151641D02*
X1113433D01*
G01X1117783Y1175066D02*
X1113433D01*
G01X1117783Y1168373D02*
X1113433D01*
G01X1117783Y1161680D02*
X1113433D01*
G01X1117783Y1181759D02*
X1113433D01*
G01X1117783Y1191798D02*
X1113433D01*
G01X1117783Y1188452D02*
X1113433D01*
G01X1117783Y1205184D02*
X1113433D01*
G01X1117783Y1198491D02*
X1113433D01*
G01X1117783Y1218570D02*
X1113433D01*
G01X1117783Y1211877D02*
X1113433D01*
G01X1117783Y1225263D02*
X1113433D01*
G01X1117783Y1241995D02*
X1113433D01*
G01X1117783Y1235302D02*
X1113433D01*
G01X1117783Y1228609D02*
X1113433D01*
G01X1156691Y780184D02*
X1151301D01*
X1149628Y778511D01*
X1147861D01*
G01X1138707Y778479D02*
X1136495D01*
X1135670Y779304D01*
Y780444D01*
X1134990Y781124D01*
X1133184D01*
X1132244Y780184D01*
X1126991D01*
G01X1156691Y773491D02*
X1150237D01*
X1148564Y771818D01*
X1147861D01*
G01X1138707Y771783D02*
X1136310D01*
X1135670Y772423D01*
Y773715D01*
X1135062Y774323D01*
X1133076D01*
X1132244Y773491D01*
X1126991D01*
G01X1156691Y786877D02*
X1154539D01*
X1153511Y787905D01*
X1151910D01*
X1150236Y789579D01*
X1149501D01*
X1148472Y788550D01*
X1147861D01*
G01X1138707Y788508D02*
X1137903D01*
X1136832Y789579D01*
X1134706D01*
X1132202Y787905D01*
X1130179D01*
X1129151Y786877D01*
X1126991D01*
G01X1156691Y796916D02*
X1150237D01*
X1148564Y795243D01*
X1147861D01*
G01X1138707Y795208D02*
X1136310D01*
X1135670Y795848D01*
Y797140D01*
X1135062Y797748D01*
X1133076D01*
X1132244Y796916D01*
X1126991D01*
G01X1156691Y790223D02*
X1154531D01*
X1153503Y789195D01*
X1152445D01*
X1150771Y790869D01*
X1149488D01*
X1148460Y791897D01*
X1147861D01*
G01X1138707Y791934D02*
X1137848D01*
X1136783Y790869D01*
X1134314D01*
X1131810Y789195D01*
X1130137D01*
X1129109Y790223D01*
X1126991D01*
G01X1156691Y816995D02*
X1151301D01*
X1149628Y815322D01*
X1147861D01*
G01X1138707Y815290D02*
X1136495D01*
X1135670Y816115D01*
Y817255D01*
X1134990Y817935D01*
X1133184D01*
X1132244Y816995D01*
X1126991D01*
G01X1156691Y810302D02*
X1150237D01*
X1148564Y808629D01*
X1147861D01*
G01X1138707Y808594D02*
X1136310D01*
X1135670Y809234D01*
Y810526D01*
X1135062Y811134D01*
X1133076D01*
X1132244Y810302D01*
X1126991D01*
G01X1156691Y803609D02*
X1151301D01*
X1149628Y801936D01*
X1147861D01*
G01X1138707Y801904D02*
X1136495D01*
X1135670Y802729D01*
Y803869D01*
X1134990Y804549D01*
X1133184D01*
X1132244Y803609D01*
X1126991D01*
G01X1156691Y833727D02*
X1150237D01*
X1148564Y832054D01*
X1147861D01*
G01X1138707Y832019D02*
X1136310D01*
X1135670Y832659D01*
Y833951D01*
X1135062Y834559D01*
X1133076D01*
X1132244Y833727D01*
X1126991D01*
G01X1156691Y823688D02*
X1154539D01*
X1153511Y824716D01*
X1151910D01*
X1150236Y826390D01*
X1149501D01*
X1148472Y825361D01*
X1147861D01*
G01X1138707Y825319D02*
X1137903D01*
X1136832Y826390D01*
X1134706D01*
X1132202Y824716D01*
X1130179D01*
X1129151Y823688D01*
X1126991D01*
G01X1156691Y827034D02*
X1154531D01*
X1153503Y826006D01*
X1152445D01*
X1150771Y827680D01*
X1149488D01*
X1148460Y828708D01*
X1147861D01*
G01X1138707Y828745D02*
X1137848D01*
X1136783Y827680D01*
X1134314D01*
X1131810Y826006D01*
X1130137D01*
X1129109Y827034D01*
X1126991D01*
G01X1156691Y847113D02*
X1150237D01*
X1148564Y845440D01*
X1147861D01*
G01X1138707Y845405D02*
X1136310D01*
X1135670Y846045D01*
Y847337D01*
X1135062Y847945D01*
X1133076D01*
X1132244Y847113D01*
X1126991D01*
G01X1156691Y840420D02*
X1151301D01*
X1149628Y838747D01*
X1147861D01*
G01X1138707Y838715D02*
X1136495D01*
X1135670Y839540D01*
Y840680D01*
X1134990Y841360D01*
X1133184D01*
X1132244Y840420D01*
X1126991D01*
G01X1156691Y853806D02*
X1151301D01*
X1149628Y852133D01*
X1147861D01*
G01X1138707Y852101D02*
X1136495D01*
X1135670Y852926D01*
Y854066D01*
X1134990Y854746D01*
X1133184D01*
X1132244Y853806D01*
X1126991D01*
G01X1156691Y860499D02*
X1154539D01*
X1153511Y861527D01*
X1151910D01*
X1150236Y863201D01*
X1149501D01*
X1148472Y862172D01*
X1147861D01*
G01X1138707Y862130D02*
X1137903D01*
X1136832Y863201D01*
X1134705D01*
X1132202Y861527D01*
X1130179D01*
X1129151Y860499D01*
X1126991D01*
G01X1156691Y863845D02*
X1154531D01*
X1153503Y862817D01*
X1152445D01*
X1150771Y864491D01*
X1149488D01*
X1148460Y865519D01*
X1147862D01*
G01X1138708Y865555D02*
X1138707Y865556D01*
X1137848D01*
X1136783Y864491D01*
X1134313D01*
X1131810Y862817D01*
X1130137D01*
X1129109Y863845D01*
X1126991D01*
G01X1156691Y883924D02*
X1150237D01*
X1148564Y882251D01*
X1147861D01*
G01X1138707Y882216D02*
X1136310D01*
X1135670Y882856D01*
Y884148D01*
X1135062Y884756D01*
X1133076D01*
X1132244Y883924D01*
X1126991D01*
G01X1156691Y877231D02*
X1151301D01*
X1149628Y875558D01*
X1147861D01*
G01X1138707Y875526D02*
X1136495D01*
X1135670Y876351D01*
Y877491D01*
X1134990Y878171D01*
X1133184D01*
X1132244Y877231D01*
X1126991D01*
G01X1156691Y870538D02*
X1150237D01*
X1148564Y868865D01*
X1147861D01*
G01X1138707Y868830D02*
X1136310D01*
X1135670Y869470D01*
Y870762D01*
X1135062Y871370D01*
X1133076D01*
X1132244Y870538D01*
X1126991D01*
G01X1156691Y890617D02*
X1151301D01*
X1149628Y888944D01*
X1147861D01*
G01X1138707Y888912D02*
X1136495D01*
X1135670Y889737D01*
Y890877D01*
X1134990Y891557D01*
X1133184D01*
X1132244Y890617D01*
X1126991D01*
G01X1156691Y897310D02*
X1154539D01*
X1153511Y898338D01*
X1151910D01*
X1150236Y900012D01*
X1149501D01*
X1148472Y898983D01*
X1147861D01*
G01X1138707Y898941D02*
X1137903D01*
X1136832Y900012D01*
X1134706D01*
X1132202Y898338D01*
X1130179D01*
X1129151Y897310D01*
X1126991D01*
G01X1156691Y900656D02*
X1154531D01*
X1153503Y899628D01*
X1152445D01*
X1150771Y901302D01*
X1149488D01*
X1148460Y902330D01*
X1147861D01*
G01X1138707Y902367D02*
X1137848D01*
X1136783Y901302D01*
X1134314D01*
X1131810Y899628D01*
X1130137D01*
X1129109Y900656D01*
X1126991D01*
G01X1156691Y914042D02*
X1151301D01*
X1149628Y912369D01*
X1147861D01*
G01X1138707Y912337D02*
X1136495D01*
X1135670Y913162D01*
Y914302D01*
X1134990Y914982D01*
X1133184D01*
X1132244Y914042D01*
X1126991D01*
G01X1156691Y907349D02*
X1150237D01*
X1148564Y905676D01*
X1147861D01*
G01X1138707Y905641D02*
X1136310D01*
X1135670Y906281D01*
Y907573D01*
X1135062Y908181D01*
X1133076D01*
X1132244Y907349D01*
X1126991D01*
G01X1156691Y927428D02*
X1151301D01*
X1149628Y925755D01*
X1147861D01*
G01X1138707Y925723D02*
X1136495D01*
X1135670Y926548D01*
Y927688D01*
X1134990Y928368D01*
X1133184D01*
X1132244Y927428D01*
X1126991D01*
G01X1156691Y920735D02*
X1150237D01*
X1148564Y919062D01*
X1147861D01*
G01X1138707Y919027D02*
X1136310D01*
X1135670Y919667D01*
Y920959D01*
X1135062Y921567D01*
X1133076D01*
X1132244Y920735D01*
X1126991D01*
G01X1156691Y944160D02*
X1150237D01*
X1148564Y942487D01*
X1147861D01*
G01X1138707Y942452D02*
X1136310D01*
X1135670Y943092D01*
Y944384D01*
X1135062Y944992D01*
X1133076D01*
X1132244Y944160D01*
X1126991D01*
G01X1156691Y934121D02*
X1154539D01*
X1153511Y935149D01*
X1151910D01*
X1150236Y936823D01*
X1149501D01*
X1148472Y935794D01*
X1147861D01*
G01X1138707Y935752D02*
X1137903D01*
X1136832Y936823D01*
X1134706D01*
X1132202Y935149D01*
X1130179D01*
X1129151Y934121D01*
X1126991D01*
G01X1156691Y937467D02*
X1154531D01*
X1153503Y936439D01*
X1152445D01*
X1150771Y938113D01*
X1149488D01*
X1148460Y939141D01*
X1147862D01*
G01X1138708Y939171D02*
X1137841D01*
X1136783Y938113D01*
X1134314D01*
X1131810Y936439D01*
X1130137D01*
X1129109Y937467D01*
X1126991D01*
G01X1131341Y960892D02*
X1126991D01*
G01X1156691Y950853D02*
X1151301D01*
X1149628Y949180D01*
X1147861D01*
G01X1138707Y949148D02*
X1136495D01*
X1135670Y949973D01*
Y951113D01*
X1134990Y951793D01*
X1133184D01*
X1132244Y950853D01*
X1126991D01*
G01X1131341Y957546D02*
X1126991D01*
G01X1156691Y980971D02*
X1150237D01*
X1148564Y979298D01*
X1147861D01*
G01X1138707Y979263D02*
X1136310D01*
X1135670Y979903D01*
Y981195D01*
X1135062Y981803D01*
X1133076D01*
X1132244Y980971D01*
X1126991D01*
G01X1156691Y974278D02*
X1150237D01*
X1148564Y972605D01*
X1147861D01*
G01X1138707Y972570D02*
X1136310D01*
X1135670Y973210D01*
Y974502D01*
X1135062Y975110D01*
X1133076D01*
X1132244Y974278D01*
X1126991D01*
G01X1131341Y967585D02*
X1126991D01*
G01X1156691Y994357D02*
X1150237D01*
X1148564Y992684D01*
X1147861D01*
G01X1138707Y992649D02*
X1136310D01*
X1135670Y993289D01*
Y994581D01*
X1135062Y995189D01*
X1133076D01*
X1132244Y994357D01*
X1126991D01*
G01X1156691Y987664D02*
X1150237D01*
X1148564Y985991D01*
X1147861D01*
G01X1138707Y985956D02*
X1136310D01*
X1135670Y986596D01*
Y987888D01*
X1135062Y988496D01*
X1133076D01*
X1132244Y987664D01*
X1126991D01*
G01X1156691Y1027822D02*
X1150237D01*
X1148564Y1026149D01*
X1147861D01*
G01X1138707Y1026114D02*
X1136310D01*
X1135670Y1026754D01*
Y1028046D01*
X1135062Y1028654D01*
X1133076D01*
X1132244Y1027822D01*
X1126991D01*
G01X1156691Y1021129D02*
X1149973D01*
X1148300Y1019456D01*
X1147861D01*
G01X1138707Y1019510D02*
X1136223D01*
X1136222Y1019509D01*
X1135670Y1020061D01*
Y1021199D01*
X1134799Y1022070D01*
X1133185D01*
X1132244Y1021129D01*
X1126991D01*
G01X1156691Y1041207D02*
X1150237D01*
X1148564Y1039534D01*
X1147861D01*
G01X1138707Y1039499D02*
X1136310D01*
X1135670Y1040139D01*
Y1041431D01*
X1135062Y1042039D01*
X1133076D01*
X1132244Y1041207D01*
X1126991D01*
G01X1156691Y1034515D02*
X1150237D01*
X1148564Y1032842D01*
X1147861D01*
G01X1138707Y1032807D02*
X1136310D01*
X1135670Y1033447D01*
Y1034739D01*
X1135062Y1035347D01*
X1133076D01*
X1132244Y1034515D01*
X1126991D01*
G01X1156691Y1061286D02*
X1150237D01*
X1148564Y1059613D01*
X1148152D01*
G01X1138180D02*
X1136310D01*
X1135670Y1060253D01*
Y1061510D01*
X1135062Y1062118D01*
X1133076D01*
X1132244Y1061286D01*
X1126991D01*
G01X1156691Y1047900D02*
X1150237D01*
X1148564Y1046227D01*
X1147861D01*
G01X1138707Y1046192D02*
X1136310D01*
X1135670Y1046832D01*
Y1048124D01*
X1135062Y1048732D01*
X1133076D01*
X1132244Y1047900D01*
X1126991D01*
G01X1131341Y1054593D02*
X1126991D01*
G01X1156691Y1074672D02*
X1151301D01*
X1149628Y1072999D01*
X1147861D01*
G01X1138707Y1072967D02*
X1136495D01*
X1135670Y1073792D01*
Y1074932D01*
X1134990Y1075612D01*
X1133184D01*
X1132244Y1074672D01*
X1126991D01*
G01X1156691Y1067979D02*
X1150237D01*
X1148564Y1066306D01*
X1147861D01*
G01X1138707Y1066271D02*
X1136310D01*
X1135670Y1066911D01*
Y1068203D01*
X1135062Y1068811D01*
X1133076D01*
X1132244Y1067979D01*
X1126991D01*
G01X1156691Y1091404D02*
X1150237D01*
X1148564Y1089731D01*
X1147861D01*
G01X1138707Y1089696D02*
X1136310D01*
X1135670Y1090336D01*
Y1091628D01*
X1135062Y1092236D01*
X1133076D01*
X1132244Y1091404D01*
X1126991D01*
G01X1156691Y1081365D02*
X1154539D01*
X1153511Y1082393D01*
X1151910D01*
X1150236Y1084067D01*
X1149501D01*
X1148472Y1083038D01*
X1147861D01*
G01X1138707Y1082996D02*
X1137903D01*
X1136832Y1084067D01*
X1134706D01*
X1132202Y1082393D01*
X1130179D01*
X1129151Y1081365D01*
X1126991D01*
G01X1156691Y1084711D02*
X1154531D01*
X1153503Y1083683D01*
X1152445D01*
X1150771Y1085357D01*
X1149488D01*
X1148460Y1086385D01*
X1147861D01*
G01X1138707Y1086422D02*
X1137848D01*
X1136783Y1085357D01*
X1134314D01*
X1131810Y1083683D01*
X1130137D01*
X1129109Y1084711D01*
X1126991D01*
G01X1156691Y1098097D02*
X1151301D01*
X1149628Y1096424D01*
X1147861D01*
G01X1138707Y1096392D02*
X1136495D01*
X1135670Y1097217D01*
Y1098357D01*
X1134990Y1099037D01*
X1133184D01*
X1132244Y1098097D01*
X1126991D01*
G01X1156691Y1111483D02*
X1151301D01*
X1149628Y1109810D01*
X1147861D01*
G01X1138707Y1109778D02*
X1136495D01*
X1135670Y1110603D01*
Y1111743D01*
X1134990Y1112423D01*
X1133184D01*
X1132244Y1111483D01*
X1126991D01*
G01X1156691Y1104790D02*
X1150237D01*
X1148564Y1103117D01*
X1147861D01*
G01X1138707Y1103082D02*
X1136310D01*
X1135670Y1103722D01*
Y1105014D01*
X1135062Y1105622D01*
X1133076D01*
X1132244Y1104790D01*
X1126991D01*
G01X1156691Y1128215D02*
X1150237D01*
X1148564Y1126542D01*
X1147861D01*
G01X1138707Y1126507D02*
X1136310D01*
X1135670Y1127147D01*
Y1128439D01*
X1135062Y1129047D01*
X1133076D01*
X1132244Y1128215D01*
X1126991D01*
G01X1156691Y1118176D02*
X1154539D01*
X1153511Y1119204D01*
X1151910D01*
X1150236Y1120878D01*
X1149501D01*
X1148472Y1119849D01*
X1147861D01*
G01X1138707Y1119807D02*
X1137903D01*
X1136832Y1120878D01*
X1134706D01*
X1132202Y1119204D01*
X1130179D01*
X1129151Y1118176D01*
X1126991D01*
G01X1156691Y1121522D02*
X1154531D01*
X1153503Y1120494D01*
X1152445D01*
X1150771Y1122168D01*
X1149488D01*
X1148460Y1123196D01*
X1147861D01*
G01X1138707Y1123233D02*
X1137848D01*
X1136783Y1122168D01*
X1134314D01*
X1131810Y1120494D01*
X1130137D01*
X1129109Y1121522D01*
X1126991D01*
G01X1156691Y1141601D02*
X1150237D01*
X1148564Y1139928D01*
X1147861D01*
G01X1138707Y1139893D02*
X1136310D01*
X1135670Y1140533D01*
Y1141825D01*
X1135062Y1142433D01*
X1133076D01*
X1132244Y1141601D01*
X1126991D01*
G01X1156691Y1134908D02*
X1151301D01*
X1149628Y1133235D01*
X1147861D01*
G01X1138707Y1133203D02*
X1136495D01*
X1135670Y1134028D01*
Y1135168D01*
X1134990Y1135848D01*
X1133184D01*
X1132244Y1134908D01*
X1126991D01*
G01X1156691Y1148294D02*
X1151301D01*
X1149628Y1146621D01*
X1147861D01*
G01X1138707Y1146589D02*
X1136495D01*
X1135670Y1147414D01*
Y1148554D01*
X1134990Y1149234D01*
X1133184D01*
X1132244Y1148294D01*
X1126991D01*
G01X1156691Y1154987D02*
X1154539D01*
X1153511Y1156015D01*
X1151910D01*
X1150236Y1157689D01*
X1149501D01*
X1148472Y1156660D01*
X1147861D01*
G01X1138707Y1156618D02*
X1137903D01*
X1136832Y1157689D01*
X1134706D01*
X1132202Y1156015D01*
X1130179D01*
X1129151Y1154987D01*
X1126991D01*
G01X1156691Y1158333D02*
X1154531D01*
X1153503Y1157305D01*
X1152445D01*
X1150771Y1158979D01*
X1149488D01*
X1148460Y1160007D01*
X1147861D01*
G01X1138707Y1160044D02*
X1137848D01*
X1136783Y1158979D01*
X1134314D01*
X1131810Y1157305D01*
X1130137D01*
X1129109Y1158333D01*
X1126991D01*
G01X1156691Y1171719D02*
X1151301D01*
X1149628Y1170046D01*
X1147861D01*
G01X1138707Y1170014D02*
X1136495D01*
X1135670Y1170839D01*
Y1171979D01*
X1134990Y1172659D01*
X1133184D01*
X1132244Y1171719D01*
X1126991D01*
G01X1156691Y1165026D02*
X1150237D01*
X1148564Y1163353D01*
X1147861D01*
G01X1138707Y1163318D02*
X1136310D01*
X1135670Y1163958D01*
Y1165250D01*
X1135062Y1165858D01*
X1133076D01*
X1132244Y1165026D01*
X1126991D01*
G01X1156691Y1185105D02*
X1151301D01*
X1149628Y1183432D01*
X1147861D01*
G01X1138707Y1183400D02*
X1136495D01*
X1135670Y1184225D01*
Y1185365D01*
X1134990Y1186045D01*
X1133184D01*
X1132244Y1185105D01*
X1126991D01*
G01X1156691Y1178412D02*
X1150237D01*
X1148564Y1176739D01*
X1147861D01*
G01X1138707Y1176704D02*
X1136310D01*
X1135670Y1177344D01*
Y1178636D01*
X1135062Y1179244D01*
X1133076D01*
X1132244Y1178412D01*
X1126991D01*
G01X1156691Y1191798D02*
X1154539D01*
X1153511Y1192826D01*
X1151910D01*
X1150236Y1194500D01*
X1149501D01*
X1148472Y1193471D01*
X1147861D01*
G01X1138707Y1193429D02*
X1137903D01*
X1136832Y1194500D01*
X1134706D01*
X1132202Y1192826D01*
X1130179D01*
X1129151Y1191798D01*
X1126991D01*
G01X1156691Y1208530D02*
X1151301D01*
X1149628Y1206857D01*
X1147861D01*
G01X1138707Y1206825D02*
X1136495D01*
X1135670Y1207650D01*
Y1208790D01*
X1134990Y1209470D01*
X1133184D01*
X1132244Y1208530D01*
X1126991D01*
G01X1156691Y1201837D02*
X1150237D01*
X1148564Y1200164D01*
X1147861D01*
G01X1138707Y1200129D02*
X1136310D01*
X1135670Y1200769D01*
Y1202061D01*
X1135062Y1202669D01*
X1133076D01*
X1132244Y1201837D01*
X1126991D01*
G01X1156691Y1195144D02*
X1154531D01*
X1153503Y1194116D01*
X1152445D01*
X1150771Y1195790D01*
X1149488D01*
X1148460Y1196818D01*
X1147861D01*
G01X1138707Y1196855D02*
X1137848D01*
X1136783Y1195790D01*
X1134314D01*
X1131810Y1194116D01*
X1130137D01*
X1129109Y1195144D01*
X1126991D01*
G01X1156691Y1221916D02*
X1151301D01*
X1149628Y1220243D01*
X1147861D01*
G01X1138707Y1220211D02*
X1136495D01*
X1135670Y1221036D01*
Y1222176D01*
X1134990Y1222856D01*
X1133184D01*
X1132244Y1221916D01*
X1126991D01*
G01X1156691Y1215223D02*
X1150237D01*
X1148564Y1213550D01*
X1147861D01*
G01X1138707Y1213515D02*
X1136310D01*
X1135670Y1214155D01*
Y1215447D01*
X1135062Y1216055D01*
X1133076D01*
X1132244Y1215223D01*
X1126991D01*
G01X1156691Y1238648D02*
X1150237D01*
X1148564Y1236975D01*
X1147861D01*
G01X1138707Y1236940D02*
X1136310D01*
X1135670Y1237580D01*
Y1238872D01*
X1135062Y1239480D01*
X1133076D01*
X1132244Y1238648D01*
X1126991D01*
G01X1156691Y1228609D02*
X1154539D01*
X1153511Y1229637D01*
X1151910D01*
X1150236Y1231311D01*
X1149501D01*
X1148472Y1230282D01*
X1147861D01*
G01X1138707Y1230240D02*
X1137903D01*
X1136832Y1231311D01*
X1134706D01*
X1132202Y1229637D01*
X1130179D01*
X1129151Y1228609D01*
X1126991D01*
G01X1156691Y1231955D02*
X1154531D01*
X1153503Y1230927D01*
X1152445D01*
X1150771Y1232601D01*
X1149488D01*
X1148460Y1233629D01*
X1147861D01*
G01X1138707Y1233666D02*
X1137848D01*
X1136783Y1232601D01*
X1134314D01*
X1131810Y1230927D01*
X1130137D01*
X1129109Y1231955D01*
X1126991D01*
G01X1156691Y1245341D02*
X1150537D01*
X1148864Y1243668D01*
X1147861D01*
G01X1138707Y1243636D02*
X1136495D01*
X1135670Y1244461D01*
Y1245601D01*
X1134990Y1246281D01*
X1133184D01*
X1132244Y1245341D01*
X1126991D01*
G01X1172833Y770144D02*
X1169620D01*
X1168803Y770961D01*
X1167045D01*
X1166211Y770127D01*
X1164655D01*
X1164149Y770633D01*
Y771230D01*
X1163562Y771817D01*
X1161419D01*
G01X1152265Y771873D02*
X1150872D01*
X1150311Y771312D01*
Y770640D01*
X1149815Y770144D01*
X1143133D01*
G01X1172833Y776837D02*
X1167657D01*
X1166823Y777671D01*
X1165136D01*
X1164477Y777012D01*
Y775730D01*
X1163911Y775164D01*
X1161419D01*
G01X1152265Y775124D02*
X1149362D01*
X1147649Y776837D01*
X1143133D01*
G01X1172833Y786877D02*
X1170902D01*
X1169874Y785849D01*
X1167104D01*
X1164600Y784176D01*
X1163007D01*
X1161979Y785204D01*
X1161419D01*
G01X1152265Y785235D02*
X1151537D01*
X1150488Y784186D01*
X1149544D01*
X1147881Y785849D01*
X1146018D01*
X1144990Y786877D01*
X1143133D01*
G01X1172833Y783530D02*
X1170905D01*
X1169876Y784559D01*
X1167496D01*
X1164992Y782886D01*
X1163004D01*
X1161976Y781858D01*
X1161419D01*
G01X1152265Y781835D02*
X1151488D01*
X1150427Y782896D01*
X1149009D01*
X1147346Y784559D01*
X1146030D01*
X1145001Y783530D01*
X1143133D01*
G01X1172833Y800263D02*
X1167657D01*
X1166823Y801097D01*
X1165136D01*
X1164477Y800438D01*
Y799156D01*
X1163911Y798590D01*
X1161419D01*
G01X1152265Y798550D02*
X1149362D01*
X1147649Y800263D01*
X1143133D01*
G01X1172833Y793570D02*
X1169620D01*
X1168803Y794387D01*
X1167045D01*
X1166211Y793553D01*
X1164655D01*
X1164149Y794059D01*
Y794656D01*
X1163562Y795243D01*
X1161419D01*
G01X1152265Y795299D02*
X1150872D01*
X1150311Y794738D01*
Y794066D01*
X1149815Y793570D01*
X1143133D01*
G01X1172833Y813648D02*
X1167657D01*
X1166823Y814482D01*
X1165136D01*
X1164477Y813823D01*
Y812541D01*
X1163911Y811975D01*
X1161419D01*
G01X1152265Y811935D02*
X1149362D01*
X1147649Y813648D01*
X1143133D01*
G01X1172833Y806955D02*
X1169620D01*
X1168803Y807772D01*
X1167045D01*
X1166211Y806938D01*
X1164655D01*
X1164149Y807444D01*
Y808041D01*
X1163562Y808628D01*
X1161419D01*
G01X1152265Y808684D02*
X1150872D01*
X1150311Y808123D01*
Y807451D01*
X1149815Y806955D01*
X1143133D01*
G01X1172833Y820341D02*
X1170905D01*
X1169876Y821370D01*
X1167496D01*
X1164992Y819697D01*
X1163004D01*
X1161976Y818669D01*
X1161419D01*
G01X1152265Y818646D02*
X1151488D01*
X1150427Y819707D01*
X1149009D01*
X1147346Y821370D01*
X1146030D01*
X1145001Y820341D01*
X1143133D01*
G01X1172833Y837074D02*
X1167657D01*
X1166823Y837908D01*
X1165136D01*
X1164477Y837249D01*
Y835967D01*
X1163911Y835401D01*
X1161419D01*
G01X1152265Y835361D02*
X1149362D01*
X1147649Y837074D01*
X1143133D01*
G01X1172833Y830381D02*
X1169620D01*
X1168803Y831198D01*
X1167045D01*
X1166211Y830364D01*
X1164655D01*
X1164149Y830870D01*
Y831467D01*
X1163562Y832054D01*
X1161419D01*
G01X1152265Y832110D02*
X1150872D01*
X1150311Y831549D01*
Y830877D01*
X1149815Y830381D01*
X1143133D01*
G01X1172833Y823688D02*
X1170902D01*
X1169874Y822660D01*
X1167104D01*
X1164600Y820987D01*
X1163007D01*
X1161979Y822015D01*
X1161419D01*
G01X1152265Y822046D02*
X1151537D01*
X1150488Y820997D01*
X1149544D01*
X1147881Y822660D01*
X1146018D01*
X1144990Y823688D01*
X1143133D01*
G01X1172833Y850459D02*
X1167657D01*
X1166823Y851293D01*
X1165136D01*
X1164477Y850634D01*
Y849352D01*
X1163911Y848786D01*
X1161419D01*
G01X1152265Y848746D02*
X1149362D01*
X1147649Y850459D01*
X1143133D01*
G01X1172833Y843766D02*
X1169620D01*
X1168803Y844583D01*
X1167045D01*
X1166211Y843749D01*
X1164655D01*
X1164149Y844255D01*
Y844852D01*
X1163562Y845439D01*
X1161419D01*
G01X1152265Y845495D02*
X1150872D01*
X1150311Y844934D01*
Y844262D01*
X1149815Y843766D01*
X1143133D01*
G01X1172833Y867192D02*
X1169620D01*
X1168803Y868009D01*
X1167045D01*
X1166211Y867175D01*
X1164655D01*
X1164149Y867681D01*
Y868278D01*
X1163562Y868865D01*
X1161419D01*
G01X1152265Y868921D02*
X1150872D01*
X1150311Y868360D01*
Y867688D01*
X1149815Y867192D01*
X1143133D01*
G01X1172833Y860499D02*
X1170902D01*
X1169874Y859471D01*
X1167104D01*
X1164600Y857798D01*
X1163007D01*
X1161979Y858826D01*
X1161419D01*
G01X1152265Y858857D02*
X1151537D01*
X1150488Y857808D01*
X1149544D01*
X1147881Y859471D01*
X1146018D01*
X1144990Y860499D01*
X1143133D01*
G01X1172833Y857152D02*
X1170905D01*
X1169876Y858181D01*
X1167496D01*
X1164992Y856508D01*
X1163004D01*
X1161976Y855480D01*
X1161419D01*
G01X1152265Y855457D02*
X1151488D01*
X1150427Y856518D01*
X1149009D01*
X1147346Y858181D01*
X1146030D01*
X1145001Y857152D01*
X1143133D01*
G01X1172833Y873885D02*
X1167657D01*
X1166823Y874719D01*
X1165136D01*
X1164477Y874060D01*
Y872778D01*
X1163911Y872212D01*
X1161419D01*
G01X1152265Y872172D02*
X1149362D01*
X1147649Y873885D01*
X1143133D01*
G01X1172833Y880577D02*
X1169620D01*
X1168803Y881394D01*
X1167045D01*
X1166211Y880560D01*
X1164655D01*
X1164149Y881066D01*
Y881663D01*
X1163562Y882250D01*
X1161419D01*
G01X1152265Y882306D02*
X1150872D01*
X1150311Y881745D01*
Y881073D01*
X1149815Y880577D01*
X1143133D01*
G01X1172833Y887270D02*
X1167657D01*
X1166823Y888104D01*
X1165136D01*
X1164477Y887445D01*
Y886163D01*
X1163911Y885597D01*
X1161419D01*
G01X1152265Y885557D02*
X1149362D01*
X1147649Y887270D01*
X1143133D01*
G01X1172833Y897310D02*
X1170902D01*
X1169874Y896282D01*
X1167104D01*
X1164600Y894609D01*
X1163007D01*
X1161979Y895637D01*
X1161419D01*
G01X1152265Y895668D02*
X1151537D01*
X1150488Y894619D01*
X1149544D01*
X1147881Y896282D01*
X1146018D01*
X1144990Y897310D01*
X1143133D01*
G01X1172833Y893963D02*
X1170905D01*
X1169876Y894992D01*
X1167496D01*
X1164992Y893319D01*
X1163004D01*
X1161976Y892291D01*
X1161419D01*
G01X1152265Y892268D02*
X1151488D01*
X1150427Y893329D01*
X1149009D01*
X1147346Y894992D01*
X1146030D01*
X1145001Y893963D01*
X1143133D01*
G01X1172833Y910696D02*
X1167657D01*
X1166823Y911530D01*
X1165136D01*
X1164477Y910871D01*
Y909589D01*
X1163911Y909023D01*
X1161419D01*
G01X1152265Y908983D02*
X1149362D01*
X1147649Y910696D01*
X1143133D01*
G01X1172833Y904003D02*
X1169620D01*
X1168803Y904820D01*
X1167045D01*
X1166211Y903986D01*
X1164655D01*
X1164149Y904492D01*
Y905089D01*
X1163562Y905676D01*
X1161419D01*
G01X1152265Y905732D02*
X1150872D01*
X1150311Y905171D01*
Y904499D01*
X1149815Y904003D01*
X1143133D01*
G01X1172833Y924081D02*
X1167657D01*
X1166823Y924915D01*
X1165136D01*
X1164477Y924256D01*
Y922974D01*
X1163911Y922408D01*
X1161419D01*
G01X1152265Y922368D02*
X1149362D01*
X1147649Y924081D01*
X1143133D01*
G01X1172833Y917389D02*
X1169620D01*
X1168803Y918206D01*
X1167045D01*
X1166211Y917372D01*
X1164655D01*
X1164149Y917878D01*
Y918475D01*
X1163562Y919062D01*
X1161419D01*
G01X1152265Y919118D02*
X1150872D01*
X1150311Y918557D01*
Y917885D01*
X1149815Y917389D01*
X1143133D01*
G01X1172833Y934121D02*
X1170902D01*
X1169874Y933093D01*
X1167104D01*
X1164600Y931420D01*
X1163007D01*
X1161979Y932448D01*
X1161419D01*
G01X1152265Y932479D02*
X1151537D01*
X1150488Y931430D01*
X1149544D01*
X1147881Y933093D01*
X1146018D01*
X1144990Y934121D01*
X1143133D01*
G01X1172833Y930774D02*
X1170905D01*
X1169876Y931803D01*
X1167496D01*
X1164992Y930130D01*
X1163004D01*
X1161976Y929102D01*
X1161419D01*
G01X1152265Y929079D02*
X1151488D01*
X1150427Y930140D01*
X1149009D01*
X1147346Y931803D01*
X1146030D01*
X1145001Y930774D01*
X1143133D01*
G01X1172833Y947507D02*
X1167657D01*
X1166823Y948341D01*
X1165136D01*
X1164477Y947682D01*
Y946400D01*
X1163911Y945834D01*
X1161419D01*
G01X1152265Y945794D02*
X1149362D01*
X1147649Y947507D01*
X1143133D01*
G01X1172833Y940814D02*
X1169620D01*
X1168803Y941631D01*
X1167045D01*
X1166211Y940797D01*
X1164655D01*
X1164149Y941303D01*
Y941900D01*
X1163562Y942487D01*
X1161419D01*
G01X1152265Y942543D02*
X1150872D01*
X1150311Y941982D01*
Y941310D01*
X1149815Y940814D01*
X1143133D01*
G01X1147483Y964239D02*
X1143133D01*
G01X1172833Y977625D02*
X1169620D01*
X1168803Y978442D01*
X1167045D01*
X1166211Y977608D01*
X1164655D01*
X1164149Y978114D01*
Y978711D01*
X1163562Y979298D01*
X1161419D01*
G01X1152265Y979354D02*
X1150872D01*
X1150311Y978793D01*
Y978121D01*
X1149815Y977625D01*
X1143133D01*
G01X1172833Y970932D02*
X1169620D01*
X1168803Y971749D01*
X1167045D01*
X1166211Y970915D01*
X1164655D01*
X1164149Y971421D01*
Y972018D01*
X1163562Y972605D01*
X1161419D01*
G01X1152265Y972661D02*
X1150872D01*
X1150311Y972100D01*
Y971428D01*
X1149815Y970932D01*
X1143133D01*
G01X1172833Y991011D02*
X1169620D01*
X1168803Y991828D01*
X1167045D01*
X1166211Y990994D01*
X1164655D01*
X1164149Y991500D01*
Y992097D01*
X1163562Y992684D01*
X1161419D01*
G01X1152265Y992740D02*
X1150872D01*
X1150311Y992179D01*
Y991507D01*
X1149815Y991011D01*
X1143133D01*
G01X1172833Y984318D02*
X1169620D01*
X1168803Y985135D01*
X1167045D01*
X1166211Y984301D01*
X1164655D01*
X1164149Y984807D01*
Y985404D01*
X1163562Y985991D01*
X1161419D01*
G01X1152265Y986047D02*
X1150872D01*
X1150311Y985486D01*
Y984814D01*
X1149815Y984318D01*
X1143133D01*
G01X1147483Y1021129D02*
X1143133D01*
G01X1147483Y1024475D02*
X1143133D01*
G01X1172833Y1031168D02*
X1169620D01*
X1168803Y1031985D01*
X1167045D01*
X1166211Y1031151D01*
X1164655D01*
X1164149Y1031657D01*
Y1032254D01*
X1163562Y1032841D01*
X1161419D01*
G01X1152265Y1032897D02*
X1150872D01*
X1150311Y1032336D01*
Y1031664D01*
X1149815Y1031168D01*
X1143133D01*
G01X1172833Y1044554D02*
X1169620D01*
X1168803Y1045371D01*
X1167045D01*
X1166211Y1044537D01*
X1164655D01*
X1164149Y1045043D01*
Y1045640D01*
X1163562Y1046227D01*
X1161419D01*
G01X1152265Y1046283D02*
X1150872D01*
X1150311Y1045722D01*
Y1045050D01*
X1149815Y1044554D01*
X1143133D01*
G01X1172833Y1037861D02*
X1169620D01*
X1168803Y1038678D01*
X1167045D01*
X1166211Y1037844D01*
X1164655D01*
X1164149Y1038350D01*
Y1038947D01*
X1163562Y1039534D01*
X1161419D01*
G01X1152265Y1039590D02*
X1150872D01*
X1150311Y1039029D01*
Y1038357D01*
X1149815Y1037861D01*
X1143133D01*
G01X1147483Y1051247D02*
X1143133D01*
G01X1172833Y1071326D02*
X1167657D01*
X1166823Y1072160D01*
X1165136D01*
X1164477Y1071501D01*
Y1070219D01*
X1163911Y1069653D01*
X1161419D01*
G01X1152265Y1069613D02*
X1149362D01*
X1147649Y1071326D01*
X1143133D01*
G01X1172833Y1064633D02*
X1169620D01*
X1168803Y1065450D01*
X1167045D01*
X1166211Y1064616D01*
X1164655D01*
X1164149Y1065122D01*
Y1065719D01*
X1163562Y1066306D01*
X1161419D01*
G01X1152265Y1066362D02*
X1150872D01*
X1150311Y1065801D01*
Y1065129D01*
X1149815Y1064633D01*
X1143133D01*
G01Y1081365D02*
X1144990D01*
X1146018Y1080337D01*
X1147881D01*
X1149544Y1078674D01*
X1150488D01*
X1151544Y1079730D01*
X1152265D01*
G01X1161419Y1079692D02*
X1161979D01*
X1163007Y1078664D01*
X1164600D01*
X1167104Y1080337D01*
X1169874D01*
X1170902Y1081365D01*
X1172833D01*
G01Y1078018D02*
X1170905D01*
X1169876Y1079047D01*
X1167496D01*
X1164992Y1077374D01*
X1163004D01*
X1161976Y1076346D01*
X1161419D01*
G01X1152265Y1076323D02*
X1151488D01*
X1150427Y1077384D01*
X1149009D01*
X1147346Y1079047D01*
X1146030D01*
X1145001Y1078018D01*
X1143133D01*
G01Y1094751D02*
X1147649D01*
X1149362Y1093038D01*
X1152265D01*
G01X1161419Y1093078D02*
X1163911D01*
X1164477Y1093644D01*
Y1094926D01*
X1165136Y1095585D01*
X1166823D01*
X1167657Y1094751D01*
X1172833D01*
G01X1143133Y1088058D02*
X1149815D01*
X1150311Y1088554D01*
Y1089226D01*
X1150872Y1089787D01*
X1152265D01*
G01X1161419Y1089731D02*
X1163562D01*
X1164149Y1089144D01*
Y1088547D01*
X1164655Y1088041D01*
X1166211D01*
X1167045Y1088875D01*
X1168803D01*
X1169620Y1088058D01*
X1172833D01*
G01Y1108137D02*
X1167657D01*
X1166823Y1108971D01*
X1165136D01*
X1164477Y1108312D01*
Y1107030D01*
X1163911Y1106464D01*
X1161419D01*
G01X1152265Y1106424D02*
X1149362D01*
X1147649Y1108137D01*
X1143133D01*
G01X1172833Y1101444D02*
X1169620D01*
X1168803Y1102261D01*
X1167045D01*
X1166211Y1101427D01*
X1164655D01*
X1164149Y1101933D01*
Y1102530D01*
X1163562Y1103117D01*
X1161419D01*
G01X1152265Y1103173D02*
X1150872D01*
X1150311Y1102612D01*
Y1101940D01*
X1149815Y1101444D01*
X1143133D01*
G01X1172833Y1124869D02*
X1169620D01*
X1168803Y1125686D01*
X1167045D01*
X1166211Y1124852D01*
X1164655D01*
X1164149Y1125358D01*
Y1125955D01*
X1163562Y1126542D01*
X1161419D01*
G01X1152265Y1126598D02*
X1150872D01*
X1150311Y1126037D01*
Y1125365D01*
X1149815Y1124869D01*
X1143133D01*
G01Y1118176D02*
X1144990D01*
X1146018Y1117148D01*
X1147881D01*
X1149544Y1115485D01*
X1150488D01*
X1151544Y1116541D01*
X1152265D01*
G01X1161419Y1116503D02*
X1161979D01*
X1163007Y1115475D01*
X1164600D01*
X1167104Y1117148D01*
X1169874D01*
X1170902Y1118176D01*
X1172833D01*
G01X1143133Y1114829D02*
X1145001D01*
X1146030Y1115858D01*
X1147346D01*
X1149009Y1114195D01*
X1150427D01*
X1151488Y1113134D01*
X1152265D01*
G01X1161419Y1113157D02*
X1161976D01*
X1163004Y1114185D01*
X1164992D01*
X1167496Y1115858D01*
X1169876D01*
X1170905Y1114829D01*
X1172833D01*
G01Y1144948D02*
X1167657D01*
X1166823Y1145782D01*
X1165136D01*
X1164477Y1145123D01*
Y1143841D01*
X1163911Y1143275D01*
X1161419D01*
G01X1152265Y1143235D02*
X1149362D01*
X1147649Y1144948D01*
X1143133D01*
G01X1172833Y1138255D02*
X1169620D01*
X1168803Y1139072D01*
X1167045D01*
X1166211Y1138238D01*
X1164655D01*
X1164149Y1138744D01*
Y1139341D01*
X1163562Y1139928D01*
X1161419D01*
G01X1152265Y1139984D02*
X1150872D01*
X1150311Y1139423D01*
Y1138751D01*
X1149815Y1138255D01*
X1143133D01*
G01X1172833Y1131562D02*
X1167657D01*
X1166823Y1132396D01*
X1165136D01*
X1164477Y1131737D01*
Y1130455D01*
X1163911Y1129889D01*
X1161419D01*
G01X1152265Y1129849D02*
X1149362D01*
X1147649Y1131562D01*
X1143133D01*
G01Y1154987D02*
X1144990D01*
X1146018Y1153959D01*
X1147881D01*
X1149544Y1152296D01*
X1150488D01*
X1151544Y1153352D01*
X1152265D01*
G01X1161419Y1153314D02*
X1161979D01*
X1163007Y1152286D01*
X1164600D01*
X1167104Y1153959D01*
X1169874D01*
X1170902Y1154987D01*
X1172833D01*
G01Y1151641D02*
X1170904D01*
X1169876Y1152669D01*
X1167496D01*
X1164992Y1150996D01*
X1163004D01*
X1161976Y1149968D01*
X1161419D01*
G01X1152265Y1149945D02*
X1151488D01*
X1150427Y1151006D01*
X1149009D01*
X1147346Y1152669D01*
X1146030D01*
X1145002Y1151641D01*
X1143133D01*
G01X1172833Y1175066D02*
X1169620D01*
X1168803Y1175883D01*
X1167045D01*
X1166211Y1175049D01*
X1164655D01*
X1164149Y1175555D01*
Y1176152D01*
X1163562Y1176739D01*
X1161419D01*
G01X1152265Y1176795D02*
X1150872D01*
X1150311Y1176234D01*
Y1175562D01*
X1149815Y1175066D01*
X1143133D01*
G01X1172833Y1168373D02*
X1167657D01*
X1166823Y1169207D01*
X1165136D01*
X1164477Y1168548D01*
Y1167266D01*
X1163911Y1166700D01*
X1161419D01*
G01X1152265Y1166660D02*
X1149362D01*
X1147649Y1168373D01*
X1143133D01*
G01X1172833Y1161680D02*
X1169620D01*
X1168803Y1162497D01*
X1167045D01*
X1166211Y1161663D01*
X1164655D01*
X1164149Y1162169D01*
Y1162766D01*
X1163562Y1163353D01*
X1161419D01*
G01X1152265Y1163409D02*
X1150872D01*
X1150311Y1162848D01*
Y1162176D01*
X1149815Y1161680D01*
X1143133D01*
G01X1172833Y1181759D02*
X1167657D01*
X1166823Y1182593D01*
X1165136D01*
X1164477Y1181934D01*
Y1180652D01*
X1163911Y1180086D01*
X1161419D01*
G01X1152265Y1180046D02*
X1149362D01*
X1147649Y1181759D01*
X1143133D01*
G01Y1191798D02*
X1144990D01*
X1146018Y1190770D01*
X1147881D01*
X1149544Y1189107D01*
X1150488D01*
X1151544Y1190163D01*
X1152265D01*
G01X1161419Y1190125D02*
X1161979D01*
X1163007Y1189097D01*
X1164600D01*
X1167104Y1190770D01*
X1169874D01*
X1170902Y1191798D01*
X1172833D01*
G01Y1188452D02*
X1170904D01*
X1169876Y1189480D01*
X1167496D01*
X1164992Y1187807D01*
X1163004D01*
X1161976Y1186779D01*
X1161419D01*
G01X1152265Y1186756D02*
X1151488D01*
X1150427Y1187817D01*
X1149009D01*
X1147346Y1189480D01*
X1146030D01*
X1145002Y1188452D01*
X1143133D01*
G01X1172833Y1205184D02*
X1167657D01*
X1166823Y1206018D01*
X1165136D01*
X1164477Y1205359D01*
Y1204077D01*
X1163911Y1203511D01*
X1161419D01*
G01X1152265Y1203471D02*
X1149362D01*
X1147649Y1205184D01*
X1143133D01*
G01X1172833Y1198491D02*
X1169620D01*
X1168803Y1199308D01*
X1167045D01*
X1166211Y1198474D01*
X1164655D01*
X1164149Y1198980D01*
Y1199577D01*
X1163562Y1200164D01*
X1161419D01*
G01X1152265Y1200220D02*
X1150872D01*
X1150311Y1199659D01*
Y1198987D01*
X1149815Y1198491D01*
X1143133D01*
G01X1172833Y1218570D02*
X1167657D01*
X1166823Y1219404D01*
X1165136D01*
X1164477Y1218745D01*
Y1217463D01*
X1163911Y1216897D01*
X1161419D01*
G01X1152265Y1216857D02*
X1149362D01*
X1147649Y1218570D01*
X1143133D01*
G01X1172833Y1211877D02*
X1169620D01*
X1168803Y1212694D01*
X1167045D01*
X1166211Y1211860D01*
X1164655D01*
X1164149Y1212366D01*
Y1212963D01*
X1163562Y1213550D01*
X1161419D01*
G01X1152265Y1213606D02*
X1150872D01*
X1150311Y1213045D01*
Y1212373D01*
X1149815Y1211877D01*
X1143133D01*
G01X1172833Y1228609D02*
X1170902D01*
X1169874Y1227581D01*
X1167104D01*
X1164600Y1225908D01*
X1163007D01*
X1161979Y1226936D01*
X1161419D01*
G01X1152265Y1226974D02*
X1151544D01*
X1150488Y1225918D01*
X1149544D01*
X1147881Y1227581D01*
X1146018D01*
X1144990Y1228609D01*
X1143133D01*
G01X1172833Y1225263D02*
X1170904D01*
X1169876Y1226291D01*
X1167496D01*
X1164992Y1224618D01*
X1163004D01*
X1161976Y1223590D01*
X1161419D01*
G01X1152265Y1223567D02*
X1151488D01*
X1150427Y1224628D01*
X1149009D01*
X1147346Y1226291D01*
X1146030D01*
X1145002Y1225263D01*
X1143133D01*
G01Y1241995D02*
X1146937D01*
X1148650Y1240282D01*
X1152265D01*
G01X1161419Y1240322D02*
X1163911D01*
X1164477Y1240888D01*
Y1242170D01*
X1165136Y1242829D01*
X1166823D01*
X1167657Y1241995D01*
X1172833D01*
G01Y1235302D02*
X1169620D01*
X1168803Y1236119D01*
X1167045D01*
X1166211Y1235285D01*
X1164655D01*
X1164149Y1235791D01*
Y1236388D01*
X1163562Y1236975D01*
X1161419D01*
G01X1152265Y1237031D02*
X1150872D01*
X1150311Y1236470D01*
Y1235798D01*
X1149815Y1235302D01*
X1143133D01*
G01X1161041Y780184D02*
X1156691D01*
G01X1161041Y773491D02*
X1156691D01*
G01X1161041Y786877D02*
X1156691D01*
G01X1161041Y796916D02*
X1156691D01*
G01X1161041Y790223D02*
X1156691D01*
G01X1161041Y816995D02*
X1156691D01*
G01X1161041Y810302D02*
X1156691D01*
G01X1161041Y803609D02*
X1156691D01*
G01X1161041Y833727D02*
X1156691D01*
G01X1161041Y823688D02*
X1156691D01*
G01X1161041Y827034D02*
X1156691D01*
G01X1161041Y847113D02*
X1156691D01*
G01X1161041Y840420D02*
X1156691D01*
G01X1161041Y853806D02*
X1156691D01*
G01X1161041Y860499D02*
X1156691D01*
G01X1161041Y863845D02*
X1156691D01*
G01X1161041Y883924D02*
X1156691D01*
G01X1161041Y877231D02*
X1156691D01*
G01X1161041Y870538D02*
X1156691D01*
G01X1161041Y890617D02*
X1156691D01*
G01X1161041Y897310D02*
X1156691D01*
G01X1161041Y900656D02*
X1156691D01*
G01X1161041Y914042D02*
X1156691D01*
G01X1161041Y907349D02*
X1156691D01*
G01X1161041Y927428D02*
X1156691D01*
G01X1161041Y920735D02*
X1156691D01*
G01X1161041Y944160D02*
X1156691D01*
G01X1161041Y934121D02*
X1156691D01*
G01X1161041Y937467D02*
X1156691D01*
G01X1161041Y960892D02*
X1156691D01*
G01X1161041Y950853D02*
X1156691D01*
G01X1161041Y957546D02*
X1156691D01*
G01X1161041Y980971D02*
X1156691D01*
G01X1161041Y974278D02*
X1156691D01*
G01X1161041Y967585D02*
X1156691D01*
G01X1161041Y994357D02*
X1156691D01*
G01X1161041Y987664D02*
X1156691D01*
G01X1161041Y1027822D02*
X1156691D01*
G01X1161041Y1021129D02*
X1156691D01*
G01X1161041Y1041207D02*
X1156691D01*
G01X1161041Y1034515D02*
X1156691D01*
G01X1161041Y1061286D02*
X1156691D01*
G01X1161041Y1047900D02*
X1156691D01*
G01X1161041Y1054593D02*
X1156691D01*
G01X1161041Y1074672D02*
X1156691D01*
G01X1161041Y1067979D02*
X1156691D01*
G01X1161041Y1091404D02*
X1156691D01*
G01X1161041Y1081365D02*
X1156691D01*
G01X1161041Y1084711D02*
X1156691D01*
G01X1161041Y1098097D02*
X1156691D01*
G01X1161041Y1111483D02*
X1156691D01*
G01X1161041Y1104790D02*
X1156691D01*
G01X1161041Y1128215D02*
X1156691D01*
G01X1161041Y1118176D02*
X1156691D01*
G01X1161041Y1121522D02*
X1156691D01*
G01X1161041Y1141601D02*
X1156691D01*
G01X1161041Y1134908D02*
X1156691D01*
G01X1161041Y1148294D02*
X1156691D01*
G01X1161041Y1154987D02*
X1156691D01*
G01X1161041Y1158333D02*
X1156691D01*
G01X1161041Y1171719D02*
X1156691D01*
G01X1161041Y1165026D02*
X1156691D01*
G01X1161041Y1185105D02*
X1156691D01*
G01X1161041Y1178412D02*
X1156691D01*
G01X1161041Y1191798D02*
X1156691D01*
G01X1161041Y1208530D02*
X1156691D01*
G01X1161041Y1201837D02*
X1156691D01*
G01X1161041Y1195144D02*
X1156691D01*
G01X1161041Y1221916D02*
X1156691D01*
G01X1161041Y1215223D02*
X1156691D01*
G01X1161041Y1238648D02*
X1156691D01*
G01X1161041Y1228609D02*
X1156691D01*
G01X1161041Y1231955D02*
X1156691D01*
G01X1161041Y1245341D02*
X1156691D01*
G01X1177183Y770144D02*
X1172833D01*
G01X1177183Y776837D02*
X1172833D01*
G01X1177183Y786877D02*
X1172833D01*
G01X1177183Y783530D02*
X1172833D01*
G01X1177183Y800263D02*
X1172833D01*
G01X1177183Y793570D02*
X1172833D01*
G01X1177183Y813648D02*
X1172833D01*
G01X1177183Y806955D02*
X1172833D01*
G01X1177183Y830381D02*
X1172833D01*
G01X1177183Y823688D02*
X1172833D01*
G01X1177183Y820341D02*
X1172833D01*
G01X1177183Y850459D02*
X1172833D01*
G01X1177183Y843766D02*
X1172833D01*
G01X1177183Y837074D02*
X1172833D01*
G01X1177183Y867192D02*
X1172833D01*
G01X1177183Y860499D02*
X1172833D01*
G01X1177183Y857152D02*
X1172833D01*
G01X1177183Y873885D02*
X1172833D01*
G01X1177183Y880577D02*
X1172833D01*
G01X1177183Y887270D02*
X1172833D01*
G01X1177183Y897310D02*
X1172833D01*
G01X1177183Y893963D02*
X1172833D01*
G01X1177183Y910696D02*
X1172833D01*
G01X1177183Y904003D02*
X1172833D01*
G01X1177183Y924081D02*
X1172833D01*
G01X1177183Y917389D02*
X1172833D01*
G01X1177183Y930774D02*
X1172833D01*
G01X1177183Y947507D02*
X1172833D01*
G01X1177183Y940814D02*
X1172833D01*
G01X1177183Y934121D02*
X1172833D01*
G01X1177183Y964239D02*
X1172833D01*
G01X1177183Y977625D02*
X1172833D01*
G01X1177183Y970932D02*
X1172833D01*
G01X1177183Y991011D02*
X1172833D01*
G01X1177183Y984318D02*
X1172833D01*
G01X1177283Y1021129D02*
X1172833D01*
G01X1177283Y1024475D02*
X1172833D01*
G01X1177283Y1044554D02*
X1172833D01*
G01X1177283Y1037861D02*
X1172833D01*
G01X1177283Y1031168D02*
X1172833D01*
G01X1177283Y1051247D02*
X1172833D01*
G01X1177283Y1071326D02*
X1172833D01*
G01X1177283Y1064633D02*
X1172833D01*
G01X1177283Y1078018D02*
X1172833D01*
G01X1177283Y1094752D02*
X1177282Y1094751D01*
X1172833D01*
G01X1177283Y1088059D02*
X1177282Y1088058D01*
X1172833D01*
G01X1177283Y1081366D02*
X1177282Y1081365D01*
X1172833D01*
G01X1177283Y1108137D02*
X1172833D01*
G01X1177283Y1101444D02*
X1172833D01*
G01X1177183Y1124869D02*
X1172833D01*
G01X1177283Y1118177D02*
X1177282Y1118176D01*
X1172833D01*
G01X1177283Y1114830D02*
X1177282Y1114829D01*
X1172833D01*
G01X1177283Y1138255D02*
X1172833D01*
G01X1177183Y1131562D02*
X1172833D01*
G01X1177283Y1144948D02*
X1172833D01*
G01X1177283Y1154988D02*
X1177282Y1154987D01*
X1172833D01*
G01X1177283Y1151641D02*
X1172833D01*
G01X1177283Y1175066D02*
X1172833D01*
G01X1177283Y1168373D02*
X1172833D01*
G01X1177283Y1161680D02*
X1172833D01*
G01X1177283Y1181759D02*
X1172833D01*
G01X1177283Y1191799D02*
X1177282Y1191798D01*
X1172833D01*
G01X1177283Y1188452D02*
X1172833D01*
G01X1177283Y1205184D02*
X1172833D01*
G01X1177283Y1198491D02*
X1172833D01*
G01X1177283Y1218570D02*
X1172833D01*
G01X1177283Y1211877D02*
X1172833D01*
G01X1177283Y1225263D02*
X1172833D01*
G01X1177250Y1241995D02*
X1172833D01*
G01X1177283Y1235302D02*
X1172833D01*
G01X1177283Y1228609D02*
X1172833D01*
G01X1186391Y780184D02*
X1191644D01*
X1192637Y781177D01*
X1194191D01*
X1195070Y780298D01*
Y779120D01*
X1195708Y778482D01*
X1198107D01*
G01X1207261Y778511D02*
X1208158D01*
X1209831Y780184D01*
X1216091D01*
G01X1186391Y773491D02*
X1191549D01*
X1192540Y774482D01*
X1194076D01*
X1194974Y773584D01*
Y772426D01*
X1195624Y771776D01*
X1198107D01*
G01X1207261Y771817D02*
X1207870D01*
X1209544Y773491D01*
X1216091D01*
G01X1186391Y786877D02*
X1188551D01*
X1189617Y787943D01*
X1190636D01*
X1194652Y789607D01*
X1195552D01*
X1196629Y788530D01*
X1198107D01*
G01X1207261Y788526D02*
X1208434D01*
X1209512Y789604D01*
X1210001D01*
X1211781Y787824D01*
X1212824D01*
X1213771Y786877D01*
X1216091D01*
G01X1186391Y803609D02*
X1190501D01*
X1191529Y804637D01*
X1194369D01*
X1195226Y803780D01*
Y802690D01*
X1196026Y801890D01*
X1198107D01*
G01X1207261Y801936D02*
X1208063D01*
X1209736Y803609D01*
X1216091D01*
G01X1186391Y796916D02*
X1191549D01*
X1192540Y797907D01*
X1194078D01*
X1194974Y797011D01*
Y795851D01*
X1195617Y795208D01*
X1198107D01*
G01X1207261Y795243D02*
X1208063D01*
X1209736Y796916D01*
X1216091D01*
G01X1186391Y790223D02*
X1188711D01*
X1189701Y789233D01*
X1190379D01*
X1194395Y790897D01*
X1195561D01*
X1196586Y791922D01*
X1198107D01*
X1198108Y791921D01*
G01X1207262Y791937D02*
X1207267Y791942D01*
X1208413D01*
X1209461Y790894D01*
X1210536D01*
X1212316Y789114D01*
X1212822D01*
X1213931Y790223D01*
X1216091D01*
G01X1186391Y816995D02*
X1191549D01*
X1192545Y817991D01*
X1194047D01*
X1194974Y817064D01*
Y815930D01*
X1195615Y815289D01*
X1198107D01*
G01X1207261Y815321D02*
X1207750D01*
X1209424Y816995D01*
X1216091D01*
G01X1186391Y810302D02*
X1190501D01*
X1191529Y811330D01*
X1194383D01*
X1195226Y810487D01*
Y809383D01*
X1196026Y808583D01*
X1198107D01*
G01X1207261Y808629D02*
X1208063D01*
X1209736Y810302D01*
X1216091D01*
G01X1186391Y833727D02*
X1190805D01*
X1192312Y835234D01*
X1194492D01*
X1194974Y834752D01*
Y832662D01*
X1195606Y832030D01*
X1198107D01*
G01X1207261Y832054D02*
X1207799D01*
X1209472Y833727D01*
X1216091D01*
G01X1186391Y823688D02*
X1188551D01*
X1189617Y824754D01*
X1190636D01*
X1194652Y826418D01*
X1195552D01*
X1196659Y825311D01*
X1198107D01*
G01X1207261Y825337D02*
X1208434D01*
X1209512Y826415D01*
X1210001D01*
X1211781Y824635D01*
X1212824D01*
X1213771Y823688D01*
X1216091D01*
G01X1186391Y827034D02*
X1188711D01*
X1189701Y826044D01*
X1190379D01*
X1194395Y827708D01*
X1195561D01*
X1196586Y828733D01*
X1198107D01*
X1198108Y828732D01*
G01X1207262Y828748D02*
X1207267Y828753D01*
X1208413D01*
X1209461Y827705D01*
X1210536D01*
X1212316Y825925D01*
X1212822D01*
X1213931Y827034D01*
X1216091D01*
G01X1186391Y853806D02*
X1191412D01*
X1192567Y854961D01*
X1193985D01*
X1195070Y853876D01*
Y852988D01*
X1195971Y852087D01*
X1198107D01*
G01X1207261Y852133D02*
X1208158D01*
X1209831Y853806D01*
X1216091D01*
G01X1186391Y847113D02*
X1190864D01*
X1191852Y848101D01*
X1193984D01*
X1195070Y847015D01*
Y846049D01*
X1195735Y845384D01*
X1198107D01*
G01X1207261Y845440D02*
X1207811D01*
X1209484Y847113D01*
X1216091D01*
G01X1186391Y840420D02*
X1191549D01*
X1192360Y841231D01*
X1194232D01*
X1194974Y840489D01*
Y839355D01*
X1195745Y838584D01*
X1198107D01*
G01X1207261Y838673D02*
X1207989D01*
X1209736Y840420D01*
X1216091D01*
G01X1186391Y860499D02*
X1188551D01*
X1189617Y861565D01*
X1190636D01*
X1194652Y863229D01*
X1195552D01*
X1196631Y862150D01*
X1198105D01*
X1198107Y862152D01*
G01X1207261Y862148D02*
X1208434D01*
X1209512Y863226D01*
X1210001D01*
X1211781Y861446D01*
X1212824D01*
X1213771Y860499D01*
X1216091D01*
G01X1186391Y863845D02*
X1188711D01*
X1189701Y862855D01*
X1190379D01*
X1194395Y864519D01*
X1195561D01*
X1196586Y865544D01*
X1198107D01*
G01X1207261Y865558D02*
X1208419D01*
X1209461Y864516D01*
X1210536D01*
X1212316Y862736D01*
X1212822D01*
X1213931Y863845D01*
X1216091D01*
G01Y883924D02*
X1209540D01*
X1207866Y882250D01*
X1207261D01*
G01X1198107Y882225D02*
X1195608D01*
X1194974Y882859D01*
Y884125D01*
X1194284Y884815D01*
X1192440D01*
X1191549Y883924D01*
X1186391D01*
G01Y877231D02*
X1190741D01*
X1191436Y877926D01*
X1193974D01*
X1194974Y876926D01*
Y876166D01*
X1195635Y875505D01*
X1198107D01*
G01X1207261Y875507D02*
X1207645D01*
X1209761Y877623D01*
X1212579D01*
X1212971Y877231D01*
X1216091D01*
G01X1186391Y870538D02*
X1191549D01*
X1192146Y871135D01*
X1194214D01*
X1194974Y870375D01*
Y869473D01*
X1195621Y868826D01*
X1198107D01*
G01X1207261Y868865D02*
X1207538D01*
X1209741Y871068D01*
X1212320D01*
X1212850Y870538D01*
X1216091D01*
G01Y890617D02*
X1209736D01*
X1208062Y888943D01*
X1207261D01*
G01X1198107Y888921D02*
X1195605D01*
X1194974Y889552D01*
Y890686D01*
X1194052Y891608D01*
X1192540D01*
X1191549Y890617D01*
X1186391D01*
G01X1216091Y897310D02*
X1213771D01*
X1212824Y898257D01*
X1211391D01*
X1209611Y900037D01*
X1208863D01*
X1207809Y898983D01*
X1207261D01*
G01X1198107Y898963D02*
X1197341D01*
X1196229Y900075D01*
X1195199D01*
X1191098Y898376D01*
X1189617D01*
X1188551Y897310D01*
X1186391D01*
G01X1216091Y900656D02*
X1213931D01*
X1212822Y899547D01*
X1211926D01*
X1210146Y901327D01*
X1208845D01*
X1207842Y902330D01*
X1207261D01*
G01X1198107Y902385D02*
X1197266D01*
X1196246Y901365D01*
X1194942D01*
X1190841Y899666D01*
X1189701D01*
X1188711Y900656D01*
X1186391D01*
G01X1216091Y914042D02*
X1209736D01*
X1207999Y912305D01*
X1207261D01*
G01X1198107Y912206D02*
X1195745D01*
X1194974Y912977D01*
Y914111D01*
X1194052Y915033D01*
X1192540D01*
X1191549Y914042D01*
X1186391D01*
G01X1216091Y907349D02*
X1209736D01*
X1208005Y905618D01*
X1207261D01*
G01X1198107Y905513D02*
X1195745D01*
X1194974Y906284D01*
Y907418D01*
X1194052Y908340D01*
X1192540D01*
X1191549Y907349D01*
X1186391D01*
G01Y927428D02*
X1186580Y927239D01*
X1191924D01*
X1192966Y928281D01*
X1194184D01*
X1194974Y927491D01*
Y926544D01*
X1195764Y925754D01*
X1196789D01*
G01X1208362D02*
X1208542D01*
X1210216Y927428D01*
X1216091D01*
G01X1186391Y920735D02*
X1192521D01*
X1193454Y921668D01*
X1194818D01*
X1195608Y920878D01*
Y919730D01*
X1196276Y919062D01*
X1197581D01*
G01X1207513D02*
X1208015D01*
X1209885Y920932D01*
X1212650D01*
X1212847Y920735D01*
X1216091D01*
G01X1186391Y950853D02*
X1191549D01*
X1192731Y952035D01*
X1194183D01*
X1194974Y951244D01*
Y949843D01*
X1195637Y949180D01*
X1197582D01*
G01X1207585D02*
X1208063D01*
X1209949Y951066D01*
X1215878D01*
X1216091Y950853D01*
G01X1186391Y944160D02*
X1191549D01*
X1192737Y945348D01*
X1194183D01*
X1194974Y944557D01*
Y943323D01*
X1195810Y942487D01*
X1197377D01*
G01X1207602D02*
X1207916D01*
X1209589Y944160D01*
X1216091D01*
G01X1186391Y934121D02*
X1188551D01*
X1189617Y935187D01*
X1191740D01*
X1193404Y936851D01*
X1195550D01*
X1196607Y935794D01*
X1196741D01*
G01X1208299D02*
X1208458D01*
X1209313Y936649D01*
X1210043D01*
X1210312Y936537D01*
X1211781Y935068D01*
X1212824D01*
X1213771Y934121D01*
X1216091D01*
G01X1186391Y937467D02*
X1188711D01*
X1189701Y936477D01*
X1191205D01*
X1192869Y938141D01*
X1195561D01*
X1196561Y939141D01*
X1196741D01*
G01X1208299D02*
X1208458D01*
X1209660Y937939D01*
X1210300D01*
X1211043Y937631D01*
X1212316Y936358D01*
X1212822D01*
X1213931Y937467D01*
X1216091D01*
G01X1190741Y960892D02*
X1186391D01*
G01Y967585D02*
X1191468D01*
X1192945Y966108D01*
Y964108D01*
X1193635Y963418D01*
X1195165D01*
X1195855Y964108D01*
Y964450D01*
X1197286Y965881D01*
X1198520D01*
G01X1206920Y965876D02*
X1207521D01*
X1207623Y965978D01*
X1212020D01*
G01X1220520Y965967D02*
X1226899D01*
X1227013Y965853D01*
X1228120D01*
G01X1236720Y965868D02*
X1259282D01*
X1264068Y967851D01*
G01X1190741Y957546D02*
X1186391D01*
G01Y980971D02*
X1189935D01*
X1193490Y984526D01*
X1195562D01*
X1197268Y982820D01*
X1198107D01*
G01X1207261Y982644D02*
X1208849D01*
X1210522Y980971D01*
X1216091D01*
G01X1186391Y974278D02*
X1189998D01*
X1193505Y977785D01*
X1195706D01*
X1197488Y976003D01*
X1198107D01*
G01X1207261Y975951D02*
X1208851D01*
X1210524Y974278D01*
X1216091D01*
G01X1186391Y994357D02*
X1191709D01*
X1192844Y995492D01*
X1194296D01*
X1195520Y994268D01*
Y993384D01*
X1196323Y992581D01*
X1198107D01*
G01X1207261Y992684D02*
X1207657D01*
X1209330Y994357D01*
X1216091D01*
G01X1186391Y987664D02*
X1189820D01*
X1193362Y991206D01*
X1194749D01*
X1196544Y989411D01*
X1198107D01*
G01X1207261Y989337D02*
X1208851D01*
X1210524Y987664D01*
X1216091D01*
G01X1186391Y1027822D02*
X1191274D01*
X1194820Y1031368D01*
X1196020D01*
X1196420Y1030968D01*
Y1030095D01*
X1196954Y1029561D01*
X1198107D01*
G01X1207261Y1029495D02*
X1207826D01*
X1209499Y1027822D01*
X1216091D01*
G01X1186391Y1021129D02*
X1191063D01*
X1196017Y1026083D01*
X1198107D01*
G01X1207261Y1026148D02*
X1207562D01*
X1212581Y1021129D01*
X1216091D01*
G01X1186391Y1047900D02*
X1191472D01*
X1192749Y1049177D01*
X1194311D01*
X1196220Y1047268D01*
Y1046727D01*
X1196895Y1046052D01*
X1198107D01*
G01X1207261Y1046227D02*
X1211230D01*
X1212903Y1047900D01*
X1216091D01*
G01X1186391Y1041207D02*
X1192052D01*
X1193020Y1042175D01*
Y1043246D01*
X1193628Y1043854D01*
X1195334D01*
X1196245Y1042943D01*
X1198107D01*
G01X1207261Y1042880D02*
X1208195D01*
X1209869Y1041206D01*
X1209870Y1041207D01*
X1216091D01*
G01X1186391Y1034515D02*
X1192647D01*
X1193483Y1035351D01*
Y1036269D01*
X1194486Y1037272D01*
X1196316D01*
X1197297Y1036291D01*
X1198107D01*
G01X1207261Y1036188D02*
X1208195D01*
X1209869Y1034514D01*
X1209870Y1034515D01*
X1216091D01*
G01Y1061286D02*
X1209475D01*
X1207802Y1059613D01*
X1207261D01*
G01X1197487D02*
X1195671D01*
X1194974Y1060310D01*
Y1061355D01*
X1194052Y1062277D01*
X1189762D01*
X1188771Y1061286D01*
X1186391D01*
G01Y1054593D02*
X1190631D01*
X1193797Y1051427D01*
X1194980D01*
X1196348Y1052795D01*
X1198220D01*
G01X1207120Y1052838D02*
X1207891D01*
X1211290Y1056237D01*
X1211665D01*
G01X1220620Y1056185D02*
X1221703D01*
X1222070Y1055818D01*
X1225655D01*
X1226135Y1056298D01*
X1227920D01*
G01X1237610Y1056266D02*
X1245360D01*
X1249812Y1054419D01*
X1262998Y1041233D01*
X1283054Y1032925D01*
X1284439Y1031540D01*
X1284449Y1031536D01*
X1292699Y1023286D01*
G01X1186391Y1074672D02*
X1189713D01*
X1190187Y1075146D01*
X1191385D01*
X1192175Y1074356D01*
Y1072658D01*
X1193122Y1071711D01*
X1194240D01*
X1195528Y1072999D01*
X1196789D01*
G01X1208314D02*
X1209333D01*
X1210518Y1074184D01*
X1212243D01*
X1212731Y1074672D01*
X1216091D01*
G01X1186391Y1067979D02*
X1189609D01*
X1190081Y1068451D01*
X1192172D01*
X1192882Y1067741D01*
Y1066534D01*
X1193621Y1065795D01*
X1194784D01*
X1195295Y1066306D01*
X1197626D01*
G01X1207471D02*
X1207958D01*
X1209631Y1067979D01*
X1216091D01*
G01X1186391Y1098097D02*
X1189733D01*
X1190157Y1098521D01*
X1192139D01*
X1192801Y1097859D01*
Y1096899D01*
X1193953Y1095747D01*
X1195640D01*
X1196317Y1096424D01*
X1197724D01*
G01X1207410D02*
X1208809D01*
X1210482Y1098097D01*
X1216091D01*
G01X1186391Y1091404D02*
X1189781D01*
X1190250Y1091873D01*
X1192174D01*
X1193183Y1090864D01*
Y1089288D01*
X1194020Y1088451D01*
X1195168D01*
X1196342Y1089625D01*
X1198107D01*
G01X1207474Y1089731D02*
X1207791D01*
X1209464Y1091404D01*
X1216091D01*
G01X1186391Y1081365D02*
X1188551D01*
X1189579Y1082393D01*
X1191020D01*
X1193524Y1084067D01*
X1195368D01*
X1196397Y1083038D01*
X1196758D01*
G01X1207420D02*
X1207872D01*
X1208901Y1084067D01*
X1209236D01*
X1209920Y1083783D01*
X1211310Y1082393D01*
X1212911D01*
X1213939Y1081365D01*
X1216091D01*
G01X1186391Y1084711D02*
X1188509D01*
X1189537Y1083683D01*
X1190628D01*
X1193132Y1085357D01*
X1195443D01*
X1196471Y1086385D01*
X1196758D01*
G01X1207420D02*
X1207860D01*
X1208888Y1085357D01*
X1209493D01*
X1210651Y1084877D01*
X1211845Y1083683D01*
X1212903D01*
X1213931Y1084711D01*
X1216091D01*
G01X1186391Y1111483D02*
X1189719D01*
X1190537Y1112301D01*
X1191701D01*
X1192513Y1111489D01*
Y1110150D01*
X1192922Y1109741D01*
X1198107D01*
G01X1207261Y1109810D02*
X1209211D01*
X1210884Y1111483D01*
X1216091D01*
G01X1186391Y1104790D02*
X1189535D01*
X1190381Y1105636D01*
X1192149D01*
X1192808Y1104977D01*
Y1103681D01*
X1193447Y1103042D01*
X1198107D01*
G01X1207261Y1103117D02*
X1207682D01*
X1209355Y1104790D01*
X1216091D01*
G01X1186391Y1128215D02*
X1188847D01*
X1188848Y1128214D01*
X1189840Y1129206D01*
X1191352D01*
X1192274Y1128284D01*
Y1127150D01*
X1192938Y1126486D01*
X1198107D01*
G01X1207261Y1126542D02*
X1207699D01*
X1209372Y1128215D01*
X1216091D01*
G01X1186391Y1118176D02*
X1188551D01*
X1189579Y1119204D01*
X1191755D01*
X1194259Y1120878D01*
X1195474D01*
X1196545Y1119807D01*
X1198107D01*
G01X1207261Y1119849D02*
X1208004D01*
X1209033Y1120878D01*
X1210064D01*
X1211738Y1119204D01*
X1212911D01*
X1213939Y1118176D01*
X1216091D01*
G01X1186391Y1121522D02*
X1188509D01*
X1189537Y1120494D01*
X1191363D01*
X1193867Y1122168D01*
X1195427D01*
X1196492Y1123233D01*
X1198107D01*
G01X1207261Y1123196D02*
X1208028D01*
X1209056Y1122168D01*
X1210599D01*
X1212273Y1120494D01*
X1212903D01*
X1213931Y1121522D01*
X1216091D01*
G01X1186391Y1141601D02*
X1188847D01*
X1188848Y1141600D01*
X1189840Y1142592D01*
X1191352D01*
X1192274Y1141670D01*
Y1140536D01*
X1192950Y1139860D01*
X1198107D01*
G01X1207261Y1139928D02*
X1207832D01*
X1209505Y1141601D01*
X1216091D01*
G01X1186391Y1134908D02*
X1188847D01*
X1188848Y1134907D01*
X1189840Y1135899D01*
X1191352D01*
X1192274Y1134977D01*
Y1133843D01*
X1192943Y1133174D01*
X1198107D01*
G01X1207261Y1133177D02*
X1208754D01*
X1210485Y1134908D01*
X1216091D01*
G01X1186391Y1148294D02*
X1191644D01*
X1192636Y1149286D01*
X1194148D01*
X1195070Y1148364D01*
Y1147230D01*
X1195779Y1146521D01*
X1198107D01*
G01X1207261Y1146579D02*
X1208691D01*
X1209826Y1147714D01*
X1212119D01*
X1212699Y1148294D01*
X1216091D01*
G01X1186391Y1154987D02*
X1188551D01*
X1189579Y1156015D01*
X1191755D01*
X1194259Y1157689D01*
X1195474D01*
X1196545Y1156618D01*
X1198107D01*
G01X1207261Y1156623D02*
X1208571D01*
X1209637Y1157689D01*
X1210064D01*
X1211738Y1156015D01*
X1212911D01*
X1213939Y1154987D01*
X1216091D01*
G01X1186391Y1158333D02*
X1188509D01*
X1189537Y1157305D01*
X1191363D01*
X1193867Y1158979D01*
X1195427D01*
X1196492Y1160044D01*
X1198107D01*
G01X1207261Y1160036D02*
X1208559D01*
X1209616Y1158979D01*
X1210599D01*
X1212273Y1157305D01*
X1212903D01*
X1213931Y1158333D01*
X1216091D01*
G01Y1178412D02*
X1209503D01*
X1207830Y1176739D01*
X1207261D01*
G01X1198107Y1176657D02*
X1192964D01*
X1192274Y1177347D01*
Y1178481D01*
X1191352Y1179403D01*
X1189840D01*
X1188848Y1178411D01*
X1188847Y1178412D01*
X1186391D01*
G01Y1171719D02*
X1188847D01*
X1188848Y1171718D01*
X1189840Y1172710D01*
X1191352D01*
X1192274Y1171788D01*
Y1170654D01*
X1192914Y1170014D01*
X1198107D01*
G01X1207261Y1170046D02*
X1208625D01*
X1210298Y1171719D01*
X1216091D01*
G01X1186391Y1165026D02*
X1188847D01*
X1188848Y1165025D01*
X1189840Y1166017D01*
X1191352D01*
X1192274Y1165095D01*
Y1164062D01*
X1193063Y1163273D01*
X1198107D01*
G01X1207261Y1163353D02*
X1207822D01*
X1209495Y1165026D01*
X1216091D01*
G01Y1185105D02*
X1212527D01*
X1211774Y1184352D01*
X1208966D01*
X1208046Y1183432D01*
X1207261D01*
G01X1198107Y1183350D02*
X1192964D01*
X1192274Y1184040D01*
Y1185174D01*
X1191352Y1186096D01*
X1189840D01*
X1188848Y1185104D01*
X1188847Y1185105D01*
X1186391D01*
G01X1216091Y1191798D02*
X1213939D01*
X1212911Y1192826D01*
X1211310D01*
X1209636Y1194500D01*
X1208901D01*
X1207872Y1193471D01*
X1207261D01*
G01X1198107Y1193429D02*
X1197303D01*
X1196232Y1194500D01*
X1194106D01*
X1191602Y1192826D01*
X1189579D01*
X1188551Y1191798D01*
X1186391D01*
G01X1216091Y1208530D02*
X1211395D01*
X1209722Y1206857D01*
X1207261D01*
G01X1198107Y1206811D02*
X1193029D01*
X1192274Y1207566D01*
Y1208599D01*
X1191352Y1209521D01*
X1189840D01*
X1188848Y1208529D01*
X1188847Y1208530D01*
X1186391D01*
G01X1216091Y1201837D02*
X1209395D01*
X1207722Y1200164D01*
X1207261D01*
G01X1198107Y1200132D02*
X1193016D01*
X1192274Y1200874D01*
Y1201906D01*
X1191352Y1202828D01*
X1189840D01*
X1188848Y1201836D01*
X1188847Y1201837D01*
X1186391D01*
G01X1216091Y1195144D02*
X1213931D01*
X1212903Y1194116D01*
X1211845D01*
X1210171Y1195790D01*
X1208888D01*
X1207860Y1196818D01*
X1207261D01*
G01X1198107Y1196855D02*
X1197248D01*
X1196183Y1195790D01*
X1193714D01*
X1191210Y1194116D01*
X1189537D01*
X1188509Y1195144D01*
X1186391D01*
G01Y1221916D02*
X1188847D01*
X1188848Y1221915D01*
X1189840Y1222907D01*
X1191352D01*
X1192274Y1221985D01*
Y1220952D01*
X1193137Y1220089D01*
X1198107D01*
G01X1207261Y1220243D02*
X1208495D01*
X1209275Y1221023D01*
X1211488D01*
X1212381Y1221916D01*
X1216091D01*
G01X1186391Y1215223D02*
X1188847D01*
X1188848Y1215222D01*
X1189840Y1216214D01*
X1191352D01*
X1192274Y1215292D01*
Y1214259D01*
X1193013Y1213520D01*
X1198107D01*
G01X1207261Y1213550D02*
X1207870D01*
X1209543Y1215223D01*
X1216091D01*
G01X1186391Y1238648D02*
X1188847D01*
X1188848Y1238647D01*
X1189840Y1239639D01*
X1191352D01*
X1192274Y1238717D01*
Y1237583D01*
X1192947Y1236910D01*
X1198107D01*
G01X1207261Y1236951D02*
X1208467D01*
X1210164Y1238648D01*
X1216091D01*
G01X1186391Y1228609D02*
X1188551D01*
X1189579Y1229637D01*
X1191776D01*
X1194280Y1231311D01*
X1195474D01*
X1196545Y1230240D01*
X1198107D01*
G01X1207261Y1230245D02*
X1208571D01*
X1209637Y1231311D01*
X1210064D01*
X1211738Y1229637D01*
X1212911D01*
X1213939Y1228609D01*
X1216091D01*
G01X1186391Y1231955D02*
X1188509D01*
X1189537Y1230927D01*
X1191384D01*
X1193888Y1232601D01*
X1195427D01*
X1196492Y1233666D01*
X1198107D01*
G01X1207261Y1233658D02*
X1208559D01*
X1209616Y1232601D01*
X1210599D01*
X1212273Y1230927D01*
X1212903D01*
X1213931Y1231955D01*
X1216091D01*
G01X1186391Y1245341D02*
X1188847D01*
X1188848Y1245340D01*
X1189840Y1246332D01*
X1191352D01*
X1192274Y1245410D01*
Y1244377D01*
X1193064Y1243587D01*
X1198107D01*
G01X1207261Y1243668D02*
X1208709D01*
X1210382Y1245341D01*
X1216091D01*
G01X1202533Y770144D02*
X1202534Y770143D01*
X1208789D01*
X1210516Y771870D01*
X1211665D01*
G01X1220819Y771817D02*
X1222567D01*
X1222920Y771464D01*
Y769925D01*
X1223420Y769425D01*
X1228007D01*
X1228726Y770144D01*
X1232233D01*
G01X1312235Y842652D02*
Y825694D01*
X1310730Y822061D01*
X1271564Y782895D01*
X1263344Y779490D01*
X1238611D01*
X1237631Y778510D01*
X1236920D01*
G01X1227720Y778475D02*
X1225202D01*
X1223493Y780184D01*
X1216091D01*
G01X1317273Y842652D02*
Y824693D01*
X1315001Y819209D01*
X1274416Y778624D01*
X1262854Y773835D01*
X1239828D01*
X1237810Y771817D01*
X1236920D01*
G01X1227820Y771792D02*
X1226588D01*
X1224889Y773491D01*
X1216091D01*
G01X1202533Y776837D02*
X1208790D01*
X1210540Y778587D01*
X1211665D01*
G01X1220819Y778535D02*
X1222542D01*
X1222920Y778157D01*
Y776618D01*
X1223420Y776118D01*
X1228029D01*
X1228748Y776837D01*
X1232233D01*
G01X1305906Y842652D02*
Y828036D01*
X1305579Y827246D01*
X1303904Y825571D01*
Y824878D01*
X1302227Y823201D01*
X1301534D01*
X1299857Y821524D01*
Y820831D01*
X1298181Y819155D01*
X1297488D01*
X1295813Y817480D01*
Y816787D01*
X1294136Y815110D01*
X1293443D01*
X1291768Y813435D01*
Y812742D01*
X1290091Y811065D01*
X1289398D01*
X1287723Y809390D01*
Y808697D01*
X1286046Y807020D01*
X1285353D01*
X1267987Y789654D01*
X1238496D01*
X1237392Y788550D01*
X1236920D01*
G01X1228020Y788483D02*
X1226488D01*
X1226154Y788817D01*
Y789545D01*
X1225905Y789794D01*
X1224873D01*
X1220214Y787864D01*
X1219020D01*
X1218032Y786876D01*
X1218031Y786877D01*
X1216091D01*
G01X1202533D02*
X1204446D01*
X1205474Y785849D01*
X1207281D01*
X1208961Y784169D01*
X1209869D01*
X1210932Y785232D01*
X1211665D01*
G01X1220819Y785204D02*
X1221471D01*
X1222459Y784216D01*
X1223929D01*
X1226373Y785849D01*
X1229222D01*
X1230250Y786877D01*
X1232233D01*
G01X1202533Y783530D02*
X1204401D01*
X1205430Y784559D01*
X1206746D01*
X1208426Y782879D01*
X1209854D01*
X1210901Y781832D01*
X1211665D01*
G01X1220819Y781858D02*
X1221304D01*
X1222372Y782926D01*
X1224321D01*
X1226765Y784559D01*
X1229316D01*
X1230345Y783530D01*
X1232233D01*
G01X1299575Y842652D02*
Y830191D01*
X1283716Y814332D01*
X1282598D01*
X1281272Y815658D01*
X1280154D01*
X1279292Y814796D01*
Y813678D01*
X1280618Y812352D01*
Y811234D01*
X1279756Y810372D01*
X1278638D01*
X1277397Y811613D01*
X1276279D01*
X1275417Y810751D01*
Y809633D01*
X1276658Y808392D01*
Y807274D01*
X1275796Y806412D01*
X1274678D01*
X1273001Y808089D01*
X1271883D01*
X1259864Y796070D01*
X1240404D01*
X1239658Y796816D01*
X1239177D01*
X1237327Y798666D01*
X1236820D01*
G01X1228020Y798658D02*
X1227294D01*
X1225363Y798004D01*
X1220373Y796916D01*
X1216091D01*
G01X1202533Y800263D02*
X1209129D01*
X1210876Y802010D01*
X1211651D01*
X1211665Y801996D01*
G01X1220819Y801936D02*
X1222254D01*
X1222783Y801407D01*
Y800030D01*
X1223285Y799528D01*
X1224752D01*
X1225487Y800263D01*
X1232233D01*
G01X1202533Y793570D02*
X1209158D01*
X1210894Y795306D01*
X1211665D01*
G01X1220819Y795379D02*
X1221744D01*
X1223868Y793255D01*
X1225538D01*
X1227199Y794916D01*
X1228623D01*
X1229970Y793569D01*
X1229971Y793570D01*
X1232233D01*
G01X1304616Y842652D02*
Y828293D01*
X1304485Y827977D01*
X1267452Y790944D01*
X1238384D01*
X1237406Y791922D01*
X1236820D01*
G01X1228120Y791953D02*
X1226968D01*
X1226094Y791079D01*
X1226089Y791084D01*
X1224616D01*
X1219957Y789154D01*
X1219106D01*
X1218037Y790223D01*
X1216091D01*
G01X1285427Y844376D02*
X1260055Y819004D01*
X1241896D01*
X1238066Y815174D01*
X1236920D01*
G01X1227720Y815157D02*
X1226087D01*
X1224249Y816995D01*
X1216091D01*
G01X1288145Y839971D02*
X1260584Y812410D01*
X1242662D01*
X1238780Y808528D01*
X1236820D01*
G01X1227720Y808569D02*
X1225201D01*
X1224875Y808895D01*
Y809986D01*
X1224318Y810543D01*
X1220223D01*
X1219982Y810302D01*
X1216091D01*
G01X1202533Y813648D02*
X1208445D01*
X1210185Y815388D01*
X1211665D01*
G01X1220819Y815351D02*
X1222436D01*
X1223222Y814565D01*
Y813428D01*
X1223967Y812683D01*
X1227322D01*
X1228287Y813648D01*
X1232233D01*
G01X1202533Y806955D02*
X1209129D01*
X1210876Y808702D01*
X1211651D01*
X1211665Y808688D01*
G01X1220819Y808628D02*
X1222254D01*
X1222783Y808099D01*
Y806825D01*
X1223509Y806099D01*
X1224631D01*
X1225487Y806955D01*
X1232233D01*
G01X1294539Y842653D02*
Y837868D01*
X1260120Y803449D01*
X1258993D01*
X1257456Y804986D01*
X1256236D01*
X1255446Y804196D01*
Y802002D01*
X1254656Y801212D01*
X1253436D01*
X1252646Y802002D01*
Y804196D01*
X1251856Y804986D01*
X1250636D01*
X1249846Y804196D01*
Y802002D01*
X1249056Y801212D01*
X1247836D01*
X1247046Y802002D01*
Y804196D01*
X1246256Y804986D01*
X1245036D01*
X1244246Y804196D01*
Y802002D01*
X1243456Y801212D01*
X1242483D01*
X1241182Y802513D01*
X1238418D01*
X1238232Y802435D01*
X1236925Y801889D01*
X1236620D01*
G01X1227920Y801875D02*
X1225202D01*
X1223468Y803609D01*
X1216091D01*
G01X1202533Y820341D02*
X1204401D01*
X1205430Y821370D01*
X1206336D01*
X1208016Y819690D01*
X1209146D01*
X1210230Y818606D01*
X1211665D01*
G01X1220819Y818627D02*
X1222186D01*
X1223265Y819706D01*
X1225094D01*
X1227584Y821370D01*
X1229316D01*
X1230345Y820341D01*
X1232233D01*
G01X1216091Y833727D02*
X1218036D01*
X1218037Y833726D01*
X1219305Y834994D01*
X1222102D01*
X1223370Y833726D01*
X1225298D01*
X1227014Y832010D01*
X1228220D01*
G01X1236620Y832028D02*
X1237411D01*
X1238998Y833615D01*
X1248023D01*
X1254637Y840229D01*
X1256691D01*
X1258730Y838190D01*
X1259848D01*
X1260710Y839052D01*
Y840170D01*
X1259632Y841248D01*
Y842366D01*
X1260494Y843228D01*
X1261612D01*
X1262564Y842276D01*
X1263978D01*
X1279910Y858208D01*
G01X1202533Y830381D02*
X1208578D01*
X1210312Y832115D01*
X1211665D01*
G01X1220819Y832054D02*
X1221914D01*
X1222368Y831600D01*
Y830271D01*
X1223082Y829557D01*
X1224147D01*
X1224971Y830381D01*
X1232233D01*
G01X1281916Y851200D02*
X1280242Y849526D01*
Y848833D01*
X1278565Y847156D01*
X1277872D01*
X1276197Y845481D01*
Y844788D01*
X1274520Y843111D01*
X1273827D01*
X1272152Y841436D01*
Y840743D01*
X1270475Y839066D01*
X1269782D01*
X1268107Y837391D01*
Y836698D01*
X1266430Y835021D01*
X1265737D01*
X1264062Y833346D01*
Y832653D01*
X1262385Y830976D01*
X1261692D01*
X1260017Y829301D01*
Y828608D01*
X1258340Y826931D01*
X1257647D01*
X1257044Y826328D01*
X1254674D01*
X1254184Y825838D01*
X1251814D01*
X1251324Y826328D01*
X1248954D01*
X1248464Y825838D01*
X1246094D01*
X1245604Y826328D01*
X1239325D01*
X1238327Y825330D01*
X1236820D01*
G01X1228020Y825324D02*
X1226330D01*
X1225228Y826426D01*
X1223886D01*
X1219907Y824778D01*
X1219123D01*
X1218032Y823687D01*
X1218031Y823688D01*
X1216091D01*
G01X1202533D02*
X1204446D01*
X1205474Y822660D01*
X1206871D01*
X1208551Y820980D01*
X1209095D01*
X1210188Y822073D01*
X1211665D01*
G01X1220819D02*
X1222219D01*
X1223296Y820996D01*
X1224702D01*
X1227192Y822660D01*
X1229222D01*
X1230250Y823688D01*
X1232233D01*
G01X1281003Y852112D02*
X1256509Y827618D01*
X1239353D01*
X1238186Y828785D01*
X1236720D01*
G01X1228020Y828743D02*
X1226260D01*
X1225233Y827716D01*
X1223629D01*
X1219650Y826068D01*
X1219003D01*
X1218037Y827034D01*
X1216091D01*
G01X1277087Y891198D02*
Y891195D01*
X1273281Y887389D01*
X1268432D01*
X1266283Y885240D01*
Y870479D01*
X1241209Y845405D01*
X1236720D01*
G01X1228020Y845395D02*
X1225211D01*
X1223493Y847113D01*
X1216091D01*
G01X1202533Y850459D02*
X1208790D01*
X1210503Y852172D01*
X1211665D01*
G01X1220819Y852132D02*
X1222391D01*
X1222795Y851728D01*
Y850365D01*
X1223496Y849664D01*
X1224737D01*
X1225532Y850459D01*
X1232233D01*
G01X1202533Y843766D02*
X1208831D01*
X1210562Y845497D01*
X1211665D01*
G01X1220819Y845439D02*
X1222396D01*
X1222874Y844961D01*
Y843546D01*
X1223374Y843046D01*
X1227847D01*
X1228567Y843766D01*
X1232233D01*
G01X1273663Y864121D02*
X1270806D01*
X1270251Y863566D01*
Y862448D01*
X1273036Y859663D01*
Y858545D01*
X1272174Y857683D01*
X1271056D01*
X1268271Y860468D01*
X1267153D01*
X1245959Y839274D01*
X1237890D01*
X1237321Y838705D01*
X1236720D01*
G01X1228020Y838693D02*
X1225220D01*
X1223493Y840420D01*
X1216091D01*
G01X1202533Y837074D02*
X1208965D01*
X1210693Y838802D01*
X1211665D01*
G01X1220819Y838768D02*
X1222370D01*
X1222874Y838264D01*
Y836854D01*
X1223374Y836354D01*
X1227961D01*
X1228681Y837074D01*
X1232233D01*
G01X1202533Y867192D02*
X1208159D01*
X1210168Y869201D01*
X1211665D01*
G01X1220819Y868965D02*
X1222420D01*
X1223019Y868366D01*
Y867600D01*
X1223798Y866821D01*
X1225116D01*
X1226033Y867738D01*
X1227864D01*
X1228410Y867192D01*
X1232233D01*
G01X1276665Y897018D02*
X1265303D01*
X1260992Y892707D01*
Y872527D01*
X1244778Y856313D01*
X1243520D01*
X1241728Y854521D01*
Y853263D01*
X1240561Y852096D01*
X1236720D01*
G01X1228020Y852095D02*
X1225204D01*
X1223493Y853806D01*
X1216091D01*
G01X1276265Y904400D02*
X1273895D01*
X1273405Y903910D01*
X1271035D01*
X1270545Y904400D01*
X1268175D01*
X1267685Y903910D01*
X1265315D01*
X1264825Y904400D01*
X1262251D01*
X1260576Y902725D01*
Y902032D01*
X1258899Y900355D01*
X1258206D01*
X1256531Y898680D01*
Y897987D01*
X1254854Y896310D01*
X1254161D01*
X1253483Y895632D01*
Y893262D01*
X1253973Y892772D01*
Y890402D01*
X1253483Y889912D01*
Y887542D01*
X1253973Y887052D01*
Y884682D01*
X1253483Y884192D01*
Y881822D01*
X1253973Y881332D01*
Y878962D01*
X1253483Y878472D01*
Y875590D01*
X1251808Y873915D01*
Y873222D01*
X1250131Y871545D01*
X1249438D01*
X1247763Y869870D01*
Y869177D01*
X1246086Y867500D01*
X1245393D01*
X1241094Y863201D01*
X1239250D01*
X1238187Y862138D01*
X1236920D01*
G01X1227720Y862146D02*
X1226221D01*
X1225128Y863239D01*
X1224133D01*
X1220094Y861566D01*
X1219100D01*
X1218032Y860498D01*
X1218031Y860499D01*
X1216091D01*
G01X1202533D02*
X1204446D01*
X1205474Y859471D01*
X1206861D01*
X1208541Y857791D01*
X1209113D01*
X1210176Y858854D01*
X1211665D01*
G01X1220819Y858859D02*
X1222096D01*
X1223102Y857853D01*
X1224298D01*
X1226830Y859545D01*
X1229296D01*
X1230250Y860499D01*
X1232233D01*
G01X1276279Y905690D02*
X1261716D01*
X1252193Y896167D01*
Y876125D01*
X1240559Y864491D01*
X1239184D01*
X1238127Y865548D01*
X1236961D01*
G01X1227820Y865543D02*
X1226137D01*
X1225123Y864529D01*
X1223876D01*
X1219837Y862856D01*
X1219026D01*
X1218037Y863845D01*
X1216091D01*
G01X1202533Y857152D02*
X1204401D01*
X1205430Y858181D01*
X1206326D01*
X1208006Y856501D01*
X1209084D01*
X1210127Y855458D01*
X1211665D01*
G01X1220819Y855450D02*
X1221996D01*
X1223109Y856563D01*
X1224690D01*
X1227222Y858255D01*
X1229242D01*
X1230345Y857152D01*
X1232233D01*
G01X1202533Y873885D02*
X1208749D01*
X1210766Y875902D01*
X1211665D01*
G01X1220819Y875628D02*
X1221881D01*
X1222560Y874949D01*
Y873979D01*
X1223374Y873165D01*
X1224495D01*
X1225215Y873885D01*
X1232233D01*
G01X1220441Y883924D02*
X1216091D01*
G01X1232233Y880577D02*
X1226951D01*
X1226007Y879633D01*
X1223914D01*
X1222874Y880673D01*
Y881749D01*
X1222370Y882253D01*
X1220819D01*
G01X1211665Y882319D02*
X1210431D01*
X1208689Y880577D01*
X1202533D01*
G01X1282466Y917756D02*
X1252206D01*
X1238772Y904322D01*
Y877006D01*
X1237249Y875483D01*
X1236720D01*
G01X1228020Y875526D02*
X1227061D01*
X1226669Y875918D01*
X1224440D01*
X1223127Y877231D01*
X1216091D01*
G01Y870538D02*
X1220373D01*
X1224287Y871391D01*
X1226838Y872256D01*
X1228020D01*
G01X1236957Y872215D02*
X1237357D01*
X1238267Y871305D01*
X1240229D01*
X1243926Y875002D01*
Y895778D01*
X1245441Y897293D01*
Y898411D01*
X1244276Y899576D01*
Y900694D01*
X1245138Y901556D01*
X1246256D01*
X1247421Y900391D01*
X1248539D01*
X1259542Y911394D01*
X1264630D01*
X1265828Y912592D01*
X1267430D01*
X1268628Y911394D01*
X1270230D01*
X1271428Y912592D01*
X1273030D01*
X1274228Y911394D01*
X1276665D01*
G01X1220441Y890617D02*
X1216091D01*
G01X1232233Y887270D02*
X1226343D01*
X1225470Y886397D01*
X1223527D01*
X1222874Y887050D01*
Y888442D01*
X1222372Y888944D01*
X1220819D01*
G01X1211665Y889011D02*
X1210572D01*
X1208829Y887268D01*
X1208827Y887270D01*
X1202533D01*
G01X1220441Y897310D02*
X1216091D01*
G01X1232233D02*
X1230250D01*
X1229222Y896282D01*
X1226887D01*
X1224529Y894707D01*
X1222401D01*
X1221471Y895637D01*
X1220819D01*
G01X1211665Y895727D02*
X1210966D01*
X1209871Y894632D01*
X1208931D01*
X1207281Y896282D01*
X1205474D01*
X1204446Y897310D01*
X1202533D01*
G01X1220441Y900656D02*
X1216091D01*
G01X1232233Y893963D02*
X1230345D01*
X1229316Y894992D01*
X1227279D01*
X1224921Y893417D01*
X1222430D01*
X1221304Y892291D01*
X1220819D01*
G01X1211665Y892245D02*
X1210921D01*
X1209824Y893342D01*
X1208396D01*
X1206746Y894992D01*
X1205430D01*
X1204401Y893963D01*
X1202533D01*
G01Y917389D02*
X1205977D01*
X1206217Y917149D01*
X1208850D01*
X1210763Y919062D01*
X1211175D01*
G01X1221051D02*
X1222373D01*
X1222874Y918561D01*
Y917687D01*
X1224045Y916516D01*
X1225898D01*
X1226771Y917389D01*
X1232233D01*
G01X1220441Y914042D02*
X1216091D01*
G01X1220441Y907349D02*
X1216091D01*
G01X1232233Y910696D02*
X1226343D01*
X1225470Y909823D01*
X1223527D01*
X1222874Y910476D01*
Y911868D01*
X1222373Y912369D01*
X1220819D01*
G01X1211665Y912404D02*
X1210788D01*
X1209080Y910696D01*
X1202533D01*
G01X1232233Y904003D02*
X1226343D01*
X1225470Y903130D01*
X1223527D01*
X1222874Y903783D01*
Y905175D01*
X1222373Y905676D01*
X1220819D01*
G01X1211665Y905756D02*
X1210619D01*
X1208866Y904003D01*
X1202533D01*
G01X1293288Y937992D02*
X1280899D01*
X1274421Y931514D01*
X1246793D01*
X1244987Y929708D01*
X1241049D01*
X1239286Y927945D01*
Y926178D01*
X1238862Y925754D01*
X1238086D01*
G01X1226450D02*
X1225167D01*
X1223493Y927428D01*
X1216091D01*
G01X1292628Y932782D02*
X1283229D01*
X1274247Y923800D01*
X1244327D01*
X1239589Y919062D01*
X1237245D01*
G01X1227226D02*
X1225166D01*
X1223493Y920735D01*
X1216091D01*
G01X1202533Y924081D02*
X1209144D01*
X1210817Y925754D01*
X1211120D01*
G01X1221076D02*
X1222373D01*
X1222874Y925253D01*
Y923861D01*
X1223527Y923208D01*
X1225470D01*
X1226343Y924081D01*
X1232233D01*
G01X1202533Y934121D02*
X1204446D01*
X1205474Y933093D01*
X1207281D01*
X1208775Y931599D01*
X1209224Y931413D01*
X1209869D01*
X1210904Y932448D01*
X1211177D01*
G01X1221830D02*
X1222277D01*
X1223296Y931429D01*
X1224702D01*
X1227192Y933093D01*
X1229222D01*
X1230250Y934121D01*
X1232233D01*
G01X1202533Y930774D02*
X1204401D01*
X1205430Y931803D01*
X1206746D01*
X1208044Y930505D01*
X1208967Y930123D01*
X1209854D01*
X1210876Y929101D01*
X1211177D01*
G01X1221830D02*
X1222227D01*
X1223265Y930139D01*
X1225094D01*
X1227584Y931803D01*
X1229316D01*
X1230345Y930774D01*
X1232233D01*
G01X1297766Y953659D02*
X1270410D01*
X1267924Y951173D01*
X1255742Y946126D01*
X1241472D01*
X1239104Y943758D01*
Y943310D01*
X1238281Y942487D01*
X1237198D01*
G01X1227353D02*
X1226274D01*
X1223807Y944954D01*
X1222049D01*
X1221255Y944160D01*
X1216091D01*
G01X1202533Y947507D02*
X1209332D01*
X1211008Y949183D01*
X1211153D01*
G01X1221077Y949180D02*
X1222520D01*
X1222874Y948826D01*
Y947287D01*
X1223374Y946787D01*
X1225183D01*
X1225903Y947507D01*
X1232233D01*
G01X1202533Y940814D02*
X1208556D01*
X1210229Y942487D01*
X1210454D01*
G01X1221917D02*
X1222410D01*
X1223120Y941777D01*
Y940384D01*
X1223529Y939975D01*
X1224648D01*
X1225487Y940814D01*
X1232233D01*
G01X1294966Y945325D02*
X1292596D01*
X1292106Y944835D01*
X1289736D01*
X1289246Y945325D01*
X1286876D01*
X1286386Y944835D01*
X1284016D01*
X1283526Y945325D01*
X1281156D01*
X1280666Y944835D01*
X1278296D01*
X1277806Y945325D01*
X1271933D01*
X1269204Y944195D01*
X1268941Y943561D01*
X1266750Y942653D01*
X1266110Y942918D01*
X1263921Y942012D01*
X1263656Y941372D01*
X1261465Y940464D01*
X1260825Y940730D01*
X1258123Y939611D01*
X1256239D01*
X1255749Y939121D01*
X1253379D01*
X1252889Y939611D01*
X1250519D01*
X1250029Y939121D01*
X1247659D01*
X1247169Y939611D01*
X1244799D01*
X1243038Y937850D01*
X1240056D01*
X1239125Y936919D01*
Y936550D01*
X1238369Y935794D01*
X1238022D01*
G01X1226466D02*
X1226259D01*
X1225192Y936861D01*
X1223280D01*
X1221607Y935188D01*
X1219100D01*
X1218032Y934120D01*
X1218031Y934121D01*
X1216091D01*
G01Y937467D02*
X1218037D01*
X1219026Y936478D01*
X1221072D01*
X1222745Y938151D01*
X1225312D01*
X1226301Y939140D01*
X1226466D01*
G01X1238022D02*
X1242503D01*
X1244264Y940901D01*
X1257866D01*
X1268215Y945188D01*
X1268221Y945185D01*
X1271676Y946615D01*
X1294966D01*
G01X1220441Y960892D02*
X1216091D01*
G01X1297766Y960847D02*
X1269539D01*
X1263944Y955252D01*
X1256190Y952039D01*
X1240209D01*
X1237350Y949180D01*
X1237182D01*
G01X1227306D02*
X1225166D01*
X1223493Y950853D01*
X1216091D01*
G01X1264875Y962553D02*
X1256826Y959219D01*
X1236920D01*
G01X1227370D02*
X1223901D01*
X1223212Y959908D01*
Y960971D01*
X1221618Y962565D01*
X1220759D01*
G01X1212020Y962506D02*
X1209833D01*
X1208100Y964239D01*
X1202533D01*
G01X1220441Y957546D02*
X1216091D01*
G01X1268063Y977647D02*
X1260867Y984843D01*
X1240269D01*
X1238150Y982724D01*
X1236720D01*
G01X1228020Y982681D02*
X1225725D01*
X1224014Y980970D01*
X1224013Y980971D01*
X1216091D01*
G01X1202533Y977625D02*
X1209141D01*
X1209142Y977624D01*
X1210882Y979364D01*
X1211665D01*
G01X1220819Y979298D02*
X1222200D01*
X1222680Y978818D01*
Y977938D01*
X1223260Y977358D01*
X1224380D01*
X1225480Y978458D01*
X1228143D01*
X1228976Y977625D01*
X1232233D01*
G01X1263479Y974962D02*
X1261863Y976578D01*
X1242641D01*
X1242078Y976015D01*
X1236720D01*
G01X1228020Y975982D02*
X1227125D01*
X1225421Y974278D01*
X1216091D01*
G01X1263548Y970464D02*
X1259319Y968711D01*
X1238752D01*
X1238162Y969301D01*
X1236720D01*
G01X1228020Y969349D02*
X1222480D01*
X1220715Y967584D01*
X1220714Y967585D01*
X1216091D01*
G01X1202533Y970932D02*
X1206220D01*
X1207153Y969999D01*
X1208800D01*
X1209620Y970819D01*
Y972019D01*
X1210239Y972638D01*
X1211665D01*
G01X1220819Y972605D02*
X1226678D01*
X1228351Y970932D01*
X1232233D01*
G01X1277650Y982736D02*
X1261946Y998440D01*
X1237842D01*
X1236226Y996824D01*
X1222970D01*
X1220503Y994357D01*
X1216091D01*
G01X1202533Y991011D02*
X1209163D01*
X1210913Y992761D01*
X1211665D01*
G01X1220819Y992684D02*
X1222020D01*
X1222730Y991974D01*
Y991375D01*
X1223440Y990665D01*
X1224737D01*
X1226050Y991978D01*
X1228006D01*
X1228973Y991011D01*
X1232233D01*
G01X1272980Y980066D02*
X1261248Y991798D01*
X1239981D01*
X1237520Y989337D01*
X1236920D01*
G01X1227720Y989422D02*
X1225910D01*
X1224152Y987664D01*
X1216091D01*
G01X1202533Y984318D02*
X1207370D01*
X1207950Y984898D01*
Y985582D01*
X1208436Y986068D01*
X1211665D01*
G01X1220819Y985991D02*
X1221948D01*
X1223349Y984590D01*
X1225481D01*
X1226781Y985890D01*
X1228368D01*
X1229940Y984318D01*
X1232233D01*
G01X1306767Y984495D02*
X1303625D01*
X1297357Y990762D01*
X1295667Y993291D01*
X1287785Y1001174D01*
X1262794D01*
X1241991Y1006025D01*
X1241403Y1005659D01*
X1239094Y1006197D01*
X1238728Y1006786D01*
X1236420Y1007324D01*
X1235832Y1006958D01*
X1233523Y1007496D01*
X1233157Y1008085D01*
X1230849Y1008623D01*
X1230261Y1008257D01*
X1227952Y1008795D01*
X1227586Y1009384D01*
X1225278Y1009922D01*
X1224690Y1009557D01*
X1222380Y1010095D01*
X1222015Y1010684D01*
X1219707Y1011222D01*
X1219118Y1010856D01*
X1216809Y1011395D01*
X1216443Y1011984D01*
X1211777Y1013072D01*
X1209510Y1015337D01*
X1209013Y1016540D01*
X1208643Y1017434D01*
Y1020247D01*
X1206683Y1022207D01*
X1205729D01*
X1204651Y1021129D01*
X1202533D01*
G01X1306767Y985785D02*
X1304160D01*
X1298360Y991585D01*
X1296670Y994114D01*
X1288320Y1002464D01*
X1262943D01*
X1212429Y1014245D01*
X1210605Y1016068D01*
X1210410Y1016540D01*
X1209933Y1017691D01*
Y1020782D01*
X1207218Y1023497D01*
X1205661D01*
X1204683Y1024475D01*
X1202533D01*
G01Y1031168D02*
X1206480D01*
X1207497Y1032185D01*
X1209003D01*
X1209580Y1031608D01*
Y1030518D01*
X1210633Y1029465D01*
X1211665D01*
G01X1220819Y1029495D02*
X1223947D01*
X1225620Y1031168D01*
X1232233D01*
G01X1267067Y1011753D02*
X1248330Y1019514D01*
X1241214Y1026630D01*
X1239800Y1027216D01*
X1237461Y1029555D01*
X1236820D01*
G01X1228020Y1029539D02*
X1227193D01*
X1225476Y1027822D01*
X1216091D01*
G01X1268267Y1008809D02*
X1267257D01*
X1247136Y1017144D01*
X1239834Y1024446D01*
X1238408Y1025037D01*
X1236720Y1025736D01*
G01X1228020Y1026083D02*
X1227304D01*
X1222350Y1021129D01*
X1216091D01*
G01X1202533Y1044554D02*
X1208936D01*
X1210682Y1042808D01*
X1211665D01*
G01X1220819Y1042880D02*
X1221282D01*
X1222501Y1044099D01*
X1223787D01*
X1225475Y1042411D01*
X1226493D01*
X1228636Y1044554D01*
X1232233D01*
G01X1216091Y1041207D02*
X1220291D01*
X1222019Y1039479D01*
X1228020D01*
G01X1236820D02*
X1237831D01*
X1238392Y1040040D01*
X1242571D01*
X1254151Y1028460D01*
X1255175Y1028036D01*
X1255177Y1028034D01*
X1273943Y1020260D01*
X1278409Y1015794D01*
G01X1202533Y1037861D02*
X1208936D01*
X1210665Y1036132D01*
X1211665D01*
G01X1220819Y1036188D02*
X1222287D01*
X1223230Y1035245D01*
X1225827D01*
X1226330Y1035748D01*
Y1036788D01*
X1227403Y1037861D01*
X1232233D01*
G01X1272021Y1014059D02*
X1270046Y1016034D01*
X1251075Y1023891D01*
X1242359Y1032607D01*
X1241204Y1033085D01*
X1239677Y1033718D01*
X1238197D01*
X1237249Y1032770D01*
X1236720D01*
G01X1228020Y1032781D02*
X1221447D01*
X1219713Y1034515D01*
X1216091D01*
G01X1220441Y1061286D02*
X1216091D01*
G01Y1047900D02*
X1220812D01*
X1222555Y1046157D01*
X1228020D01*
G01X1236820Y1046125D02*
X1237548D01*
X1238084Y1045589D01*
X1243333D01*
X1244717Y1045016D01*
X1257002Y1032731D01*
X1258028Y1032306D01*
X1258030Y1032304D01*
X1276015Y1024855D01*
X1276016Y1024853D01*
X1277465Y1024253D01*
X1283516Y1018202D01*
G01X1285603Y1019689D02*
X1278913Y1026379D01*
X1277945Y1026780D01*
X1277943Y1026783D01*
X1258428Y1034866D01*
X1246141Y1047153D01*
X1243812Y1048118D01*
X1238807D01*
X1237287Y1049638D01*
X1236720D01*
G01X1228120Y1049657D02*
X1227400D01*
X1227316Y1049573D01*
X1220819D01*
G01X1211665Y1049406D02*
X1210757D01*
X1209575Y1048224D01*
X1208865D01*
X1208420Y1048669D01*
Y1050050D01*
X1208111Y1050359D01*
X1206920D01*
X1206032Y1051247D01*
X1202533D01*
G01X1290365Y1022052D02*
X1281771Y1030646D01*
X1281287Y1030847D01*
X1281284Y1030852D01*
X1261708Y1038960D01*
X1248385Y1052284D01*
X1245079Y1053655D01*
X1238299D01*
X1237543Y1052899D01*
X1236620D01*
G01X1228020Y1052892D02*
X1222210D01*
X1220509Y1054593D01*
X1216091D01*
G01Y1074672D02*
X1219786D01*
X1220915Y1074424D01*
X1222416D01*
X1223400Y1075408D01*
X1224830D01*
X1225280Y1074958D01*
Y1073918D01*
X1226199Y1072999D01*
X1226466D01*
G01X1238007D02*
X1238416D01*
X1239206Y1073789D01*
Y1076062D01*
X1240129Y1076985D01*
X1244394D01*
X1268540Y1052839D01*
X1270449Y1052049D01*
X1271738D01*
G01X1272036Y1046785D02*
X1271715Y1046464D01*
X1270458D01*
X1265756Y1048412D01*
X1247574Y1066594D01*
X1242877D01*
X1242090Y1065807D01*
X1240013D01*
X1239222Y1066598D01*
Y1068666D01*
X1238236Y1069652D01*
X1238000D01*
G01X1226459D02*
X1225168D01*
X1223495Y1067979D01*
X1216091D01*
G01X1202533Y1071326D02*
X1208427D01*
X1208830Y1070923D01*
Y1070204D01*
X1209447Y1069587D01*
X1211136D01*
G01X1221060Y1069652D02*
X1221718D01*
X1222272Y1070206D01*
Y1071150D01*
X1222953Y1071831D01*
X1223983D01*
X1224489Y1071325D01*
X1224490Y1071326D01*
X1232233D01*
G01X1202533Y1064633D02*
X1209168D01*
X1209169Y1064632D01*
X1209665Y1065128D01*
Y1065687D01*
X1210284Y1066306D01*
X1211167D01*
G01X1221091D02*
X1222180D01*
X1222517Y1065969D01*
Y1064288D01*
X1223548Y1063257D01*
X1225576D01*
X1226464Y1064145D01*
X1228487D01*
X1228975Y1064633D01*
X1232233D01*
G01X1202533Y1081365D02*
X1204390D01*
X1205418Y1080337D01*
X1206845D01*
X1208508Y1078674D01*
X1209134D01*
X1210152Y1079692D01*
X1210359D01*
G01X1221837D02*
X1222365D01*
X1223393Y1078664D01*
X1224968D01*
X1227472Y1080337D01*
X1229274D01*
X1230302Y1081365D01*
X1232233D01*
G01X1202533Y1078018D02*
X1204401D01*
X1205430Y1079047D01*
X1206310D01*
X1207973Y1077384D01*
X1209107D01*
X1210145Y1076346D01*
X1210359D01*
G01X1221837Y1076345D02*
X1222051D01*
X1223080Y1077374D01*
X1225360D01*
X1227864Y1079047D01*
X1229276D01*
X1230305Y1078018D01*
X1232233D01*
G01X1216091Y1091404D02*
X1223493D01*
X1225166Y1093077D01*
X1227337D01*
G01X1237007D02*
X1237670D01*
X1238318Y1092429D01*
X1250323D01*
X1263438Y1079314D01*
X1264749Y1076150D01*
X1275728Y1065171D01*
G01X1202533Y1094751D02*
X1208427D01*
X1208830Y1094348D01*
Y1093574D01*
X1209327Y1093077D01*
X1211231D01*
G01X1220901D02*
X1221939D01*
X1222272Y1093410D01*
Y1094575D01*
X1222859Y1095162D01*
X1224077D01*
X1224489Y1094750D01*
X1224490Y1094751D01*
X1232233D01*
G01X1202533Y1088058D02*
X1208444D01*
X1208445Y1088057D01*
X1210119Y1089731D01*
X1210430D01*
G01X1221844D02*
X1222480D01*
X1222923Y1089288D01*
Y1088520D01*
X1223708Y1087735D01*
X1225315D01*
X1226696Y1089116D01*
X1227815D01*
X1228873Y1088058D01*
X1232233D01*
G01X1273414Y1058499D02*
X1271739Y1060174D01*
X1271046D01*
X1269369Y1061851D01*
Y1062544D01*
X1267694Y1064219D01*
X1267001D01*
X1265324Y1065896D01*
Y1066589D01*
X1263649Y1068264D01*
X1262956D01*
X1261279Y1069941D01*
Y1070634D01*
X1259604Y1072309D01*
X1258911D01*
X1257234Y1073986D01*
Y1074679D01*
X1255559Y1076354D01*
X1254866D01*
X1253189Y1078031D01*
Y1078724D01*
X1251600Y1080313D01*
X1247315Y1083176D01*
X1244028Y1084538D01*
X1238601D01*
X1238212Y1084149D01*
Y1083443D01*
X1237807Y1083038D01*
X1237198D01*
G01X1227385D02*
X1226992D01*
X1225939Y1084091D01*
X1223870D01*
X1219865Y1082432D01*
X1219106D01*
X1218038Y1081364D01*
X1218037Y1081365D01*
X1216091D01*
G01X1274327Y1059412D02*
X1252423Y1081316D01*
X1247927Y1084320D01*
X1244285Y1085828D01*
X1238219D01*
X1237663Y1086384D01*
X1237198D01*
G01X1227385D02*
X1226809D01*
X1225806Y1085381D01*
X1223613D01*
X1219608Y1083722D01*
X1219020D01*
X1218031Y1084711D01*
X1216091D01*
G01X1273820Y1074237D02*
X1270714Y1077343D01*
X1267673Y1084683D01*
X1254636Y1097720D01*
X1238920D01*
X1237542Y1096342D01*
X1237208D01*
G01X1227336D02*
X1225212D01*
X1224713Y1096841D01*
X1219573Y1097963D01*
X1219249Y1098097D01*
X1216091D01*
G01Y1111483D02*
X1218052D01*
X1219552Y1109983D01*
X1221243D01*
X1222129Y1110665D01*
X1222331Y1111427D01*
X1223642Y1112187D01*
X1224732Y1111897D01*
X1225908Y1109869D01*
X1226232Y1109783D01*
X1227920D01*
G01X1236620Y1109772D02*
X1237743D01*
X1238426Y1110055D01*
X1238858Y1110487D01*
X1239530Y1112117D01*
X1239833Y1112852D01*
X1240726Y1113745D01*
X1244302D01*
X1245506Y1112541D01*
X1246624D01*
X1247728Y1113645D01*
X1249980D01*
X1251113Y1112512D01*
X1252232D01*
X1252769Y1113049D01*
X1256947D01*
X1266821Y1103175D01*
G01X1263257Y1099610D02*
X1257295Y1105572D01*
X1238407D01*
X1237471Y1106508D01*
X1236820D01*
G01X1228020Y1106544D02*
X1226654D01*
X1225967Y1105857D01*
Y1103068D01*
X1225509Y1102610D01*
X1224505D01*
X1222325Y1104790D01*
X1216091D01*
G01X1202533Y1108137D02*
X1208270D01*
X1208830Y1107577D01*
Y1106833D01*
X1209260Y1106403D01*
X1211665D01*
G01X1220819Y1106459D02*
X1221713D01*
X1222272Y1107018D01*
Y1107961D01*
X1222953Y1108642D01*
X1223983D01*
X1224488Y1108137D01*
X1232233D01*
G01X1202533Y1101444D02*
X1209168D01*
X1209169Y1101443D01*
X1209665Y1101939D01*
Y1102779D01*
X1210067Y1103181D01*
X1211665D01*
G01X1220819Y1103139D02*
X1221399D01*
X1224258Y1100280D01*
X1227308D01*
X1228472Y1101444D01*
X1232233D01*
G01X1216091Y1128215D02*
X1224727D01*
X1226458Y1129946D01*
X1227807D01*
G01X1236961Y1129888D02*
X1237220D01*
X1237747Y1129670D01*
X1239263Y1128154D01*
X1261300D01*
X1273585Y1115869D01*
G01X1202533Y1124869D02*
X1208321D01*
X1210057Y1126605D01*
X1211665D01*
G01X1220819Y1126615D02*
X1222388D01*
X1223032Y1125971D01*
Y1124979D01*
X1223605Y1124406D01*
X1224671D01*
X1226028Y1125763D01*
X1229003D01*
X1229898Y1124868D01*
X1229899Y1124869D01*
X1232233D01*
G01X1270470Y1109954D02*
X1268795Y1111629D01*
X1268102D01*
X1266425Y1113306D01*
Y1113999D01*
X1264750Y1115674D01*
X1264057D01*
X1262380Y1117351D01*
Y1118044D01*
X1260413Y1120011D01*
X1257825Y1120525D01*
X1257249Y1120140D01*
X1254924Y1120603D01*
X1254539Y1121180D01*
X1251777Y1121729D01*
X1250421D01*
X1249931Y1121239D01*
X1247561D01*
X1247071Y1121729D01*
X1244701D01*
X1244211Y1121239D01*
X1241841D01*
X1241351Y1121729D01*
X1239819D01*
X1239087Y1120997D01*
Y1120185D01*
X1238682Y1119780D01*
X1236920D01*
G01X1227920Y1119783D02*
X1226298D01*
X1225179Y1120902D01*
X1224455D01*
X1220450Y1119243D01*
X1219106D01*
X1218038Y1118175D01*
X1218037Y1118176D01*
X1216091D01*
G01X1202533D02*
X1204390D01*
X1205521Y1117045D01*
X1206896D01*
X1208456Y1115485D01*
X1209770D01*
X1210826Y1116541D01*
X1211665D01*
G01X1220819D02*
X1221989D01*
X1223055Y1115475D01*
X1224968D01*
X1227472Y1117148D01*
X1229274D01*
X1230302Y1118176D01*
X1232233D01*
G01X1271383Y1110867D02*
X1261049Y1121201D01*
X1251905Y1123019D01*
X1238399D01*
X1238195Y1123223D01*
X1236720D01*
G01X1227720Y1123266D02*
X1226164D01*
X1225090Y1122192D01*
X1224198D01*
X1220193Y1120533D01*
X1219020D01*
X1218031Y1121522D01*
X1216091D01*
G01X1202533Y1114829D02*
X1204401D01*
X1205327Y1115755D01*
X1206361D01*
X1207921Y1114195D01*
X1209759D01*
X1210839Y1113115D01*
X1211665D01*
G01X1220819Y1113114D02*
X1222029D01*
X1223100Y1114185D01*
X1225360D01*
X1227864Y1115858D01*
X1229276D01*
X1230305Y1114829D01*
X1232233D01*
G01X1282169Y1129353D02*
X1282166D01*
X1281225Y1130294D01*
Y1131107D01*
X1279430Y1132902D01*
Y1134020D01*
X1279998Y1134588D01*
Y1135706D01*
X1279136Y1136568D01*
X1278018D01*
X1277450Y1136000D01*
X1276332D01*
X1275470Y1136862D01*
Y1137980D01*
X1276038Y1138548D01*
Y1139666D01*
X1275176Y1140528D01*
X1274058D01*
X1273490Y1139960D01*
X1272372D01*
X1270501Y1141831D01*
X1259122D01*
X1258332Y1141041D01*
Y1140494D01*
X1257542Y1139704D01*
X1256322D01*
X1255532Y1140494D01*
Y1141041D01*
X1254742Y1141831D01*
X1253522D01*
X1252732Y1141041D01*
Y1140494D01*
X1251942Y1139704D01*
X1250722D01*
X1249932Y1140494D01*
Y1141041D01*
X1249142Y1141831D01*
X1247922D01*
X1247132Y1141041D01*
Y1140494D01*
X1246342Y1139704D01*
X1245122D01*
X1244332Y1140494D01*
Y1141041D01*
X1243542Y1141831D01*
X1238754D01*
X1237290Y1143295D01*
X1236720D01*
G01X1228020Y1143327D02*
X1226496D01*
X1226106Y1142937D01*
Y1141192D01*
X1225323Y1140409D01*
X1223949D01*
X1222757Y1141601D01*
X1216091D01*
G01X1202533Y1144948D02*
X1208427D01*
X1208830Y1144545D01*
Y1143728D01*
X1209365Y1143193D01*
X1211665D01*
G01X1220819Y1143274D02*
X1221717D01*
X1222272Y1143829D01*
Y1144772D01*
X1222953Y1145453D01*
X1223983D01*
X1224489Y1144947D01*
X1224490Y1144948D01*
X1232233D01*
G01X1202533Y1138255D02*
X1209168D01*
X1209169Y1138254D01*
X1209665Y1138750D01*
Y1139380D01*
X1210264Y1139979D01*
X1211665D01*
G01X1220819Y1139928D02*
X1221933D01*
X1222517Y1139344D01*
Y1138396D01*
X1223288Y1137625D01*
X1225164D01*
X1225794Y1138255D01*
X1232233D01*
G01X1277169Y1119453D02*
X1263225Y1133397D01*
X1241975D01*
X1241267Y1134105D01*
X1238282D01*
X1237412Y1133235D01*
X1236920D01*
G01X1227920Y1133155D02*
X1226935D01*
X1224287Y1134053D01*
X1220373Y1134908D01*
X1216091D01*
G01X1202533Y1131562D02*
X1207513D01*
X1207980Y1131095D01*
Y1130413D01*
X1208535Y1129858D01*
X1211665D01*
G01X1220819Y1129831D02*
X1222525D01*
X1223082Y1130388D01*
Y1131514D01*
X1223661Y1132093D01*
X1224942D01*
X1225474Y1131561D01*
X1225475Y1131562D01*
X1232233D01*
G01X1216091Y1148294D02*
X1222255D01*
X1226616Y1150102D01*
X1227920D01*
G01X1236020Y1150011D02*
X1237500D01*
X1238063Y1150574D01*
X1240682D01*
X1241472Y1149784D01*
Y1147834D01*
X1242262Y1147044D01*
X1243482D01*
X1244272Y1147834D01*
Y1149784D01*
X1245062Y1150574D01*
X1246282D01*
X1247072Y1149784D01*
Y1147834D01*
X1247862Y1147044D01*
X1249082D01*
X1249872Y1147834D01*
Y1149784D01*
X1250662Y1150574D01*
X1269906D01*
X1274809Y1148543D01*
X1284769Y1138583D01*
G01X1287906Y1145789D02*
X1286231Y1147464D01*
X1285538D01*
X1283861Y1149141D01*
Y1149834D01*
X1282186Y1151509D01*
X1281493D01*
X1279816Y1153186D01*
Y1153880D01*
X1278785Y1154911D01*
X1275331Y1156341D01*
X1274691Y1156076D01*
X1272500Y1156984D01*
X1272235Y1157624D01*
X1269598Y1158716D01*
X1267469D01*
X1266979Y1158226D01*
X1264609D01*
X1264119Y1158716D01*
X1261749D01*
X1261259Y1158226D01*
X1258889D01*
X1258399Y1158716D01*
X1255862D01*
X1255372Y1158226D01*
X1253002D01*
X1252512Y1158716D01*
X1250142D01*
X1249652Y1158226D01*
X1247282D01*
X1246792Y1158716D01*
X1244422D01*
X1243932Y1158226D01*
X1241562D01*
X1241072Y1158716D01*
X1238702D01*
X1238328Y1158342D01*
Y1157590D01*
X1237398Y1156660D01*
X1236920D01*
G01X1227920Y1156523D02*
X1226602D01*
X1226320Y1156805D01*
Y1157622D01*
X1226001Y1157941D01*
X1224760D01*
X1220011Y1155974D01*
X1219026D01*
X1218038Y1154986D01*
X1218037Y1154987D01*
X1216091D01*
G01X1202533D02*
X1204390D01*
X1205418Y1153959D01*
X1206845D01*
X1208508Y1152296D01*
X1209134D01*
X1210190Y1153352D01*
X1211665D01*
G01X1220819D02*
X1221341D01*
X1222407Y1152286D01*
X1223591D01*
X1226095Y1153959D01*
X1229274D01*
X1230302Y1154987D01*
X1232233D01*
G01X1288819Y1146702D02*
X1279516Y1156005D01*
X1269855Y1160006D01*
X1236920D01*
G01X1227720Y1160152D02*
X1227059D01*
X1226138Y1159231D01*
X1224503D01*
X1219754Y1157264D01*
X1219100D01*
X1218031Y1158333D01*
X1216091D01*
G01X1202533Y1151641D02*
X1204402D01*
X1205430Y1152669D01*
X1206310D01*
X1207973Y1151006D01*
X1209107D01*
X1210168Y1149945D01*
X1211665D01*
G01X1220819Y1149925D02*
X1221167D01*
X1222238Y1150996D01*
X1223983D01*
X1226487Y1152669D01*
X1229276D01*
X1230304Y1151641D01*
X1232233D01*
G01Y1175066D02*
X1228873D01*
X1228227Y1175712D01*
X1226229D01*
X1225403Y1174886D01*
X1224171D01*
X1223503Y1175554D01*
Y1176227D01*
X1222991Y1176739D01*
X1220819D01*
G01X1211665Y1176817D02*
X1210291D01*
X1209665Y1176191D01*
Y1175563D01*
X1209168Y1175066D01*
X1202533D01*
G01X1293446Y1156629D02*
X1279965Y1170110D01*
X1270213Y1174149D01*
X1241719D01*
X1237548Y1169978D01*
X1236620D01*
G01X1227920Y1169983D02*
X1227079D01*
X1224832Y1170745D01*
X1220373Y1171719D01*
X1216091D01*
G01X1291529Y1151412D02*
X1282573Y1160368D01*
X1265551Y1167419D01*
X1243685D01*
X1241917Y1165651D01*
X1238366D01*
X1237305Y1166712D01*
X1237150D01*
X1237134Y1166728D01*
X1236720D01*
G01X1228020Y1166775D02*
X1226096D01*
X1221874Y1165026D01*
X1216091D01*
G01X1202533Y1168373D02*
X1208427D01*
X1208830Y1167970D01*
Y1167407D01*
X1209594Y1166643D01*
X1211665D01*
G01X1220819Y1166699D02*
X1221717D01*
X1222272Y1167254D01*
Y1168197D01*
X1223243Y1169168D01*
X1224441D01*
X1225431Y1168758D01*
X1225816Y1168373D01*
X1232233D01*
G01X1202533Y1161680D02*
X1209074D01*
X1209665Y1162271D01*
Y1162805D01*
X1210274Y1163414D01*
X1211665D01*
G01X1220819Y1163353D02*
X1221847D01*
X1223224Y1161976D01*
X1224839D01*
X1226216Y1163353D01*
X1227300D01*
X1228973Y1161680D01*
X1232233D01*
G01X1220441Y1185105D02*
X1216091D01*
G01X1220441Y1178412D02*
X1216091D01*
G01X1232233Y1181759D02*
X1226448D01*
X1225746Y1182461D01*
X1224669D01*
X1223831Y1181623D01*
Y1180775D01*
X1223141Y1180085D01*
X1220819D01*
G01X1211665Y1180021D02*
X1209348D01*
X1208830Y1180539D01*
Y1181259D01*
X1208330Y1181759D01*
X1202533D01*
G01X1220441Y1191798D02*
X1216091D01*
G01X1232233D02*
X1230302D01*
X1229274Y1190770D01*
X1226504D01*
X1224000Y1189097D01*
X1222407D01*
X1221379Y1190125D01*
X1220819D01*
G01X1211665Y1190163D02*
X1210944D01*
X1209888Y1189107D01*
X1208944D01*
X1207281Y1190770D01*
X1205418D01*
X1204390Y1191798D01*
X1202533D01*
G01X1232233Y1188452D02*
X1230304D01*
X1229276Y1189480D01*
X1226896D01*
X1224392Y1187807D01*
X1222404D01*
X1221376Y1186779D01*
X1220819D01*
G01X1211665Y1186756D02*
X1210888D01*
X1209827Y1187817D01*
X1208409D01*
X1206746Y1189480D01*
X1205430D01*
X1204402Y1188452D01*
X1202533D01*
G01X1232233Y1205184D02*
X1226450D01*
X1226449Y1205183D01*
X1225746Y1205886D01*
X1224579D01*
X1223831Y1205138D01*
Y1204200D01*
X1223141Y1203510D01*
X1220819D01*
G01X1211665Y1203430D02*
X1209364D01*
X1208830Y1203964D01*
Y1204626D01*
X1208272Y1205184D01*
X1202533D01*
G01X1232233Y1198491D02*
X1228873D01*
X1228185Y1199179D01*
X1226271D01*
X1225403Y1198311D01*
X1224171D01*
X1223503Y1198979D01*
Y1199652D01*
X1222991Y1200164D01*
X1220819D01*
G01X1211665Y1200234D02*
X1210283D01*
X1209665Y1199616D01*
Y1198986D01*
X1209169Y1198490D01*
X1209168Y1198491D01*
X1202533D01*
G01X1220441Y1208530D02*
X1216091D01*
G01X1220441Y1201837D02*
X1216091D01*
G01X1220441Y1195144D02*
X1216091D01*
G01Y1221916D02*
X1219351D01*
X1223868Y1220929D01*
X1226056Y1220186D01*
X1228020D01*
G01X1236720Y1220181D02*
X1238569D01*
X1239539Y1221151D01*
X1240758D01*
X1264548Y1197361D01*
X1266543Y1196028D01*
X1266761Y1194934D01*
X1265728Y1193389D01*
X1265946Y1192294D01*
X1266962Y1191615D01*
X1268056Y1191833D01*
X1269089Y1193378D01*
X1270183Y1193596D01*
X1271199Y1192917D01*
X1271417Y1191822D01*
X1270384Y1190277D01*
X1270602Y1189182D01*
X1271618Y1188503D01*
X1272712Y1188721D01*
X1273745Y1190266D01*
X1274839Y1190484D01*
X1275980Y1189721D01*
X1297508Y1168193D01*
G01X1295895Y1162679D02*
X1275491Y1183083D01*
X1264079D01*
X1247066Y1200096D01*
Y1201214D01*
X1248850Y1202998D01*
Y1204116D01*
X1247988Y1204978D01*
X1246870D01*
X1245086Y1203194D01*
X1243968D01*
X1243329Y1203833D01*
Y1209723D01*
X1238565Y1214487D01*
Y1216154D01*
X1238559Y1216188D01*
X1238552Y1216227D01*
X1237488Y1216938D01*
X1236820D01*
G01X1228020Y1216960D02*
X1224982D01*
X1223245Y1215223D01*
X1216091D01*
G01X1202533Y1218570D02*
X1208427D01*
X1208830Y1218167D01*
Y1217350D01*
X1209330Y1216850D01*
X1211665D01*
G01X1220819Y1216896D02*
X1221717D01*
X1222272Y1217451D01*
Y1218394D01*
X1222953Y1219075D01*
X1223983D01*
X1224489Y1218569D01*
X1224490Y1218570D01*
X1232233D01*
G01X1202533Y1211877D02*
X1209168D01*
X1209169Y1211876D01*
X1209665Y1212372D01*
Y1213002D01*
X1210241Y1213578D01*
X1211665D01*
G01X1220819Y1213550D02*
X1221879D01*
X1223553Y1211876D01*
X1224849D01*
X1226152Y1213179D01*
X1227671D01*
X1228973Y1211877D01*
X1232233D01*
G01X1202533Y1228609D02*
X1204390D01*
X1205418Y1227581D01*
X1206845D01*
X1208508Y1225918D01*
X1209134D01*
X1210190Y1226974D01*
X1211665D01*
G01X1220819D02*
X1221989D01*
X1223055Y1225908D01*
X1224968D01*
X1227472Y1227581D01*
X1229274D01*
X1230302Y1228609D01*
X1232233D01*
G01X1202533Y1225263D02*
X1204402D01*
X1205430Y1226291D01*
X1206310D01*
X1207973Y1224628D01*
X1209107D01*
X1210168Y1223567D01*
X1211665D01*
G01X1220819Y1223547D02*
X1222029D01*
X1223100Y1224618D01*
X1225360D01*
X1227864Y1226291D01*
X1229276D01*
X1230304Y1225263D01*
X1232233D01*
G01X1305473Y1178155D02*
X1251192Y1232436D01*
X1246210Y1235765D01*
X1240306Y1238211D01*
X1238703D01*
X1238283Y1238631D01*
Y1239572D01*
X1237490Y1240365D01*
X1236620D01*
G01X1228120Y1240361D02*
X1225793D01*
X1225163Y1239731D01*
Y1238677D01*
X1224544Y1238058D01*
X1223510D01*
X1222920Y1238648D01*
X1216091D01*
G01X1202533Y1241995D02*
X1207699D01*
X1209423Y1240271D01*
X1211601D01*
G01X1220755Y1240324D02*
X1221673D01*
X1222272Y1240923D01*
Y1242123D01*
X1222986Y1242837D01*
X1224628D01*
X1225470Y1241995D01*
X1232233D01*
G01X1202533Y1235302D02*
X1209153D01*
X1210826Y1236975D01*
X1211665D01*
G01X1220819Y1237006D02*
X1222099D01*
X1224062Y1235043D01*
X1225261D01*
X1227031Y1236813D01*
X1228432D01*
X1229943Y1235302D01*
X1232233D01*
G01X1300994Y1173676D02*
X1277233Y1197437D01*
X1260513Y1211160D01*
X1253964Y1217709D01*
X1253271D01*
X1251594Y1219386D01*
Y1220079D01*
X1249919Y1221754D01*
X1249226D01*
X1247549Y1223431D01*
Y1224124D01*
X1245874Y1225799D01*
X1245181D01*
X1243505Y1227475D01*
Y1228168D01*
X1240688Y1230985D01*
X1240094Y1231231D01*
X1239479D01*
X1238497Y1230249D01*
X1236720D01*
G01X1228120Y1230259D02*
X1226275D01*
X1225185Y1231349D01*
X1224206D01*
X1220167Y1229676D01*
X1219106D01*
X1218038Y1228608D01*
X1218037Y1228609D01*
X1216091D01*
G01Y1231955D02*
X1218031D01*
X1219020Y1230966D01*
X1219910D01*
X1223949Y1232639D01*
X1225176D01*
X1225970Y1233433D01*
X1226580Y1233686D01*
X1228120D01*
G01X1236620Y1233650D02*
X1238307D01*
X1239436Y1232521D01*
X1240351D01*
X1241419Y1232079D01*
X1261381Y1212118D01*
X1278101Y1198395D01*
X1301907Y1174589D01*
G01X1309043Y1181725D02*
X1254068Y1236700D01*
X1248995Y1240089D01*
X1245904Y1241368D01*
X1245477Y1242399D01*
X1245879Y1243370D01*
X1245452Y1244401D01*
X1244323Y1244869D01*
X1243292Y1244442D01*
X1242890Y1243471D01*
X1241859Y1243044D01*
X1239751Y1243918D01*
X1238377D01*
X1238075Y1243616D01*
X1236720D01*
G01X1228120Y1243604D02*
X1227483D01*
X1223918Y1244813D01*
X1221500Y1245341D01*
X1216091D01*
G01X1319793Y842652D02*
Y824195D01*
X1317138Y817785D01*
X1275842Y776489D01*
X1263109Y771215D01*
X1242466D01*
X1241229Y769978D01*
X1232399D01*
X1232233Y770144D01*
G01X1314753Y842652D02*
Y825192D01*
X1312865Y820634D01*
X1272990Y780759D01*
X1262475Y776404D01*
X1232666D01*
X1232233Y776837D01*
G01X1308427Y842652D02*
Y826455D01*
X1307991Y825402D01*
X1268418Y785829D01*
X1235588D01*
X1234540Y786877D01*
X1232233D01*
G01Y783530D02*
X1234513D01*
X1234514Y783529D01*
X1235524Y784539D01*
X1256925D01*
X1257415Y784049D01*
X1259785D01*
X1260275Y784539D01*
X1262645D01*
X1263135Y784049D01*
X1265505D01*
X1265995Y784539D01*
X1268953D01*
X1275519Y791105D01*
X1276212D01*
X1277889Y792782D01*
Y793475D01*
X1279564Y795150D01*
X1280257D01*
X1281934Y796827D01*
Y797520D01*
X1283609Y799195D01*
X1284302D01*
X1285979Y800872D01*
Y801565D01*
X1287654Y803240D01*
X1288347D01*
X1290024Y804917D01*
Y805610D01*
X1291699Y807285D01*
X1292392D01*
X1294069Y808962D01*
Y809655D01*
X1295744Y811330D01*
X1296437D01*
X1298114Y813007D01*
Y813700D01*
X1299789Y815375D01*
X1300482D01*
X1302159Y817052D01*
Y817745D01*
X1303834Y819420D01*
X1304527D01*
X1306203Y821096D01*
Y821789D01*
X1309085Y824671D01*
X1309717Y826198D01*
Y842652D01*
G01X1297057Y842653D02*
Y836824D01*
X1295406Y835173D01*
Y834055D01*
X1297057Y832404D01*
Y831286D01*
X1296195Y830424D01*
X1295077D01*
X1293426Y832075D01*
X1292308D01*
X1291446Y831213D01*
Y830095D01*
X1293123Y828418D01*
Y827300D01*
X1292261Y826438D01*
X1291143D01*
X1289466Y828115D01*
X1288348D01*
X1287486Y827253D01*
Y826135D01*
X1289163Y824458D01*
Y823340D01*
X1288301Y822478D01*
X1287183D01*
X1285506Y824155D01*
X1284388D01*
X1283526Y823293D01*
Y822175D01*
X1285203Y820498D01*
Y819380D01*
X1284341Y818518D01*
X1283223D01*
X1281546Y820195D01*
X1280428D01*
X1258862Y798629D01*
X1241472D01*
X1240369Y799732D01*
X1239540Y799897D01*
X1237698Y800263D01*
X1232233D01*
G01X1302094Y842652D02*
Y829149D01*
X1275579Y802634D01*
X1274463D01*
X1272783Y804312D01*
X1271668D01*
X1270804Y803448D01*
Y802331D01*
X1272483Y800654D01*
Y799538D01*
X1271619Y798674D01*
X1270503D01*
X1268823Y800352D01*
X1267707D01*
X1266843Y799488D01*
Y798372D01*
X1268523Y796694D01*
Y795578D01*
X1266433Y793488D01*
X1239404D01*
X1238529Y794363D01*
X1235002D01*
X1234208Y793569D01*
X1234207Y793570D01*
X1232233D01*
G01X1286365Y841752D02*
X1259541Y814928D01*
X1257666D01*
X1256108Y816486D01*
X1254866D01*
X1253308Y814928D01*
X1252066D01*
X1250508Y816486D01*
X1249266D01*
X1247708Y814928D01*
X1246466D01*
X1244908Y816486D01*
X1243078D01*
X1239067Y812475D01*
X1237363D01*
X1236190Y813648D01*
X1232233D01*
G01X1289926Y838191D02*
X1260135Y808400D01*
X1258325D01*
X1256833Y809892D01*
X1255525D01*
X1254033Y808400D01*
X1252725D01*
X1251233Y809892D01*
X1249925D01*
X1248433Y808400D01*
X1247125D01*
X1245633Y809892D01*
X1243958D01*
X1240076Y806010D01*
X1235225D01*
X1234280Y806955D01*
X1232233D01*
G01X1279221Y853897D02*
X1259735Y834411D01*
X1258617D01*
X1256090Y836938D01*
X1254972D01*
X1254110Y836076D01*
Y834958D01*
X1256637Y832431D01*
Y831313D01*
X1255705Y830381D01*
X1232233D01*
G01X1284044Y849072D02*
X1258274Y823302D01*
X1235863D01*
X1235852Y823313D01*
X1235764D01*
X1235389Y823688D01*
X1232233D01*
G01Y820341D02*
X1234348D01*
X1236019Y822012D01*
X1241649D01*
X1242139Y821522D01*
X1244509D01*
X1244999Y822012D01*
X1247369D01*
X1247859Y821522D01*
X1250229D01*
X1250719Y822012D01*
X1253089D01*
X1253579Y821522D01*
X1255949D01*
X1256439Y822012D01*
X1258809D01*
X1260687Y823890D01*
X1261380D01*
X1263057Y825567D01*
Y826260D01*
X1264732Y827935D01*
X1265425D01*
X1267102Y829612D01*
Y830305D01*
X1268777Y831980D01*
X1269470D01*
X1271147Y833657D01*
Y834350D01*
X1272822Y836025D01*
X1273515D01*
X1275192Y837702D01*
Y838395D01*
X1276867Y840070D01*
X1277560D01*
X1279237Y841747D01*
Y842440D01*
X1280912Y844115D01*
X1281605D01*
X1283282Y845792D01*
Y846485D01*
X1284957Y848160D01*
G01X1276665Y894357D02*
X1275780Y893472D01*
X1273660D01*
X1272740Y892552D01*
Y890782D01*
X1271977Y890019D01*
X1269980D01*
X1269190Y890809D01*
Y893667D01*
X1268400Y894457D01*
X1267180D01*
X1266390Y893667D01*
Y890809D01*
X1265600Y890019D01*
X1264626D01*
X1263595Y888988D01*
Y871418D01*
X1240235Y848058D01*
X1238219D01*
X1235818Y850459D01*
X1232233D01*
G01X1277995Y888540D02*
X1274274Y884819D01*
X1269669D01*
X1268801Y883951D01*
Y881273D01*
X1269591Y880483D01*
X1271467D01*
X1272257Y879693D01*
Y878473D01*
X1271467Y877683D01*
X1269591D01*
X1268801Y876893D01*
Y875673D01*
X1269591Y874883D01*
X1271467D01*
X1272257Y874093D01*
Y872873D01*
X1271467Y872083D01*
X1269591D01*
X1268801Y871293D01*
Y869413D01*
X1242157Y842769D01*
X1235262D01*
X1234265Y843766D01*
X1232233D01*
G01X1277565Y859512D02*
X1271796Y853743D01*
X1270678D01*
X1267893Y856528D01*
X1266775D01*
X1265913Y855666D01*
Y854548D01*
X1268698Y851763D01*
Y850645D01*
X1267836Y849783D01*
X1266718D01*
X1263933Y852568D01*
X1262815D01*
X1261953Y851706D01*
Y850588D01*
X1264738Y847803D01*
Y846597D01*
X1263887Y845746D01*
X1256359D01*
X1247026Y836413D01*
X1236282D01*
X1235621Y837074D01*
X1232233D01*
G01X1276665Y908784D02*
X1260684D01*
X1249558Y897658D01*
Y895695D01*
X1248768Y894905D01*
X1247404D01*
X1246614Y894115D01*
Y892895D01*
X1247404Y892105D01*
X1248768D01*
X1249558Y891315D01*
Y890095D01*
X1248768Y889305D01*
X1247404D01*
X1246614Y888515D01*
Y887295D01*
X1247404Y886505D01*
X1248768D01*
X1249558Y885715D01*
Y884495D01*
X1248768Y883705D01*
X1247404D01*
X1246614Y882915D01*
Y881695D01*
X1247404Y880905D01*
X1248768D01*
X1249558Y880115D01*
Y877071D01*
X1240665Y868178D01*
X1236392D01*
X1235406Y867192D01*
X1232233D01*
G01X1276265Y901387D02*
X1263538D01*
X1256542Y894391D01*
Y874391D01*
X1242656Y860505D01*
X1241281Y859935D01*
X1238488D01*
X1237150Y860486D01*
X1235113D01*
X1235100Y860499D01*
X1232233D01*
G01Y857152D02*
X1235360D01*
X1236116Y857908D01*
Y858714D01*
X1236598Y859196D01*
X1236894D01*
X1238232Y858645D01*
X1241538D01*
X1243387Y859411D01*
X1245697Y861721D01*
X1246390D01*
X1248067Y863398D01*
Y864091D01*
X1249742Y865766D01*
X1250435D01*
X1252112Y867443D01*
Y868136D01*
X1253787Y869811D01*
X1254480D01*
X1256157Y871488D01*
Y872181D01*
X1257832Y873856D01*
Y877251D01*
X1258322Y877741D01*
Y880111D01*
X1257832Y880601D01*
Y882971D01*
X1258322Y883461D01*
Y885831D01*
X1257832Y886321D01*
Y888691D01*
X1258322Y889181D01*
Y891551D01*
X1257832Y892041D01*
Y893856D01*
X1260028Y896052D01*
X1260721D01*
X1262398Y897729D01*
Y898422D01*
X1264073Y900097D01*
X1264825D01*
X1265315Y899607D01*
X1267685D01*
X1268175Y900097D01*
X1270545D01*
X1271035Y899607D01*
X1273405D01*
X1273895Y900097D01*
X1276265D01*
G01X1280268Y913910D02*
X1279708D01*
X1278424Y915194D01*
X1253398D01*
X1251904Y913700D01*
Y912582D01*
X1253709Y910777D01*
Y909659D01*
X1252847Y908797D01*
X1251729D01*
X1249924Y910602D01*
X1248806D01*
X1247944Y909740D01*
Y908622D01*
X1249749Y906817D01*
Y905699D01*
X1248887Y904837D01*
X1247769D01*
X1245964Y906642D01*
X1244846D01*
X1241337Y903133D01*
Y875976D01*
X1239246Y873885D01*
X1232233D01*
G01X1236583Y880577D02*
X1232233D01*
G01X1236583Y887270D02*
X1232233D01*
G01X1236583Y897310D02*
X1232233D01*
G01X1236583Y893963D02*
X1232233D01*
G01X1236583Y910696D02*
X1232233D01*
G01X1236583Y904003D02*
X1232233D01*
G01X1293288Y935302D02*
X1282188D01*
X1273813Y926927D01*
X1270780D01*
X1269990Y927717D01*
Y928099D01*
X1269200Y928889D01*
X1267980D01*
X1267190Y928099D01*
Y927717D01*
X1266400Y926927D01*
X1265180D01*
X1264390Y927717D01*
Y928099D01*
X1263600Y928889D01*
X1262380D01*
X1261590Y928099D01*
Y927717D01*
X1260800Y926927D01*
X1259580D01*
X1258790Y927717D01*
Y928099D01*
X1258000Y928889D01*
X1256780D01*
X1255990Y928099D01*
Y927717D01*
X1255200Y926927D01*
X1253980D01*
X1253190Y927717D01*
Y928099D01*
X1252400Y928889D01*
X1251180D01*
X1250390Y928099D01*
Y927717D01*
X1249600Y926927D01*
X1243805D01*
X1239922Y923044D01*
X1238634D01*
X1237597Y924081D01*
X1232233D01*
G01Y917389D02*
X1237289D01*
X1238397Y916281D01*
X1240817D01*
X1245791Y921255D01*
X1275998D01*
X1280351Y925608D01*
X1281467D01*
X1282791Y924285D01*
X1283907D01*
X1284771Y925149D01*
Y926265D01*
X1283447Y927588D01*
Y928704D01*
X1285006Y930263D01*
X1286763D01*
X1287553Y929473D01*
Y928826D01*
X1288343Y928036D01*
X1289563D01*
X1290353Y928826D01*
Y929473D01*
X1291143Y930263D01*
X1292628D01*
G01X1232233Y930774D02*
X1235447D01*
X1236204Y931531D01*
Y932265D01*
X1236655Y932716D01*
X1239025D01*
X1239515Y932226D01*
X1241885D01*
X1242375Y932716D01*
X1244433D01*
X1246239Y934522D01*
X1248609D01*
X1249099Y934032D01*
X1251469D01*
X1251959Y934522D01*
X1254329D01*
X1254819Y934032D01*
X1257189D01*
X1257679Y934522D01*
X1258862D01*
X1261051Y935428D01*
X1261691Y935163D01*
X1263882Y936071D01*
X1264147Y936711D01*
X1266991Y937889D01*
X1268358D01*
X1268778Y937469D01*
Y935877D01*
X1270324Y934331D01*
X1272639D01*
X1274185Y935877D01*
Y940484D01*
X1274701Y941000D01*
X1277806D01*
X1278296Y940510D01*
X1280666D01*
X1281156Y941000D01*
X1283526D01*
X1284016Y940510D01*
X1286386D01*
X1286876Y941000D01*
X1289246D01*
X1289736Y940510D01*
X1292106D01*
X1292596Y941000D01*
X1294966D01*
G01X1297766Y957227D02*
X1296664Y958329D01*
X1294245D01*
X1293455Y957539D01*
Y957029D01*
X1292665Y956239D01*
X1291445D01*
X1290655Y957029D01*
Y957539D01*
X1289865Y958329D01*
X1288645D01*
X1287855Y957539D01*
Y957029D01*
X1287065Y956239D01*
X1285845D01*
X1285055Y957029D01*
Y957539D01*
X1284265Y958329D01*
X1283045D01*
X1282255Y957539D01*
Y957029D01*
X1281465Y956239D01*
X1280245D01*
X1279455Y957029D01*
Y957539D01*
X1278665Y958329D01*
X1277445D01*
X1276655Y957539D01*
Y957029D01*
X1275865Y956239D01*
X1274645D01*
X1273855Y957029D01*
Y957539D01*
X1273065Y958329D01*
X1270986D01*
X1265960Y953303D01*
X1256278Y949293D01*
X1241065D01*
X1238651Y946879D01*
X1237532D01*
X1236904Y947507D01*
X1232233D01*
G01X1297866Y951002D02*
X1296235D01*
X1295445Y950212D01*
Y949923D01*
X1294655Y949133D01*
X1293435D01*
X1292645Y949923D01*
Y950351D01*
X1291855Y951141D01*
X1290635D01*
X1289845Y950351D01*
Y949923D01*
X1289055Y949133D01*
X1287835D01*
X1287045Y949923D01*
Y950212D01*
X1286255Y951002D01*
X1285035D01*
X1284245Y950212D01*
Y949923D01*
X1283455Y949133D01*
X1282235D01*
X1281445Y949923D01*
Y950351D01*
X1280655Y951141D01*
X1279435D01*
X1278645Y950351D01*
Y949923D01*
X1277855Y949133D01*
X1276635D01*
X1274766Y951002D01*
X1272790D01*
X1270914Y949126D01*
X1257583Y943605D01*
X1242538D01*
X1239747Y940814D01*
X1232233D01*
G01X1294966Y942290D02*
X1274166D01*
X1272895Y941019D01*
Y936412D01*
X1272104Y935621D01*
X1270859D01*
X1270068Y936412D01*
Y938004D01*
X1268893Y939179D01*
X1266734D01*
X1258605Y935812D01*
X1245704D01*
X1243898Y934006D01*
X1235885D01*
X1235771Y934120D01*
X1233301D01*
X1233300Y934121D01*
X1232233D01*
G01X1264164Y965008D02*
X1258624Y962709D01*
X1241071D01*
X1241070Y962708D01*
X1236139D01*
X1234608Y964239D01*
X1232233D01*
G01X1265744Y976400D02*
X1260697Y981447D01*
X1241857D01*
X1239215Y978805D01*
X1237580D01*
X1236400Y977625D01*
X1232233D01*
G01X1262167Y972651D02*
X1259479D01*
X1258721Y971893D01*
X1236453D01*
X1235492Y970932D01*
X1232233D01*
G01X1275613Y981199D02*
X1262291Y994521D01*
X1239081D01*
X1235571Y991011D01*
X1232233D01*
G01X1270230Y979216D02*
X1260566Y988880D01*
X1242967D01*
X1240444Y987835D01*
X1239084Y987271D01*
X1236131Y984318D01*
X1232233D01*
G01Y1021129D02*
X1234241D01*
X1235400Y1022288D01*
X1236319D01*
X1246328Y1012279D01*
X1263925Y1004989D01*
X1289882D01*
X1299599Y995271D01*
X1302307Y991219D01*
X1304972Y988554D01*
X1306767D01*
G01Y989844D02*
X1305507D01*
X1303310Y992042D01*
X1300602Y996094D01*
X1290417Y1006279D01*
X1264182D01*
X1262640Y1006918D01*
X1262375Y1007558D01*
X1260184Y1008466D01*
X1259544Y1008201D01*
X1257355Y1009108D01*
X1257090Y1009748D01*
X1254899Y1010656D01*
X1254259Y1010391D01*
X1252070Y1011297D01*
X1251805Y1011938D01*
X1249614Y1012846D01*
X1248974Y1012580D01*
X1247059Y1013373D01*
X1236854Y1023578D01*
X1235320D01*
X1234423Y1024475D01*
X1232233D01*
G01X1280681Y1017466D02*
X1276023Y1022124D01*
X1256604Y1030169D01*
X1256602Y1030171D01*
X1255576Y1030596D01*
X1243614Y1042558D01*
X1237724D01*
X1236414Y1043868D01*
X1235140D01*
X1234454Y1044554D01*
X1232233D01*
G01X1274377Y1015427D02*
X1271086Y1018718D01*
X1252727Y1026323D01*
X1241528Y1037522D01*
X1239223D01*
X1237969Y1036268D01*
X1236109D01*
X1234516Y1037861D01*
X1232233D01*
G01X1269682Y1012770D02*
X1268506Y1013946D01*
X1249649Y1021756D01*
X1241230Y1030175D01*
X1241204Y1030186D01*
X1238831Y1031168D01*
X1232233D01*
G01X1287983Y1020870D02*
X1280339Y1028514D01*
X1279616Y1028814D01*
X1279614Y1028817D01*
X1260280Y1036825D01*
X1247997Y1049110D01*
X1244043Y1050748D01*
X1239729D01*
X1239230Y1051247D01*
X1232233D01*
G01X1271738Y1049511D02*
X1269852D01*
X1267102Y1050650D01*
X1247406Y1070346D01*
X1246288D01*
X1245060Y1069118D01*
X1243942D01*
X1243152Y1069908D01*
Y1071026D01*
X1244308Y1072182D01*
Y1073444D01*
X1243328Y1074424D01*
X1241665D01*
X1240875Y1073634D01*
Y1073003D01*
X1239197Y1071325D01*
X1238588D01*
X1238585Y1071326D01*
X1232233D01*
G01X1273830Y1044991D02*
X1272708Y1043869D01*
X1269080D01*
X1265073Y1045529D01*
X1250328Y1060274D01*
X1249210D01*
X1248772Y1059836D01*
X1247654D01*
X1246792Y1060698D01*
Y1061816D01*
X1247230Y1062254D01*
Y1063372D01*
X1246547Y1064055D01*
X1243973D01*
X1243183Y1063265D01*
Y1061261D01*
X1242393Y1060471D01*
X1241173D01*
X1240383Y1061261D01*
Y1062497D01*
X1239593Y1063287D01*
X1238633D01*
X1237288Y1064632D01*
X1234132D01*
X1234131Y1064633D01*
X1232233D01*
G01Y1078018D02*
X1233338D01*
X1233339Y1078017D01*
X1235440D01*
X1236157Y1078734D01*
Y1079687D01*
X1236474Y1080004D01*
X1238953D01*
X1239443Y1079514D01*
X1241813D01*
X1242303Y1080004D01*
X1244673D01*
X1249084Y1076734D01*
X1250141Y1075677D01*
Y1074983D01*
X1251818Y1073306D01*
X1252511D01*
X1254186Y1071631D01*
Y1070939D01*
X1255863Y1069262D01*
X1256556D01*
X1258231Y1067587D01*
Y1066894D01*
X1259908Y1065217D01*
X1260601D01*
X1262276Y1063542D01*
Y1062849D01*
X1263953Y1061172D01*
X1264646D01*
X1266321Y1059497D01*
Y1058804D01*
X1267998Y1057127D01*
X1268691D01*
X1270366Y1055452D01*
G01X1275728Y1068743D02*
X1268519Y1075952D01*
X1267794Y1077704D01*
X1266672Y1078169D01*
X1265910Y1080009D01*
X1266375Y1081131D01*
X1265494Y1083255D01*
X1265088Y1083661D01*
X1262822D01*
X1262032Y1084451D01*
Y1086717D01*
X1261128Y1087621D01*
X1258862D01*
X1258072Y1088411D01*
Y1090677D01*
X1257168Y1091581D01*
X1254902D01*
X1254112Y1092371D01*
Y1094637D01*
X1253580Y1095169D01*
X1240983D01*
X1240982Y1095168D01*
X1238721D01*
X1238304Y1094751D01*
X1232233D01*
G01X1275728Y1061601D02*
X1261312Y1076017D01*
Y1077815D01*
X1260231Y1078896D01*
X1258433D01*
X1257352Y1079977D01*
Y1081775D01*
X1256271Y1082856D01*
X1254473D01*
X1253392Y1083937D01*
Y1085735D01*
X1252311Y1086816D01*
X1249453D01*
X1246442Y1089827D01*
X1244201D01*
X1242730Y1088356D01*
X1240397D01*
X1239495Y1089258D01*
X1238376D01*
X1237176Y1088058D01*
X1232233D01*
G01X1271279Y1056364D02*
X1249929Y1077714D01*
X1245099Y1081294D01*
X1232304D01*
X1232233Y1081365D01*
G01X1265041Y1101394D02*
X1258325Y1108110D01*
X1256644D01*
X1255854Y1108900D01*
Y1109686D01*
X1255064Y1110476D01*
X1253844D01*
X1253054Y1109686D01*
Y1108900D01*
X1252264Y1108110D01*
X1251044D01*
X1250254Y1108900D01*
Y1109707D01*
X1249464Y1110497D01*
X1248244D01*
X1247454Y1109707D01*
Y1108900D01*
X1246664Y1108110D01*
X1245444D01*
X1244654Y1108900D01*
Y1109728D01*
X1243864Y1110518D01*
X1242644D01*
X1241854Y1109728D01*
Y1108900D01*
X1241044Y1108090D01*
X1237992D01*
X1237945Y1108137D01*
X1232233D01*
G01X1261469Y1097822D02*
X1257207Y1102084D01*
X1255449D01*
X1255015Y1101650D01*
Y1101649D01*
X1254581Y1101215D01*
X1252749D01*
X1252315Y1101649D01*
Y1102519D01*
X1251881Y1102953D01*
X1250049D01*
X1249615Y1102519D01*
Y1101649D01*
X1249181Y1101215D01*
X1247349D01*
X1246915Y1101649D01*
Y1102519D01*
X1246481Y1102953D01*
X1244649D01*
X1244215Y1102519D01*
Y1101649D01*
X1243781Y1101215D01*
X1241949D01*
X1241515Y1101649D01*
Y1102519D01*
X1241081Y1102953D01*
X1238538D01*
X1237669Y1102084D01*
X1236327D01*
X1235687Y1101444D01*
X1232233D01*
G01X1273454Y1112438D02*
X1260256Y1125636D01*
X1259276D01*
X1258197Y1124557D01*
X1257109D01*
X1256030Y1125636D01*
X1238347D01*
X1237575Y1124864D01*
X1236944D01*
X1235785Y1126023D01*
X1235202D01*
X1234047Y1124868D01*
X1234046Y1124869D01*
X1232233D01*
G01X1269423Y1106706D02*
X1260270Y1115859D01*
X1255213Y1117953D01*
X1254091Y1118176D01*
X1232233D01*
G01X1268510Y1105794D02*
X1266835Y1107469D01*
X1266142D01*
X1264465Y1109146D01*
Y1109839D01*
X1262790Y1111514D01*
X1262097D01*
X1260420Y1113191D01*
Y1113884D01*
X1259539Y1114765D01*
X1254837Y1116712D01*
X1253964Y1116886D01*
X1252829D01*
X1252339Y1116396D01*
X1249969D01*
X1249479Y1116886D01*
X1247109D01*
X1246619Y1116396D01*
X1244249D01*
X1243759Y1116886D01*
X1241389D01*
X1240899Y1116396D01*
X1238529D01*
X1238039Y1116886D01*
X1236588D01*
X1236135Y1116433D01*
Y1115523D01*
X1235440Y1114828D01*
X1233339D01*
X1233338Y1114829D01*
X1232233D01*
G01X1281172Y1125356D02*
X1280223Y1126305D01*
X1279197D01*
X1277706Y1124814D01*
X1276758D01*
X1275743Y1125829D01*
Y1126947D01*
X1278207Y1129411D01*
Y1130529D01*
X1277345Y1131391D01*
X1276227D01*
X1273763Y1128927D01*
X1272645D01*
X1271783Y1129789D01*
Y1130907D01*
X1274247Y1133371D01*
Y1134489D01*
X1273385Y1135351D01*
X1272267D01*
X1269803Y1132887D01*
X1268685D01*
X1267823Y1133749D01*
Y1134867D01*
X1270287Y1137331D01*
Y1138449D01*
X1269425Y1139311D01*
X1268307D01*
X1265893Y1136897D01*
X1243455D01*
X1242184Y1138168D01*
X1239099D01*
X1237374Y1139893D01*
X1236143D01*
X1234504Y1138254D01*
X1234503Y1138255D01*
X1232233D01*
G01X1275387Y1117671D02*
X1262221Y1130837D01*
X1240455D01*
X1239730Y1131562D01*
X1232233D01*
G01X1283232Y1134512D02*
Y1136227D01*
X1275109Y1144350D01*
X1269062D01*
X1268272Y1145140D01*
Y1147065D01*
X1267482Y1147855D01*
X1266262D01*
X1265472Y1147065D01*
Y1145140D01*
X1264682Y1144350D01*
X1263462D01*
X1262672Y1145140D01*
Y1147065D01*
X1261882Y1147855D01*
X1260662D01*
X1259872Y1147065D01*
Y1145140D01*
X1259082Y1144350D01*
X1257862D01*
X1257072Y1145140D01*
Y1147065D01*
X1256282Y1147855D01*
X1255062D01*
X1254272Y1147065D01*
Y1145140D01*
X1253482Y1144350D01*
X1240006D01*
X1239018Y1145338D01*
X1236143D01*
X1235753Y1144948D01*
X1232233D01*
G01X1285778Y1143661D02*
X1277095Y1152344D01*
X1270991Y1154872D01*
X1232348D01*
X1232233Y1154987D01*
G01Y1151641D02*
X1235796D01*
X1235797Y1151640D01*
X1236226Y1152069D01*
Y1152889D01*
X1236919Y1153582D01*
X1239037D01*
X1239527Y1153092D01*
X1241897D01*
X1242387Y1153582D01*
X1244757D01*
X1245247Y1153092D01*
X1247617D01*
X1248107Y1153582D01*
X1250477D01*
X1250967Y1153092D01*
X1253337D01*
X1253827Y1153582D01*
X1256197D01*
X1256687Y1153092D01*
X1259057D01*
X1259547Y1153582D01*
X1261917D01*
X1262407Y1153092D01*
X1264777D01*
X1265267Y1153582D01*
X1270734D01*
X1276364Y1151250D01*
X1276775Y1150839D01*
Y1150146D01*
X1278452Y1148469D01*
X1279145D01*
X1280820Y1146794D01*
Y1146101D01*
X1282497Y1144424D01*
X1283190D01*
X1284865Y1142749D01*
G01X1236583Y1175066D02*
X1232233D01*
G01X1292960Y1153543D02*
X1283964Y1162539D01*
X1279102Y1164551D01*
X1278675Y1165582D01*
X1279145Y1166717D01*
X1278718Y1167749D01*
X1277589Y1168217D01*
X1276558Y1167790D01*
X1276088Y1166654D01*
X1275057Y1166227D01*
X1273928Y1166695D01*
X1273501Y1167726D01*
X1273971Y1168861D01*
X1273544Y1169893D01*
X1272415Y1170361D01*
X1271384Y1169934D01*
X1270914Y1168798D01*
X1269883Y1168371D01*
X1266103Y1169937D01*
X1260828D01*
X1260038Y1170727D01*
Y1170841D01*
X1259248Y1171631D01*
X1258028D01*
X1257238Y1170841D01*
Y1170727D01*
X1256448Y1169937D01*
X1255228D01*
X1254438Y1170727D01*
Y1170841D01*
X1253648Y1171631D01*
X1252428D01*
X1251638Y1170841D01*
Y1170727D01*
X1250848Y1169937D01*
X1249628D01*
X1248838Y1170727D01*
Y1170841D01*
X1248048Y1171631D01*
X1246828D01*
X1246038Y1170841D01*
Y1170727D01*
X1245248Y1169937D01*
X1242097D01*
X1240533Y1168373D01*
X1232233D01*
G01X1289737Y1149619D02*
X1281120Y1158236D01*
X1270547Y1162616D01*
X1265584D01*
X1264794Y1163406D01*
Y1164106D01*
X1264004Y1164896D01*
X1262784D01*
X1261994Y1164106D01*
Y1163406D01*
X1261204Y1162616D01*
X1259984D01*
X1259194Y1163406D01*
Y1164106D01*
X1258404Y1164896D01*
X1257184D01*
X1256394Y1164106D01*
Y1163406D01*
X1255604Y1162616D01*
X1254384D01*
X1253594Y1163406D01*
Y1164106D01*
X1252804Y1164896D01*
X1251584D01*
X1250794Y1164106D01*
Y1163406D01*
X1250004Y1162616D01*
X1248784D01*
X1247994Y1163406D01*
Y1164106D01*
X1247204Y1164896D01*
X1245984D01*
X1245194Y1164106D01*
Y1163406D01*
X1244404Y1162616D01*
X1237505D01*
X1236569Y1161680D01*
X1232233D01*
G01X1236583Y1181759D02*
X1232233D01*
G01X1236583Y1191798D02*
X1232233D01*
G01X1236583Y1188452D02*
X1232233D01*
G01X1236583Y1205184D02*
X1232233D01*
G01X1236583Y1198491D02*
X1232233D01*
G01X1295977Y1166160D02*
X1276183Y1185954D01*
X1268419D01*
X1262954Y1191419D01*
Y1195391D01*
X1261417Y1196928D01*
X1260299D01*
X1257617Y1194246D01*
X1256499D01*
X1255637Y1195108D01*
Y1196226D01*
X1258319Y1198908D01*
Y1200026D01*
X1257457Y1200888D01*
X1256339D01*
X1253657Y1198206D01*
X1252539D01*
X1251677Y1199068D01*
Y1200186D01*
X1254359Y1202868D01*
Y1203986D01*
X1239775Y1218570D01*
X1232233D01*
G01X1294115Y1160898D02*
X1275014Y1179999D01*
X1263578D01*
X1260801Y1182776D01*
X1259683D01*
X1258220Y1181313D01*
X1257102D01*
X1256240Y1182175D01*
Y1183293D01*
X1257703Y1184756D01*
Y1185874D01*
X1256841Y1186736D01*
X1255723D01*
X1254260Y1185273D01*
X1253142D01*
X1252280Y1186135D01*
Y1187253D01*
X1253743Y1188716D01*
Y1189834D01*
X1252881Y1190696D01*
X1251763D01*
X1250300Y1189233D01*
X1249182D01*
X1248320Y1190095D01*
Y1191213D01*
X1249783Y1192676D01*
Y1193794D01*
X1248921Y1194656D01*
X1247803D01*
X1246340Y1193193D01*
X1245222D01*
X1244360Y1194055D01*
Y1195173D01*
X1245823Y1196636D01*
Y1197754D01*
X1240718Y1202859D01*
Y1208617D01*
X1237458Y1211877D01*
X1232233D01*
G01X1298295Y1170978D02*
X1275039Y1194234D01*
X1273208Y1195737D01*
X1272518Y1195669D01*
X1270685Y1197174D01*
X1270617Y1197864D01*
X1268786Y1199367D01*
X1268096Y1199299D01*
X1266263Y1200804D01*
X1266195Y1201493D01*
X1264364Y1202996D01*
X1263674Y1202928D01*
X1261841Y1204433D01*
X1261773Y1205123D01*
X1259942Y1206626D01*
X1259252Y1206558D01*
X1257419Y1208063D01*
X1257351Y1208752D01*
X1254488Y1211102D01*
X1241041Y1224550D01*
X1239833Y1225049D01*
X1239014Y1225387D01*
X1239012Y1225388D01*
X1236854Y1226283D01*
X1235397D01*
X1234376Y1225262D01*
X1234375Y1225263D01*
X1232233D01*
G01X1307017Y1180174D02*
X1252667Y1234524D01*
X1247522Y1237962D01*
X1239833Y1241148D01*
X1237788Y1241995D01*
X1232233D01*
G01Y1235302D02*
X1233905D01*
X1234776Y1236173D01*
X1238593D01*
X1239833Y1235659D01*
X1244361Y1233784D01*
X1245516Y1233013D01*
X1245857Y1231292D01*
X1247154Y1230425D01*
X1248875Y1230767D01*
X1250156Y1229911D01*
X1250758Y1229309D01*
Y1228191D01*
X1250373Y1227806D01*
Y1226688D01*
X1251235Y1225826D01*
X1252353D01*
X1252738Y1226211D01*
X1253856D01*
X1254718Y1225349D01*
Y1224231D01*
X1254333Y1223846D01*
Y1222728D01*
X1255195Y1221866D01*
X1256313D01*
X1256698Y1222251D01*
X1257816D01*
X1258678Y1221389D01*
Y1220271D01*
X1258293Y1219886D01*
Y1218768D01*
X1259155Y1217906D01*
X1260273D01*
X1260658Y1218291D01*
X1261776D01*
X1262638Y1217429D01*
Y1216311D01*
X1262257Y1215930D01*
Y1214812D01*
X1263119Y1213950D01*
X1264237D01*
X1264618Y1214331D01*
X1265736D01*
X1266598Y1213469D01*
Y1212351D01*
X1266604Y1212345D01*
Y1211233D01*
X1267395Y1210442D01*
X1269625D01*
X1270558Y1209509D01*
Y1208391D01*
X1272538Y1206411D01*
X1273656D01*
X1303692Y1176375D01*
G01X1232233Y1228609D02*
X1234463D01*
X1235499Y1227573D01*
X1237111D01*
X1239833Y1226447D01*
X1241772Y1225645D01*
X1255356Y1212060D01*
X1275907Y1195192D01*
X1299208Y1171891D01*
G01X1313921Y882329D02*
Y880219D01*
G01X1312070Y885533D02*
Y883423D01*
G01X1313921Y895146D02*
Y893036D01*
G01X1312070Y891942D02*
Y889832D01*
G01X1310221Y888737D02*
Y886627D01*
G01X1313921Y888737D02*
Y886627D01*
G01X1317621Y882329D02*
Y880219D01*
G01X1319470Y885533D02*
Y883424D01*
X1319471Y883423D01*
G01X1325021Y901555D02*
Y899446D01*
X1325020Y899445D01*
G01X1325021Y895146D02*
Y893037D01*
X1325020Y893036D01*
G01X1326870Y891942D02*
X1326871Y891941D01*
Y889832D01*
G01X1330570Y891942D02*
X1330571Y891941D01*
Y889832D01*
G01X1317621Y895146D02*
Y893037D01*
X1317620Y893036D01*
G01X1319470Y891942D02*
Y889832D01*
G01X1323171Y898350D02*
Y896240D01*
G01X1330570Y898350D02*
X1330571Y898349D01*
Y896240D01*
G01X1317621Y888737D02*
Y886627D01*
G01X1326870Y898350D02*
X1326871Y898349D01*
Y896240D01*
G01X1321321Y888737D02*
Y886627D01*
G01X1325021Y914372D02*
X1325020Y914371D01*
Y912262D01*
G01X1326870Y911167D02*
X1326871Y911166D01*
Y909057D01*
G01X1330570Y911167D02*
X1330571Y911166D01*
Y909057D01*
G01X1326870Y904759D02*
X1326871Y904758D01*
Y902649D01*
G01X1330570Y904759D02*
X1330571Y904758D01*
Y902649D01*
G01X1323171Y917576D02*
Y915466D01*
G01X1330570Y917576D02*
X1330571Y917575D01*
Y915466D01*
G01X1326870Y917576D02*
Y915467D01*
X1326871Y915466D01*
G01X1325021Y933598D02*
Y931488D01*
G01X1326870Y930393D02*
X1326871Y930392D01*
Y928283D01*
G01X1330570Y930393D02*
X1330571Y930392D01*
Y928283D01*
G01X1330570Y923985D02*
X1330571Y923984D01*
Y921875D01*
G01X1326870Y923985D02*
Y921876D01*
X1326871Y921875D01*
G01X1325021Y920780D02*
X1325020Y920779D01*
Y918670D01*
G01X1326870Y943210D02*
X1326871Y943209D01*
Y941100D01*
G01X1325021Y940006D02*
X1325020Y940005D01*
Y937896D01*
G01X1330570Y943210D02*
X1330571Y941100D01*
G01X1323171Y936801D02*
Y934691D01*
G01X1330570Y936801D02*
Y934692D01*
X1330571Y934691D01*
G01X1326870Y936801D02*
Y934692D01*
X1326871Y934691D01*
G01X1326870Y949619D02*
X1326871Y949618D01*
Y947509D01*
G01X1330570Y949619D02*
X1330571Y949618D01*
Y947509D01*
G01X1325021Y952823D02*
X1325020Y952822D01*
Y950713D01*
G01X1326870Y962436D02*
X1326871Y962435D01*
Y960326D01*
G01X1325021Y959232D02*
X1325020Y959231D01*
Y957122D01*
G01X1330570Y962436D02*
X1330571Y962435D01*
Y960326D01*
G01X1326870Y956027D02*
X1326871Y956026D01*
Y953917D01*
G01X1330570Y956027D02*
Y953918D01*
X1330571Y953917D01*
G01X1323171Y956027D02*
Y953918D01*
X1323172Y953917D01*
G01X1326870Y981662D02*
X1326871Y981661D01*
Y979552D01*
G01X1330570Y981662D02*
X1330571Y981661D01*
Y979552D01*
G01X1325021Y978457D02*
X1325020Y978456D01*
Y976347D01*
G01X1323171Y975253D02*
Y973143D01*
G01X1325021Y972049D02*
X1325020Y972048D01*
Y969939D01*
G01X1326870Y968845D02*
X1326871Y968844D01*
Y966735D01*
G01X1330570Y968845D02*
X1330571Y968844D01*
Y966735D01*
G01X1327303Y997574D02*
Y999684D01*
G01X1323603Y1003983D02*
Y1006093D01*
G01X1325454Y1000778D02*
Y1002887D01*
X1325453Y1002888D01*
G01X1327303Y1012501D02*
Y1010391D01*
G01X1325454Y1007187D02*
Y1009296D01*
X1325453Y1009297D01*
G01X1327303Y1029617D02*
X1327304Y1029618D01*
Y1031727D01*
G01X1325454Y1026413D02*
Y1028521D01*
X1325453Y1028522D01*
Y1028523D01*
G01X1325454Y1020004D02*
X1325453Y1020005D01*
Y1022114D01*
G01X1327303Y1016800D02*
Y1018910D01*
G01X1323603Y1023208D02*
Y1025318D01*
G01X1327303Y1023208D02*
X1327313Y1023218D01*
Y1025309D01*
X1327304Y1025318D01*
G01X1325454Y1045639D02*
X1325453D01*
Y1047749D01*
G01X1325454Y1039230D02*
Y1041339D01*
X1325453Y1041340D01*
G01X1327303Y1036026D02*
Y1038136D01*
G01X1323603Y1042434D02*
Y1044544D01*
G01X1327303Y1042434D02*
Y1044544D01*
G01X1325454Y1058455D02*
X1325453Y1058456D01*
Y1060565D01*
G01X1327303Y1055251D02*
Y1057361D01*
G01X1323603Y1061660D02*
Y1063770D01*
G01X1327303Y1061660D02*
Y1063770D01*
G01Y1048842D02*
Y1050952D01*
G01Y1068068D02*
Y1070177D01*
X1327304Y1070178D01*
G01X1325454Y1064864D02*
Y1066973D01*
X1325453Y1066974D01*
G01X1325454Y1077681D02*
Y1079790D01*
X1325453Y1079791D01*
G01X1327303Y1074477D02*
Y1076587D01*
G01Y1087294D02*
Y1089404D01*
G01X1325454Y1084090D02*
Y1086198D01*
G03X1325453Y1086200I-3J0D01*
G01X1323603Y1080885D02*
Y1082995D01*
G01X1327303Y1080885D02*
Y1082995D01*
G01X1332421Y901555D02*
Y899446D01*
X1332420Y899445D01*
G01X1332421Y895146D02*
X1332420Y895145D01*
Y893036D01*
G01X1334270Y898350D02*
Y896241D01*
X1334271Y896240D01*
G01X1339821Y901555D02*
X1339820Y901554D01*
Y899445D01*
G01X1343521Y901555D02*
X1343520Y901554D01*
Y899445D01*
G01X1332421Y914372D02*
X1332420Y914371D01*
Y912262D01*
G01X1334270Y917576D02*
X1334271Y917575D01*
Y915466D01*
G01X1339821Y914372D02*
X1339820Y914371D01*
Y912262D01*
G01X1337970Y911167D02*
X1337971Y911166D01*
Y909057D01*
G01X1343521Y914372D02*
X1343520Y914371D01*
Y912262D01*
G01X1345370Y911167D02*
X1345371Y911166D01*
Y909057D01*
G01X1337970Y904759D02*
X1337971Y904758D01*
Y902649D01*
G01X1345370Y904759D02*
X1345371Y904758D01*
Y902649D01*
G01X1336121Y907963D02*
X1336120Y907962D01*
Y905853D01*
G01X1343521Y907963D02*
Y905854D01*
X1343520Y905853D01*
G01X1339821Y907963D02*
Y905854D01*
X1339820Y905853D01*
G01X1332421Y933598D02*
X1332420Y933597D01*
Y931488D01*
G01X1339821Y933598D02*
X1339820Y933597D01*
Y931488D01*
G01X1332421Y920780D02*
X1332420Y920779D01*
Y918670D01*
G01X1337970Y930393D02*
X1337971Y930392D01*
Y928283D01*
G01X1343521Y933598D02*
X1343520Y933597D01*
Y931488D01*
G01X1345370Y930393D02*
X1345371Y930392D01*
Y928283D01*
G01X1337970Y923985D02*
X1337971Y923984D01*
Y921875D01*
G01X1339821Y920780D02*
X1339820Y920779D01*
Y918670D01*
G01X1345370Y923985D02*
X1345371Y923984D01*
Y921875D01*
G01X1343521Y920780D02*
X1343520Y920779D01*
Y918670D01*
G01X1336121Y927189D02*
X1336120Y927188D01*
Y925079D01*
G01X1343521Y927189D02*
X1343520Y927188D01*
Y925079D01*
G01X1339821Y927189D02*
Y925080D01*
X1339820Y925079D01*
G01X1332421Y940006D02*
X1332420Y937896D01*
G01X1334270Y936801D02*
X1334271Y936800D01*
Y934691D01*
G01X1337970Y943210D02*
X1337971Y943209D01*
Y941100D01*
G01X1339821Y940006D02*
X1339820Y940005D01*
Y937896D01*
G01X1345370Y943210D02*
X1345371Y943209D01*
Y941100D01*
G01X1343521Y940006D02*
X1343520Y940005D01*
Y937896D01*
G01X1337970Y949619D02*
X1337971Y949618D01*
Y947509D01*
G01X1345370Y949619D02*
X1345371Y949618D01*
Y947509D01*
G01X1343521Y946414D02*
Y944305D01*
X1343520Y944304D01*
G01X1336121Y946414D02*
Y944305D01*
X1336120Y944304D01*
G01X1339821Y946414D02*
Y944305D01*
X1339820Y944304D01*
G01X1332421Y952823D02*
X1332420Y952822D01*
Y950713D01*
G01X1332421Y959232D02*
X1332420Y959231D01*
Y957122D01*
G01X1334270Y956027D02*
Y953918D01*
X1334271Y953917D01*
G01X1336121Y965640D02*
X1336120Y965639D01*
Y963530D01*
G01X1339821Y952823D02*
X1339820Y952822D01*
Y950713D01*
G01X1343521Y952823D02*
X1343520Y952822D01*
Y950713D01*
G01X1337970Y962436D02*
X1337971Y962435D01*
Y960326D01*
G01X1339821Y959232D02*
X1339820Y959231D01*
Y957122D01*
G01X1345370Y962436D02*
X1345371Y962435D01*
Y960326D01*
G01X1343521Y959232D02*
X1343520Y959231D01*
Y957122D01*
G01X1345370Y981662D02*
X1345371Y981661D01*
Y979552D01*
G01X1343521Y978457D02*
X1343520Y978456D01*
Y976347D01*
G01X1337970Y981662D02*
X1337971Y981661D01*
Y979552D01*
G01X1339821Y978457D02*
X1339820Y978456D01*
Y976347D01*
G01X1332421Y978457D02*
X1332420Y978456D01*
Y976347D01*
G01X1332421Y972049D02*
X1332420Y972048D01*
Y969939D01*
G01X1334270Y975253D02*
Y973144D01*
X1334271Y973143D01*
G01X1339821Y972049D02*
X1339820Y972048D01*
Y969939D01*
G01X1343521Y972049D02*
X1343520Y972048D01*
Y969939D01*
G01X1337970Y968845D02*
X1337971Y968844D01*
Y966735D01*
G01X1345370Y968845D02*
X1345371Y968844D01*
Y966735D01*
G01X1336121Y984866D02*
X1336120Y984865D01*
Y982756D01*
G01X1343521Y984866D02*
Y982757D01*
X1343520Y982756D01*
G01X1339821Y984866D02*
Y982757D01*
X1339820Y982756D01*
G01X1331003Y997574D02*
Y999684D01*
G01X1338403Y997574D02*
X1338404Y997575D01*
Y999684D01*
G01X1345803Y997574D02*
Y999683D01*
X1345804Y999684D01*
G01X1334703Y1003983D02*
Y1006092D01*
X1334704Y1006093D01*
G01X1332854Y1000778D02*
Y1002887D01*
X1332853Y1002888D01*
G01X1331003Y1012501D02*
Y1010391D01*
G01X1332854Y1007187D02*
Y1009296D01*
X1332853Y1009297D01*
G01X1336554Y1013595D02*
Y1015704D01*
X1336553Y1015705D01*
G01X1338403Y1010391D02*
Y1012500D01*
X1338404Y1012501D01*
G01X1345803Y1010391D02*
Y1012500D01*
X1345804Y1012501D01*
G01X1340254Y1007187D02*
Y1009296D01*
X1340253Y1009297D01*
G01X1343954Y1007187D02*
Y1009296D01*
X1343953Y1009297D01*
G01X1340254Y1000778D02*
Y1002887D01*
X1340253Y1002888D01*
G01X1343954Y1000778D02*
X1347653Y1002888D01*
G01X1331003Y1029617D02*
Y1031727D01*
G01X1332854Y1026413D02*
X1332853Y1026414D01*
Y1028523D01*
G01X1332854Y1020004D02*
X1332853Y1020005D01*
Y1022114D01*
G01X1331003Y1016800D02*
Y1018910D01*
G01X1338403Y1029617D02*
Y1031726D01*
X1338404Y1031727D01*
G01X1340254Y1026413D02*
Y1028522D01*
X1340253Y1028523D01*
G01X1345803Y1029617D02*
Y1031726D01*
X1345804Y1031727D01*
G01X1343954Y1026413D02*
Y1028522D01*
X1343953Y1028523D01*
G01X1331003Y1023208D02*
Y1025317D01*
X1331004Y1025318D01*
G01X1334703Y1023208D02*
X1334704Y1023209D01*
Y1025318D01*
G01X1340254Y1020004D02*
Y1022113D01*
X1340253Y1022114D01*
G01X1338403Y1016800D02*
X1338404Y1016801D01*
Y1018910D01*
G01X1343954Y1020004D02*
Y1022113D01*
X1343953Y1022114D01*
G01X1345803Y1016800D02*
Y1018909D01*
X1345804Y1018910D01*
G01X1332854Y1045639D02*
X1332853D01*
Y1047749D01*
G01X1332854Y1039230D02*
X1332853Y1039231D01*
Y1041340D01*
G01X1331003Y1036026D02*
Y1038136D01*
G01X1340254Y1039230D02*
X1340253Y1039231D01*
Y1041340D01*
G01X1338403Y1036026D02*
Y1038135D01*
X1338404Y1038136D01*
G01X1343954Y1039230D02*
X1343953Y1039231D01*
Y1041340D01*
G01X1345803Y1036026D02*
Y1038135D01*
X1345804Y1038136D01*
G01X1336554Y1032821D02*
Y1034930D01*
X1336553Y1034931D01*
G01X1331003Y1042434D02*
Y1044544D01*
G01X1340254Y1032821D02*
Y1034930D01*
X1340253Y1034931D01*
G01X1334703Y1042434D02*
Y1044543D01*
X1334704Y1044544D01*
G01X1343954Y1032821D02*
Y1034930D01*
X1343953Y1034931D01*
G01X1340254Y1045639D02*
X1340253D01*
Y1047749D01*
G01X1343954Y1045639D02*
X1343953D01*
Y1047749D01*
G01X1332854Y1058455D02*
X1332853Y1058456D01*
Y1060565D01*
G01X1331003Y1055251D02*
Y1057361D01*
G01X1334703Y1061660D02*
Y1063769D01*
X1334704Y1063770D01*
G01X1331003Y1061660D02*
Y1063770D01*
G01Y1048842D02*
Y1050952D01*
G01X1340254Y1058455D02*
X1340253Y1058456D01*
Y1060565D01*
G01X1338403Y1055251D02*
X1338404Y1055252D01*
Y1057361D01*
G01X1343954Y1058455D02*
X1343953Y1058456D01*
Y1060565D01*
G01X1345803Y1055251D02*
X1345804Y1055252D01*
Y1057361D01*
G01X1338403Y1048842D02*
X1338404Y1048843D01*
Y1050952D01*
G01X1345803Y1048842D02*
X1345804Y1048843D01*
Y1050952D01*
G01X1336554Y1052047D02*
X1336553Y1054157D01*
G01X1340254Y1052047D02*
X1340253Y1054157D01*
G01X1343954Y1052047D02*
X1343953Y1054157D01*
G01X1331003Y1068068D02*
Y1070178D01*
G01X1332854Y1064864D02*
Y1066973D01*
X1332853Y1066974D01*
G01X1343954Y1077681D02*
Y1079790D01*
X1343953Y1079791D01*
G01X1345803Y1074477D02*
G02X1345804Y1076587I2226050J0D01*
G01X1338403Y1068068D02*
X1338404Y1068069D01*
Y1070178D01*
G01X1340254Y1064864D02*
Y1066973D01*
X1340253Y1066974D01*
G01X1345803Y1068068D02*
X1345804Y1068069D01*
Y1070178D01*
G01X1343954Y1064864D02*
Y1066973D01*
X1343953Y1066974D01*
G01X1332854Y1077681D02*
Y1079790D01*
X1332853Y1079791D01*
G01X1331003Y1074477D02*
Y1076587D01*
G01X1340254Y1077681D02*
Y1079790D01*
X1340253Y1079791D01*
G01X1338403Y1074477D02*
G02X1338404Y1076587I2226050J0D01*
G01X1336554Y1071273D02*
Y1073382D01*
X1336553Y1073383D01*
G01X1340254Y1071273D02*
Y1073382D01*
X1340253Y1073383D01*
G01X1343954Y1071273D02*
Y1073382D01*
X1343953Y1073383D01*
G01X1331003Y1087294D02*
Y1089404D01*
G01X1332854Y1084090D02*
Y1086198D01*
G03X1332853Y1086200I-3J0D01*
G01X1331003Y1080885D02*
Y1082995D01*
G01X1334704D02*
X1334689D01*
G03X1334688Y1080885I2226050J-2110D01*
G01X1334703D01*
G01X1338403Y1093703D02*
Y1095812D01*
X1338404Y1095813D01*
G01X1345803Y1093703D02*
Y1095812D01*
X1345804Y1095813D01*
G01X1338403Y1087294D02*
Y1089403D01*
X1338404Y1089404D01*
G01X1340254Y1084090D02*
G03X1340253Y1086200I-2226050J0D01*
G01X1345803Y1087294D02*
Y1089403D01*
X1345804Y1089404D01*
G01X1343954Y1084090D02*
G03X1343953Y1086200I-2226050J0D01*
G01X1336554Y1090498D02*
Y1092607D01*
X1336553Y1092608D01*
G01X1343954Y1090498D02*
X1343953Y1090499D01*
Y1092608D01*
G01X1340254Y1090498D02*
Y1092607D01*
X1340253Y1092608D01*
G01X1340254Y1096907D02*
X1340253Y1099017D01*
G01X1343954Y1096907D02*
X1343953Y1099017D01*
G01X1350921Y901555D02*
X1350920Y901554D01*
Y899445D01*
G01X1358321Y901555D02*
X1358320Y901554D01*
Y899445D01*
G01X1347221Y895146D02*
X1347220Y895145D01*
Y893036D01*
G01X1358321Y895146D02*
X1358320Y895145D01*
Y893036D01*
G01X1350921Y895146D02*
X1350920Y895145D01*
Y893036D01*
G01X1362021Y895146D02*
X1362020Y895145D01*
Y893036D01*
G01X1349070Y898350D02*
X1349071Y898349D01*
Y896240D01*
G01X1356470Y898350D02*
Y896241D01*
X1356471Y896240D01*
G01X1352770Y898350D02*
X1352771Y898349D01*
Y896240D01*
G01X1360170Y898350D02*
Y896241D01*
X1360171Y896240D01*
G01X1352770Y904759D02*
X1352771Y904758D01*
Y902649D01*
G01X1356470Y904759D02*
X1356471Y904758D01*
Y902649D01*
G01X1347221Y907963D02*
X1347220Y907962D01*
Y905853D01*
G01X1350921Y914372D02*
X1350920Y914371D01*
Y912262D01*
G01X1352770Y911167D02*
X1352771Y911166D01*
Y909057D01*
G01X1358321Y914372D02*
X1358320Y914371D01*
Y912262D01*
G01X1356470Y911167D02*
X1356471Y911166D01*
Y909057D01*
G01X1349070Y917576D02*
X1349071Y917575D01*
Y915466D01*
G01X1362021Y907963D02*
X1362020Y907962D01*
Y905853D01*
G01X1356470Y917576D02*
X1356471Y917575D01*
Y915466D01*
G01X1352770Y917576D02*
X1352771Y917575D01*
Y915466D01*
G01X1360170Y917576D02*
X1360171Y917575D01*
Y915466D01*
G01X1347221Y927189D02*
Y925080D01*
X1347220Y925079D01*
G01X1350921Y933598D02*
X1350920Y933597D01*
Y931488D01*
G01X1352770Y930393D02*
X1352771Y930392D01*
Y928283D01*
G01X1358321Y933598D02*
X1358320Y933597D01*
Y931488D01*
G01X1356470Y930393D02*
X1356471Y930392D01*
Y928283D01*
G01X1352770Y923985D02*
X1352771Y923984D01*
Y921875D01*
G01X1350921Y920780D02*
X1350920Y920779D01*
Y918670D01*
G01X1356470Y923985D02*
X1356471Y923984D01*
Y921875D01*
G01X1358321Y920780D02*
X1358320Y920779D01*
Y918670D01*
G01X1362021Y927189D02*
Y925080D01*
X1362020Y925079D01*
G01X1356470Y943210D02*
X1356471Y943209D01*
Y941100D01*
G01X1358321Y940006D02*
X1358320Y940005D01*
Y937896D01*
G01X1352770Y949619D02*
X1352771Y949618D01*
Y947509D01*
G01X1356470Y949619D02*
X1356471Y949618D01*
Y947509D01*
G01X1352770Y943210D02*
X1352771Y943209D01*
Y941100D01*
G01X1350921Y940006D02*
X1350920Y940005D01*
Y937896D01*
G01X1349070Y936801D02*
X1349071Y936800D01*
Y934691D01*
G01X1356470Y936801D02*
X1356471Y936800D01*
Y934691D01*
G01X1352770Y936801D02*
X1352771Y936800D01*
Y934691D01*
G01X1347221Y946414D02*
Y944305D01*
X1347220Y944304D01*
G01X1360170Y936801D02*
X1360171Y936800D01*
Y934691D01*
G01X1362021Y946414D02*
X1362020Y946413D01*
Y944304D01*
G01X1352770Y962436D02*
Y960327D01*
X1352771Y960326D01*
G01X1350921Y959232D02*
X1350920Y959231D01*
Y957122D01*
G01X1356470Y962436D02*
X1356471Y962435D01*
Y960326D01*
G01X1358321Y959232D02*
X1358320Y959231D01*
Y957122D01*
G01X1350921Y952823D02*
X1350920Y952822D01*
Y950713D01*
G01X1358321Y952823D02*
X1358320Y952822D01*
Y950713D01*
G01X1349070Y956027D02*
X1349071Y953917D01*
G01X1356470Y956027D02*
X1356471Y953917D01*
G01X1352770Y956027D02*
X1352771Y953917D01*
G01X1360170Y956027D02*
X1360171Y953917D01*
G01X1347221Y965640D02*
X1347220Y965639D01*
Y963530D01*
G01X1362021Y965640D02*
X1362020Y965639D01*
Y963530D01*
G01X1352770Y981662D02*
X1352771Y981661D01*
Y979552D01*
G01X1356470Y981662D02*
X1356471Y981661D01*
Y979552D01*
G01X1350921Y978457D02*
X1350920Y978456D01*
Y976347D01*
G01X1358321Y978457D02*
X1358320Y978456D01*
Y976347D01*
G01X1349070Y975253D02*
Y973144D01*
X1349071Y973143D01*
G01X1350921Y972049D02*
X1350920Y972048D01*
Y969939D01*
G01X1358321Y972049D02*
X1358320Y972048D01*
Y969939D01*
G01X1356470Y968845D02*
X1356471Y968844D01*
Y966735D01*
G01X1352770Y968845D02*
X1352771Y968844D01*
Y966735D01*
G01X1360170Y975253D02*
Y973144D01*
X1360171Y973143D01*
G01X1347221Y984866D02*
X1347220Y984865D01*
Y982756D01*
G01X1353203Y997574D02*
Y999683D01*
X1353204Y999684D01*
G01X1356903Y997574D02*
Y999683D01*
X1356904Y999684D01*
G01X1362021Y984866D02*
Y982757D01*
X1362020Y982756D01*
G01X1349503Y1003983D02*
Y1006092D01*
X1349504Y1006093D01*
G01X1356903Y1003983D02*
Y1006092D01*
X1356904Y1006093D01*
G01X1353203Y1003983D02*
Y1006092D01*
X1353204Y1006093D01*
G01X1360603Y1003983D02*
Y1006092D01*
X1360604Y1006093D01*
G01X1347654Y1013595D02*
Y1015704D01*
X1347653Y1015705D01*
G01X1351354Y1000778D02*
Y1002887D01*
X1351353Y1002888D01*
G01X1358754Y1000778D02*
Y1002887D01*
X1358753Y1002888D01*
G01X1362454Y1013595D02*
Y1015704D01*
X1362453Y1015705D01*
G01X1353203Y1010391D02*
Y1012500D01*
X1353204Y1012501D01*
G01X1351354Y1007187D02*
Y1009296D01*
X1351353Y1009297D01*
G01X1356903Y1010391D02*
Y1012500D01*
X1356904Y1012501D01*
G01X1358754Y1007187D02*
Y1009296D01*
X1358753Y1009297D01*
G01X1353203Y1029617D02*
Y1031726D01*
X1353204Y1031727D01*
G01X1351354Y1026413D02*
Y1028522D01*
X1351353Y1028523D01*
G01X1356903Y1029617D02*
Y1031726D01*
X1356904Y1031727D01*
G01X1358754Y1026413D02*
Y1028522D01*
X1358753Y1028523D01*
G01X1351354Y1020004D02*
Y1022113D01*
X1351353Y1022114D01*
G01X1353203Y1016800D02*
Y1018909D01*
X1353204Y1018910D01*
G01X1358754Y1020004D02*
Y1022113D01*
X1358753Y1022114D01*
G01X1356903Y1016800D02*
Y1018909D01*
X1356904Y1018910D01*
G01X1353203Y1023208D02*
X1353204Y1025318D01*
G01X1360603Y1023208D02*
X1360604Y1025318D01*
G01X1349503Y1023208D02*
Y1025317D01*
X1349502Y1025318D01*
G01X1356903Y1023208D02*
Y1025317D01*
X1356902Y1025318D01*
G01X1347654Y1032821D02*
Y1034930D01*
X1347653Y1034931D01*
G01X1351354Y1045639D02*
X1351353D01*
Y1047749D01*
G01X1358754Y1045639D02*
X1358753D01*
Y1047749D01*
G01X1351354Y1039230D02*
X1351353Y1039231D01*
Y1041340D01*
G01X1353203Y1036026D02*
Y1038135D01*
X1353204Y1038136D01*
G01X1358754Y1039230D02*
X1358753Y1039231D01*
Y1041340D01*
G01X1356903Y1036026D02*
Y1038135D01*
X1356904Y1038136D01*
G01X1349503Y1042434D02*
X1349504Y1044544D01*
G01X1356903Y1042434D02*
X1356904Y1044544D01*
G01X1353203Y1042434D02*
X1353204Y1044544D01*
G01X1360603Y1042434D02*
X1360604Y1044544D01*
G01X1362454Y1032821D02*
Y1034930D01*
X1362453Y1034931D01*
G01X1351354Y1058455D02*
X1351353Y1058456D01*
Y1060565D01*
G01X1353203Y1055251D02*
X1353204Y1055252D01*
Y1057361D01*
G01X1358754Y1058455D02*
X1358753Y1058456D01*
Y1060565D01*
G01X1356903Y1055251D02*
X1356904Y1055252D01*
Y1057361D01*
G01X1353203Y1048842D02*
X1353204Y1048843D01*
Y1050952D01*
G01X1356903Y1048842D02*
X1356904Y1048843D01*
Y1050952D01*
G01X1349503Y1061660D02*
X1349504Y1063770D01*
G01X1360603Y1061660D02*
X1360604Y1063770D01*
G01X1347654Y1052047D02*
X1347653Y1054157D01*
G01X1353203Y1061660D02*
X1353204Y1063770D01*
G01X1356903Y1061660D02*
X1356904Y1063770D01*
G01X1362454Y1052047D02*
X1362453Y1052048D01*
Y1054157D01*
G01X1347654Y1071273D02*
Y1073382D01*
X1347653Y1073383D01*
G01X1356903Y1068068D02*
Y1070177D01*
X1356904Y1070178D01*
G01X1358754Y1064864D02*
G03X1358753Y1066974I-2226050J0D01*
G01X1353203Y1068068D02*
X1353204Y1068069D01*
Y1070178D01*
G01X1351354Y1064864D02*
G03X1351353Y1066974I-2226050J0D01*
G01X1351354Y1077681D02*
Y1079790D01*
X1351353Y1079791D01*
G01X1353203Y1074477D02*
G02X1353204Y1076587I2226050J0D01*
G01X1358754Y1077681D02*
Y1079790D01*
X1358753Y1079791D01*
G01X1356903Y1074477D02*
G02X1356904Y1076587I2226051J0D01*
G01X1362454Y1071273D02*
G03X1362453Y1073383I-2226050J0D01*
G01X1347654Y1090498D02*
X1347653Y1090499D01*
Y1092608D01*
G01X1353203Y1087294D02*
Y1089403D01*
X1353204Y1089404D01*
G01X1351354Y1084090D02*
G03X1351353Y1086200I-2226050J0D01*
G01X1356903Y1087294D02*
Y1089403D01*
X1356904Y1089404D01*
G01X1358754Y1084090D02*
G03X1358753Y1086200I-2226050J0D01*
G01X1349503Y1080885D02*
G02X1349504Y1082995I2226050J0D01*
G01X1362454Y1090498D02*
G03X1362453Y1092608I-2226050J0D01*
G01X1360603Y1080885D02*
G02X1360604Y1082995I2226051J0D01*
G01X1353203Y1080885D02*
G02X1353204Y1082995I2226050J0D01*
G01X1356903Y1080885D02*
G02X1356904Y1082995I2226051J0D01*
G01X1365721Y901555D02*
X1365720Y901554D01*
Y899445D01*
G01X1369421Y901555D02*
X1369420Y901554D01*
Y899445D01*
G01X1365721Y914372D02*
X1365720Y914371D01*
Y912262D01*
G01X1363870Y911167D02*
X1363871Y911166D01*
Y909057D01*
G01X1369421Y914372D02*
X1369420Y914371D01*
Y912262D01*
G01X1371270Y911167D02*
X1371271Y911166D01*
Y909057D01*
G01X1363870Y904759D02*
X1363871Y904758D01*
Y902649D01*
G01X1371270Y904759D02*
X1371271Y904758D01*
Y902649D01*
G01X1369421Y907963D02*
X1369420Y907962D01*
Y905853D01*
G01X1365721Y907963D02*
X1365720Y907962D01*
Y905853D01*
G01X1373121Y907963D02*
X1373120Y907962D01*
Y905853D01*
G01X1369421Y933598D02*
X1369420Y933597D01*
Y931488D01*
G01X1371270Y930393D02*
X1371271Y930392D01*
Y928283D01*
G01X1363870Y923985D02*
X1363871Y923984D01*
Y921875D01*
G01X1365721Y920780D02*
X1365720Y920779D01*
Y918670D01*
G01X1371270Y923985D02*
X1371271Y923984D01*
Y921875D01*
G01X1369421Y920780D02*
X1369420Y920779D01*
Y918670D01*
G01X1365721Y933598D02*
X1365720Y933597D01*
Y931488D01*
G01X1363870Y930393D02*
X1363871Y930392D01*
Y928283D01*
G01X1369421Y927189D02*
Y925080D01*
X1369420Y925079D01*
G01X1365721Y927189D02*
X1365720Y927188D01*
Y925079D01*
G01X1373121Y927189D02*
Y925080D01*
X1373120Y925079D01*
G01X1363870Y949619D02*
X1363871Y949618D01*
Y947509D01*
G01X1371270Y949619D02*
X1371271Y949618D01*
Y947509D01*
G01X1363870Y943210D02*
X1363871Y943209D01*
Y941100D01*
G01X1365721Y940006D02*
X1365720Y940005D01*
Y937896D01*
G01X1371270Y943210D02*
X1371271Y943209D01*
Y941100D01*
G01X1369421Y940006D02*
X1369420Y940005D01*
Y937896D01*
G01X1369421Y946414D02*
X1369420Y946413D01*
Y944304D01*
G01X1365721Y946414D02*
X1365720Y946413D01*
Y944304D01*
G01X1373121Y946414D02*
X1373120Y946413D01*
Y944304D01*
G01X1363870Y962436D02*
X1363871Y962435D01*
Y960326D01*
G01X1365721Y959232D02*
X1365720Y959231D01*
Y957122D01*
G01X1371270Y962436D02*
X1371271Y962435D01*
Y960326D01*
G01X1369421Y959232D02*
X1369420Y959231D01*
Y957122D01*
G01X1365721Y952823D02*
X1365720Y952822D01*
Y950713D01*
G01X1369421Y952823D02*
X1369420Y952822D01*
Y950713D01*
G01X1373121Y965640D02*
X1373120Y965639D01*
Y963530D01*
G01X1369421Y965640D02*
X1369420Y965639D01*
Y963530D01*
G01X1365721Y965640D02*
X1365720Y965639D01*
Y963530D01*
G01X1374970Y975253D02*
X1374966Y975249D01*
Y973148D01*
X1374971Y973143D01*
G01X1376821Y978457D02*
Y976348D01*
X1376820Y976347D01*
G01X1378670Y981662D02*
X1378671Y981661D01*
Y979552D01*
G01X1378670Y975253D02*
X1378666Y975249D01*
Y973148D01*
X1378671Y973143D01*
G01X1369421Y978457D02*
X1369420Y978456D01*
Y976347D01*
G01X1371270Y981662D02*
X1371271Y981661D01*
Y979552D01*
G01X1363870Y981662D02*
X1363871Y981661D01*
Y979552D01*
G01X1365721Y976347D02*
Y978457D01*
G01Y972049D02*
X1365720Y972048D01*
Y969939D01*
G01X1363870Y968845D02*
X1363871Y968844D01*
Y966735D01*
G01X1369421Y972049D02*
X1369420Y972048D01*
Y969939D01*
G01X1371270Y968845D02*
X1371271Y968844D01*
Y966735D01*
G01X1364303Y997574D02*
Y999683D01*
X1364304Y999684D01*
G01X1371703Y997574D02*
Y999683D01*
X1371704Y999684D01*
G01X1375403Y997574D02*
Y999683D01*
X1375404Y999684D01*
G01X1379103Y997574D02*
Y999683D01*
X1379104Y999684D01*
G01X1369421Y984866D02*
X1369420Y984865D01*
Y982756D01*
G01X1365721Y984866D02*
Y982757D01*
X1365720Y982756D01*
G01X1373121Y984866D02*
X1373120Y984865D01*
Y982756D01*
G01X1375403Y1003983D02*
Y1006092D01*
X1375404Y1006093D01*
G01X1379103Y1003983D02*
X1379104Y1003984D01*
Y1006093D01*
G01X1366154Y1000778D02*
Y1002887D01*
X1366153Y1002888D01*
G01X1369854Y1000778D02*
Y1002887D01*
X1369853Y1002888D01*
G01X1373554Y1013595D02*
Y1015704D01*
X1373553Y1015705D01*
G01X1364303Y1010391D02*
Y1012500D01*
X1364304Y1012501D01*
G01X1371703Y1010391D02*
Y1012500D01*
X1371704Y1012501D01*
G01X1366154Y1007187D02*
Y1009296D01*
X1366153Y1009297D01*
G01X1369854Y1007187D02*
Y1009296D01*
X1369853Y1009297D01*
G01X1364303Y1029617D02*
Y1031726D01*
X1364304Y1031727D01*
G01X1366154Y1026413D02*
Y1028522D01*
X1366153Y1028523D01*
G01X1371703Y1029617D02*
Y1031726D01*
X1371704Y1031727D01*
G01X1369854Y1026413D02*
Y1028522D01*
X1369853Y1028523D01*
G01X1366154Y1020004D02*
Y1022113D01*
X1366153Y1022114D01*
G01X1364303Y1016800D02*
Y1018909D01*
X1364304Y1018910D01*
G01X1369854Y1020004D02*
Y1022113D01*
X1369853Y1022114D01*
G01X1371703Y1016800D02*
Y1018909D01*
X1371704Y1018910D01*
G01X1366154Y1039230D02*
X1366153Y1039231D01*
Y1041340D01*
G01X1364303Y1036026D02*
Y1038135D01*
X1364304Y1038136D01*
G01X1369854Y1039230D02*
X1369853Y1039231D01*
Y1041340D01*
G01X1371703Y1036026D02*
Y1038135D01*
X1371704Y1038136D01*
G01X1366154Y1045639D02*
X1366153D01*
Y1047749D01*
G01X1369854Y1045639D02*
X1369853D01*
Y1047749D01*
G01X1369854Y1032821D02*
Y1034930D01*
X1369853Y1034931D01*
G01X1366154Y1032821D02*
Y1034930D01*
X1366153Y1034931D01*
G01X1373554Y1032821D02*
Y1034930D01*
X1373553Y1034931D01*
G01X1366154Y1058455D02*
X1366153Y1058456D01*
Y1060565D01*
G01X1364303Y1055251D02*
X1364304Y1055252D01*
Y1057361D01*
G01X1369854Y1058455D02*
X1369853Y1058456D01*
Y1060565D01*
G01X1371703Y1055251D02*
X1371704Y1055252D01*
Y1057361D01*
G01X1364303Y1048842D02*
G02X1364304Y1050952I2226050J0D01*
G01X1371703Y1048842D02*
G02X1371704Y1050952I2226050J0D01*
G01X1369854Y1052047D02*
X1369853Y1052048D01*
Y1054157D01*
G01X1366154Y1052047D02*
X1366153Y1052048D01*
Y1054157D01*
G01X1373554Y1052047D02*
X1373553Y1052048D01*
Y1054157D01*
G01X1366154Y1077681D02*
Y1079790D01*
X1366153Y1079791D01*
G01X1364303Y1074477D02*
G02X1364304Y1076587I2226050J0D01*
G01X1369854Y1077681D02*
Y1079790D01*
X1369853Y1079791D01*
G01X1371703Y1074477D02*
G02X1371704Y1076587I2226050J0D01*
G01X1364303Y1068068D02*
X1364304Y1068069D01*
Y1070178D01*
G01X1366154Y1064864D02*
G03X1366153Y1066974I-2226050J0D01*
G01X1371703Y1068068D02*
X1371704Y1068069D01*
Y1070178D01*
G01X1369854Y1064864D02*
G03X1369853Y1066974I-2226050J0D01*
G01X1369854Y1071273D02*
G03X1369853Y1073383I-2226050J0D01*
G01X1366154Y1071273D02*
G03X1366153Y1073383I-2226050J0D01*
G01X1373554Y1071273D02*
G03X1373553Y1073383I-2226050J0D01*
G01X1371703Y1093703D02*
Y1095812D01*
X1371704Y1095813D01*
G01X1364303Y1087294D02*
Y1089403D01*
X1364304Y1089404D01*
G01X1366154Y1084090D02*
G03X1366153Y1086200I-2226050J0D01*
G01X1371703Y1087294D02*
Y1089403D01*
X1371704Y1089404D01*
G01X1369854Y1084090D02*
G03X1369853Y1086200I-2226050J0D01*
G01X1364303Y1093703D02*
Y1095812D01*
X1364304Y1095813D01*
G01X1369854Y1090498D02*
G03X1369853Y1092608I-2226050J0D01*
G01X1366154Y1090498D02*
G03X1366153Y1092608I-2226050J0D01*
G01X1373554Y1090498D02*
G03X1373553Y1092608I-2226050J0D01*
G01X1369854Y1096907D02*
Y1099016D01*
X1369853Y1099017D01*
G01X1366154Y1096907D02*
Y1099016D01*
X1366153Y1099017D01*
G01X1458221Y895146D02*
X1458220Y895145D01*
Y893036D01*
G01X1460070Y898350D02*
X1460071Y898349D01*
Y896240D01*
G01X1460070Y917576D02*
Y915467D01*
X1460071Y915466D01*
G01X1460070Y936801D02*
Y934692D01*
X1460071Y934691D01*
G01X1460070Y956027D02*
X1460071Y956026D01*
Y953917D01*
G01X1460070Y975253D02*
X1460071Y975252D01*
Y973143D01*
G01X1456803Y997574D02*
Y999683D01*
X1456804Y999684D01*
G01X1458220Y982756D02*
Y984865D01*
X1458221Y984866D01*
G01X1454954Y1000778D02*
Y1002887D01*
X1454953Y1002888D01*
G01X1454954Y1007187D02*
Y1009295D01*
G03X1454953Y1009297I-3J0D01*
G01X1456803Y1010391D02*
Y1012500D01*
X1456804Y1012501D01*
G01X1460503Y1003983D02*
Y1006092D01*
X1460504Y1006093D01*
G01X1460503Y1023208D02*
Y1025317D01*
X1460504Y1025318D01*
G01X1460503Y1042434D02*
Y1044543D01*
X1460504Y1044544D01*
G01X1460503Y1061660D02*
X1460504Y1063653D01*
Y1063770D01*
G01X1460503Y1080885D02*
X1460504Y1080886D01*
Y1082995D01*
G01X1476721Y901555D02*
X1476720Y901554D01*
Y899445D01*
G01X1461921Y901555D02*
Y899446D01*
X1461920Y899445D01*
G01X1469321Y901555D02*
X1469320Y901554D01*
Y899445D01*
G01X1469321Y895146D02*
X1469320Y895145D01*
Y893036D01*
G01X1473021Y895146D02*
X1473020Y895145D01*
Y893036D01*
G01X1461921Y895146D02*
X1461920Y895145D01*
Y893036D01*
G01X1467470Y898350D02*
X1467471Y898349D01*
Y896240D01*
G01X1463770Y898350D02*
X1463771Y898349D01*
Y896240D01*
G01X1471170Y898350D02*
X1471171Y898349D01*
Y896240D01*
G01X1461921Y914372D02*
X1461920Y914371D01*
Y912262D01*
G01X1463770Y911167D02*
Y909058D01*
X1463771Y909057D01*
G01X1469321Y914372D02*
X1469320Y914371D01*
Y912262D01*
G01X1467470Y911167D02*
Y909058D01*
X1467471Y909057D01*
G01X1476721Y914372D02*
X1476720Y914371D01*
Y912262D01*
G01X1474870Y911167D02*
Y909058D01*
X1474871Y909057D01*
G01X1474870Y904759D02*
X1474871Y904758D01*
Y902649D01*
G01X1463770Y904759D02*
Y902650D01*
X1463771Y902649D01*
G01X1467470Y904759D02*
X1467471Y904758D01*
Y902649D01*
G01X1463770Y917576D02*
Y915467D01*
X1463771Y915466D01*
G01X1476721Y907963D02*
X1476720Y907962D01*
Y905853D01*
G01X1471170Y917576D02*
Y915467D01*
X1471171Y915466D01*
G01X1473021Y907963D02*
X1473020Y907962D01*
Y905853D01*
G01X1467470Y917576D02*
Y915467D01*
X1467471Y915466D01*
G01X1476721Y933598D02*
X1476720Y933597D01*
Y931488D01*
G01X1474870Y923985D02*
X1474871Y923984D01*
Y921875D01*
G01X1476721Y920780D02*
X1476720Y920779D01*
Y918670D01*
G01X1474870Y930393D02*
X1474871Y930392D01*
Y928283D01*
G01X1473021Y927189D02*
X1473020Y927188D01*
Y925079D01*
G01X1476721Y927189D02*
X1476720Y927188D01*
Y925079D01*
G01X1467470Y923985D02*
X1467471Y923984D01*
Y921875D01*
G01X1469321Y920780D02*
X1469320Y920779D01*
Y918670D01*
G01X1461921Y933598D02*
X1461920Y933597D01*
Y931488D01*
G01X1467470Y930393D02*
X1467471Y930392D01*
Y928283D01*
G01X1469321Y933598D02*
X1469320Y933597D01*
Y931488D01*
G01X1463770Y930393D02*
X1463771Y930392D01*
Y928283D01*
G01X1463770Y923985D02*
X1463771Y923984D01*
Y921875D01*
G01X1461921Y920780D02*
X1461920Y920779D01*
Y918670D01*
G01X1474870Y949619D02*
X1474871Y949618D01*
Y947509D01*
G01X1474870Y943210D02*
X1474871Y943209D01*
Y941100D01*
G01X1476721Y940006D02*
X1476720Y940005D01*
Y937896D01*
G01X1473021Y946414D02*
X1473020Y946413D01*
Y944304D01*
G01X1476721Y946414D02*
X1476720Y946413D01*
Y944304D01*
G01X1463770Y949619D02*
X1463771Y949618D01*
Y947509D01*
G01X1467470Y949619D02*
X1467471Y949618D01*
Y947509D01*
G01X1463770Y943210D02*
X1463771Y943209D01*
Y941100D01*
G01X1461921Y940006D02*
X1461920Y940005D01*
Y937896D01*
G01X1467470Y943210D02*
X1467471Y943209D01*
Y941100D01*
G01X1469321Y940006D02*
X1469320Y940005D01*
Y937896D01*
G01X1463770Y936801D02*
Y934692D01*
X1463771Y934691D01*
G01X1471170Y936801D02*
Y934692D01*
X1471171Y934691D01*
G01X1467470Y936801D02*
Y934692D01*
X1467471Y934691D01*
G01X1476721Y952823D02*
X1476720Y952822D01*
Y950713D01*
G01X1473021Y965640D02*
X1473020Y965639D01*
Y963530D01*
G01X1461921Y952823D02*
X1461920Y952822D01*
Y950713D01*
G01X1469321Y952823D02*
X1469320Y952822D01*
Y950713D01*
G01X1467470Y962436D02*
X1467471Y962435D01*
Y960326D01*
G01X1469321Y959232D02*
X1469320Y959231D01*
Y957122D01*
G01X1463770Y962436D02*
X1463771Y962435D01*
Y960326D01*
G01X1461921Y959232D02*
X1461920Y959231D01*
Y957122D01*
G01X1476721Y959232D02*
X1476720Y959231D01*
Y957122D01*
G01X1474870Y962436D02*
X1474871Y962435D01*
Y960326D01*
G01X1471170Y956027D02*
X1471171Y956026D01*
Y953917D01*
G01X1463770Y956027D02*
X1463771Y956026D01*
Y953917D01*
G01X1467470Y956027D02*
X1467471Y956026D01*
Y953917D01*
G01X1463770Y981662D02*
X1463771Y981661D01*
Y979552D01*
G01X1461921Y978457D02*
X1461920Y978456D01*
Y976347D01*
G01X1467470Y981662D02*
X1467471Y981661D01*
Y979552D01*
G01X1469321Y978457D02*
X1469320Y978456D01*
Y976347D01*
G01X1474870Y981662D02*
X1474871Y981661D01*
Y979552D01*
G01X1476721Y978457D02*
X1476720Y978456D01*
Y976347D01*
G01X1471170Y975253D02*
X1471171Y975252D01*
Y973143D01*
G01X1463770Y975253D02*
X1463771Y975252D01*
Y973143D01*
G01X1467470Y975253D02*
X1467471Y975252D01*
Y973143D01*
G01X1461921Y972049D02*
X1461920Y972048D01*
Y969939D01*
G01X1463770Y968845D02*
X1463771Y968844D01*
Y966735D01*
G01X1467470Y968845D02*
X1467471Y968844D01*
Y966735D01*
G01X1469321Y972049D02*
X1469320Y972048D01*
Y969939D01*
G01X1476721Y972049D02*
X1476720Y972048D01*
Y969939D01*
G01X1474870Y968845D02*
X1474871Y968844D01*
Y966735D01*
G01X1475303Y997574D02*
Y999683D01*
X1475304Y999684D01*
G01X1476721Y984866D02*
X1476720Y984865D01*
Y982756D01*
G01X1473021Y984866D02*
X1473020Y984865D01*
Y982756D01*
G01X1464203Y997574D02*
Y999683D01*
X1464204Y999684D01*
G01X1467903Y997574D02*
Y999683D01*
X1467904Y999684D01*
G01X1477154Y1000778D02*
X1477153Y1000779D01*
Y1002888D01*
G01X1473454Y1013595D02*
X1473453Y1015705D01*
G01X1475303Y1010391D02*
Y1012500D01*
X1475304Y1012501D01*
G01X1477154Y1007187D02*
X1477153Y1007188D01*
Y1009297D01*
G01X1471603Y1003983D02*
X1471604Y1003984D01*
Y1006093D01*
G01X1462354Y1000778D02*
X1462353Y1000779D01*
Y1002888D01*
G01X1469754Y1000778D02*
Y1002887D01*
X1469753Y1002888D01*
G01X1467903Y1010391D02*
Y1012501D01*
G01X1469754Y1007187D02*
X1469753Y1007188D01*
Y1009297D01*
G01X1464203Y1010391D02*
Y1012500D01*
X1464204Y1012501D01*
G01X1462354Y1007187D02*
Y1009296D01*
X1462353Y1009297D01*
G01X1475303Y1029617D02*
X1475304Y1029618D01*
Y1031727D01*
G01X1477154Y1026413D02*
Y1028521D01*
X1477153Y1028522D01*
Y1028523D01*
G01X1475303Y1016800D02*
X1475304Y1016801D01*
Y1018910D01*
G01X1464203Y1029617D02*
X1464204Y1029618D01*
Y1031727D01*
G01X1462354Y1026413D02*
Y1028521D01*
X1462353Y1028522D01*
Y1028523D01*
G01X1467903Y1029617D02*
X1467904Y1029618D01*
Y1031727D01*
G01X1469754Y1026413D02*
Y1028521D01*
X1469753Y1028522D01*
Y1028523D01*
G01X1462354Y1020004D02*
Y1020053D01*
X1462353Y1022114D01*
G01X1464203Y1016800D02*
X1464204Y1016801D01*
Y1018910D01*
G01X1469754Y1020004D02*
Y1020053D01*
X1469753Y1022114D01*
G01X1467903Y1016800D02*
X1467904Y1016801D01*
Y1018910D01*
G01X1464203Y1023208D02*
Y1025317D01*
X1464204Y1025318D01*
G01X1471603Y1023208D02*
Y1025317D01*
X1471604Y1025318D01*
G01X1467903Y1023208D02*
Y1025317D01*
X1467904Y1025318D01*
G01X1477154Y1039230D02*
Y1041339D01*
X1477153Y1041340D01*
G01X1475303Y1036026D02*
Y1038135D01*
X1475304Y1038136D01*
G01X1477154Y1032821D02*
Y1034930D01*
X1477153Y1034931D01*
G01X1473454Y1032821D02*
Y1034930D01*
X1473453Y1034931D01*
G01X1462354Y1045639D02*
Y1047748D01*
X1462353Y1047749D01*
G01X1469754Y1045639D02*
Y1047748D01*
X1469753Y1047749D01*
G01X1462354Y1039230D02*
Y1041339D01*
X1462353Y1041340D01*
G01X1464203Y1036026D02*
Y1038135D01*
X1464204Y1038136D01*
G01X1469754Y1039230D02*
Y1041339D01*
X1469753Y1041340D01*
G01X1467903Y1036026D02*
Y1038135D01*
X1467904Y1038136D01*
G01X1464203Y1042434D02*
Y1044543D01*
X1464204Y1044544D01*
G01X1471603Y1042434D02*
Y1044543D01*
X1471604Y1044544D01*
G01X1467903Y1042434D02*
Y1044543D01*
X1467904Y1044544D01*
G01X1477154Y1058455D02*
Y1060564D01*
X1477153Y1060565D01*
G01X1475303Y1055251D02*
Y1057360D01*
X1475304Y1057361D01*
G01X1475303Y1048842D02*
Y1050951D01*
X1475304Y1050952D01*
G01X1477154Y1045639D02*
Y1047748D01*
X1477153Y1047749D01*
G01X1477154Y1052047D02*
X1477153Y1052048D01*
Y1054157D01*
G01X1473454Y1052047D02*
X1473453Y1052048D01*
Y1054157D01*
G01X1462354Y1058455D02*
Y1060564D01*
X1462353Y1060565D01*
G01X1464203Y1055251D02*
Y1057360D01*
X1464204Y1057361D01*
G01X1469754Y1058455D02*
Y1060564D01*
X1469753Y1060565D01*
G01X1467903Y1055251D02*
Y1057360D01*
X1467904Y1057361D01*
G01X1464203Y1048842D02*
Y1050951D01*
X1464204Y1050952D01*
G01X1467903Y1048842D02*
Y1050951D01*
X1467904Y1050952D01*
G01X1464203Y1061660D02*
X1464204Y1063653D01*
Y1063770D01*
G01X1471603Y1061660D02*
X1471604Y1063653D01*
Y1063770D01*
G01X1467903Y1061660D02*
X1467904Y1063653D01*
Y1063770D01*
G01X1475303Y1068068D02*
X1475304Y1070178D01*
G01X1477154Y1064864D02*
Y1066973D01*
X1477153Y1066974D01*
G01X1475303Y1074477D02*
Y1076586D01*
X1475304Y1076587D01*
G01X1473454Y1071273D02*
X1473453Y1073383D01*
G01X1462354Y1077681D02*
Y1079790D01*
X1462353Y1079791D01*
G01X1464203Y1074477D02*
Y1076586D01*
X1464204Y1076587D01*
G01X1469754Y1077681D02*
Y1079790D01*
X1469753Y1079791D01*
G01X1467903Y1074477D02*
Y1076586D01*
X1467904Y1076587D01*
G01X1464203Y1068068D02*
X1464204Y1070178D01*
G01X1462354Y1064864D02*
Y1066973D01*
X1462353Y1066974D01*
G01X1467903Y1068068D02*
X1467904Y1070178D01*
G01X1469754Y1064864D02*
Y1066973D01*
X1469753Y1066974D01*
G01X1477154Y1077681D02*
Y1079790D01*
X1477153Y1079791D01*
G01X1467903Y1087294D02*
X1467904Y1089404D01*
G01X1469754Y1084090D02*
Y1086199D01*
X1469753Y1086200D01*
G01X1475303Y1087294D02*
X1475304Y1089404D01*
G01X1477154Y1084090D02*
Y1086199D01*
X1477153Y1086200D01*
G01X1464203Y1087294D02*
X1464204Y1089404D01*
G01X1462354Y1084090D02*
Y1086199D01*
X1462353Y1086200D01*
G01X1473454Y1090498D02*
Y1092607D01*
X1473453Y1092608D01*
G01X1471603Y1080885D02*
X1471604Y1080886D01*
Y1082995D01*
G01X1477154Y1090498D02*
Y1092607D01*
X1477153Y1092608D01*
G01X1464203Y1080885D02*
X1464204Y1080886D01*
Y1082995D01*
G01X1467903Y1080885D02*
X1467904Y1080886D01*
Y1082995D01*
G01X1487821Y901555D02*
X1487820Y901554D01*
Y899445D01*
G01X1487821Y895146D02*
X1487820Y895145D01*
Y893036D01*
G01X1484121Y895146D02*
X1484120Y895145D01*
Y893036D01*
G01X1485970Y898350D02*
X1485971Y898349D01*
Y896240D01*
G01X1493370Y898350D02*
X1493371Y898349D01*
Y896240D01*
G01X1489670Y898350D02*
X1489671Y898349D01*
Y896240D01*
G01X1480421Y901555D02*
X1480420Y901554D01*
Y899445D01*
G01X1489670Y904759D02*
X1489671Y904758D01*
Y902649D01*
G01X1493370Y904759D02*
X1493371Y904758D01*
Y902649D01*
G01X1487821Y914372D02*
X1487820Y914371D01*
Y912262D01*
G01X1489670Y911167D02*
Y909058D01*
X1489671Y909057D01*
G01X1493370Y911167D02*
Y909058D01*
X1493371Y909057D01*
G01X1489670Y917576D02*
Y915467D01*
X1489671Y915466D01*
G01X1485970Y917576D02*
Y915467D01*
X1485971Y915466D01*
G01X1493370Y917576D02*
Y915467D01*
X1493371Y915466D01*
G01X1480421Y914372D02*
X1480420Y914371D01*
Y912262D01*
G01X1482270Y911167D02*
Y909058D01*
X1482271Y909057D01*
G01X1482270Y904759D02*
X1482271Y904758D01*
Y902649D01*
G01X1484121Y907963D02*
X1484120Y907962D01*
Y905853D01*
G01X1480421Y907963D02*
X1480420Y907962D01*
Y905853D01*
G01X1487821Y933598D02*
X1487820Y933597D01*
Y931488D01*
G01X1489670Y930393D02*
X1489671Y930392D01*
Y928283D01*
G01X1493370Y930393D02*
X1493371Y930392D01*
Y928283D01*
G01X1482270Y930393D02*
X1482271Y930392D01*
Y928283D01*
G01X1482270Y923985D02*
X1482271Y923984D01*
Y921875D01*
G01X1480421Y920780D02*
X1480420Y920779D01*
Y918670D01*
G01X1489670Y923985D02*
X1489671Y923984D01*
Y921875D01*
G01X1487821Y920780D02*
X1487820Y920779D01*
Y918670D01*
G01X1493370Y923985D02*
X1493371Y923984D01*
Y921875D01*
G01X1480421Y933598D02*
X1480420Y933597D01*
Y931488D01*
G01X1480421Y927189D02*
X1480420Y927188D01*
Y925079D01*
G01X1484121Y927189D02*
X1484120Y927188D01*
Y925079D01*
G01X1489670Y943210D02*
X1489671Y943209D01*
Y941100D01*
G01X1487821Y940006D02*
X1487820Y940005D01*
Y937896D01*
G01X1493370Y943210D02*
X1493371Y943209D01*
Y941100D01*
G01X1489670Y936801D02*
X1489671D01*
Y934691D01*
G01X1485970Y936801D02*
X1485971D01*
Y934691D01*
G01X1489670Y949619D02*
X1489671Y949618D01*
Y947509D01*
G01X1482270Y949619D02*
X1482271Y949618D01*
Y947509D01*
G01X1482270Y943210D02*
X1482271Y943209D01*
Y941100D01*
G01X1480421Y940006D02*
X1480420Y940005D01*
Y937896D01*
G01X1484121Y946414D02*
X1484120Y946413D01*
Y944304D01*
G01X1480421Y946414D02*
X1480420Y946413D01*
Y944304D01*
G01X1487821Y952823D02*
X1487820Y952822D01*
Y950713D01*
G01X1493370Y949619D02*
X1493371Y949618D01*
Y947509D01*
G01X1489670Y962436D02*
X1489671Y962435D01*
Y960326D01*
G01X1487821Y959232D02*
X1487820Y959231D01*
Y957122D01*
G01X1493370Y962436D02*
X1493371Y962435D01*
Y960326D01*
G01X1480421Y952823D02*
X1480420Y952822D01*
Y950713D01*
G01X1489670Y956027D02*
X1489671Y956026D01*
Y953917D01*
G01X1493370Y956027D02*
X1493371Y956026D01*
Y953917D01*
G01X1485970Y956027D02*
X1485971Y956026D01*
Y953917D01*
G01X1480421Y959232D02*
X1480420Y959231D01*
Y957122D01*
G01X1482270Y962436D02*
X1482271Y962435D01*
Y960326D01*
G01X1484121Y965640D02*
X1484120Y965639D01*
Y963530D01*
G01X1480421Y978457D02*
X1480420Y978456D01*
Y976347D01*
G01X1482270Y981662D02*
Y979553D01*
X1482271Y979552D01*
G01X1489670Y981662D02*
X1489671Y981661D01*
Y979552D01*
G01X1493370Y981662D02*
X1493371Y981661D01*
Y979552D01*
G01X1487821Y978457D02*
Y976348D01*
X1487820Y976347D01*
G01X1485970Y975253D02*
X1485971Y975252D01*
Y973143D01*
G01X1493370Y968845D02*
X1493371Y968844D01*
Y966735D01*
G01X1487821Y972049D02*
X1487820Y972048D01*
Y969939D01*
G01X1489670Y968845D02*
X1489671Y968844D01*
Y966735D01*
G01X1480421Y972049D02*
X1480420Y972048D01*
Y969939D01*
G01X1482270Y968845D02*
X1482271Y968844D01*
Y966735D01*
G01X1482703Y997574D02*
Y999684D01*
G01X1484121Y984866D02*
X1484120Y984865D01*
Y982756D01*
G01X1480421Y984866D02*
X1480420Y984865D01*
Y982756D01*
G01X1490103Y997574D02*
X1490104Y997575D01*
Y999684D01*
G01X1490103Y1003983D02*
Y1006092D01*
X1490104Y1006093D01*
G01X1486403Y1003983D02*
Y1006092D01*
X1486404Y1006093D01*
G01X1480854Y1000778D02*
Y1002887D01*
X1480853Y1002888D01*
G01X1490103Y1010391D02*
Y1012500D01*
X1490104Y1012501D01*
G01X1488254Y1007187D02*
X1488253Y1007188D01*
Y1009297D01*
G01X1484554Y1013595D02*
X1484553Y1015705D01*
G01X1482703Y1010391D02*
Y1012500D01*
X1482704Y1012501D01*
G01X1480854Y1007187D02*
Y1009296D01*
X1480853Y1009297D01*
G01X1488254Y1000778D02*
Y1002887D01*
X1488253Y1002888D01*
G01X1490103Y1029617D02*
Y1031726D01*
X1490104Y1031727D01*
G01X1488254Y1026413D02*
Y1028521D01*
X1488253Y1028522D01*
Y1028523D01*
G01X1488254Y1020004D02*
Y1020053D01*
X1488253Y1022114D01*
G01X1490103Y1016800D02*
X1490104Y1016801D01*
Y1018910D01*
G01X1490103Y1023208D02*
Y1025317D01*
X1490104Y1025318D01*
G01X1486403Y1023208D02*
Y1025317D01*
X1486404Y1025318D01*
G01X1482703Y1029617D02*
X1482704Y1029618D01*
Y1031727D01*
G01X1480854Y1026413D02*
Y1028521D01*
X1480853Y1028522D01*
Y1028523D01*
G01X1480854Y1020004D02*
Y1020053D01*
X1480853Y1022114D01*
G01X1482703Y1016800D02*
X1482704Y1016801D01*
Y1018910D01*
G01X1477154Y1020004D02*
Y1020053D01*
X1477153Y1022114D01*
G01X1480854Y1039230D02*
Y1041339D01*
X1480853Y1041340D01*
G01X1482703Y1036026D02*
Y1038135D01*
X1482704Y1038136D01*
G01X1488254Y1045639D02*
Y1047748D01*
X1488253Y1047749D01*
G01X1488254Y1039230D02*
Y1041339D01*
X1488253Y1041340D01*
G01X1490103Y1036026D02*
Y1038135D01*
X1490104Y1038136D01*
G01X1480854Y1045639D02*
Y1047748D01*
X1480853Y1047749D01*
G01X1486403Y1042434D02*
Y1044543D01*
X1486404Y1044544D01*
G01X1484554Y1032821D02*
Y1034930D01*
X1484553Y1034931D01*
G01X1490103Y1042434D02*
Y1044543D01*
X1490104Y1044544D01*
G01X1480854Y1032821D02*
Y1034930D01*
X1480853Y1034931D01*
G01X1488254Y1058455D02*
Y1060564D01*
X1488253Y1060565D01*
G01X1490103Y1055251D02*
Y1057360D01*
X1490104Y1057361D01*
G01X1486403Y1061660D02*
X1486404Y1063653D01*
Y1063770D01*
G01X1490103Y1061660D02*
X1490104Y1063653D01*
Y1063770D01*
G01X1490103Y1048842D02*
Y1050951D01*
X1490104Y1050952D01*
G01X1480854Y1058455D02*
Y1060564D01*
X1480853Y1060565D01*
G01X1482703Y1055251D02*
Y1057360D01*
X1482704Y1057361D01*
G01X1482703Y1048842D02*
Y1050951D01*
X1482704Y1050952D01*
G01X1484554Y1052047D02*
X1484553Y1052048D01*
Y1054157D01*
G01X1480854Y1052047D02*
X1480853Y1052048D01*
Y1054157D01*
G01X1490103Y1068068D02*
X1490104Y1070178D01*
G01X1488254Y1064864D02*
Y1066973D01*
X1488253Y1066974D01*
G01X1480854Y1077681D02*
Y1079790D01*
X1480853Y1079791D01*
G01X1482703Y1074477D02*
Y1076586D01*
X1482704Y1076587D01*
G01X1482703Y1068068D02*
X1482704Y1070178D01*
G01X1480854Y1064864D02*
Y1066973D01*
X1480853Y1066974D01*
G01X1488254Y1077681D02*
Y1079790D01*
X1488253Y1079791D01*
G01X1490103Y1074477D02*
Y1076586D01*
X1490104Y1076587D01*
G01X1484554Y1071273D02*
X1484553Y1073383D01*
G01X1477154Y1071273D02*
X1477153Y1073383D01*
G01X1480854Y1071273D02*
X1480853Y1073383D01*
G01X1490103Y1087294D02*
X1490104Y1089404D01*
G01X1488254Y1084090D02*
Y1086199D01*
X1488253Y1086200D01*
G01X1490103Y1080885D02*
X1490104Y1080886D01*
Y1082995D01*
G01X1486403Y1080885D02*
X1486404Y1080886D01*
Y1082995D01*
G01X1486403Y1093703D02*
Y1095812D01*
X1486404Y1095813D01*
G01X1482703Y1093703D02*
Y1095813D01*
G01Y1087294D02*
X1482704Y1089404D01*
G01X1480854Y1084090D02*
Y1086199D01*
X1480853Y1086200D01*
G01X1484554Y1090498D02*
Y1092607D01*
X1484553Y1092608D01*
G01X1480854Y1090498D02*
Y1092607D01*
X1480853Y1092608D01*
G01X1491954Y1096907D02*
Y1099016D01*
X1491953Y1099017D01*
G01X1508170Y866307D02*
X1508171Y866306D01*
Y864197D01*
G01X1502621Y899445D02*
Y901555D01*
G01X1506321D02*
X1506320Y901554D01*
Y899445D01*
G01X1495221Y901555D02*
X1495220Y901554D01*
Y899445D01*
G01X1495221Y895146D02*
X1495220Y895145D01*
Y893036D01*
G01X1498921Y895146D02*
X1498920Y895145D01*
Y893036D01*
G01X1497070Y898350D02*
X1497071Y898349D01*
Y896240D01*
G01X1506321Y914372D02*
Y912262D01*
G01X1508170Y911167D02*
Y909058D01*
X1508171Y909057D01*
G01X1500770Y904759D02*
X1500771Y904758D01*
Y902649D01*
G01X1508170Y904759D02*
X1508171Y904758D01*
Y902649D01*
G01X1502621Y914372D02*
Y912262D01*
G01X1500770Y911167D02*
Y909058D01*
X1500771Y909057D01*
G01X1502621Y907963D02*
Y905853D01*
G01X1498921Y907963D02*
X1498920Y907962D01*
Y905853D01*
G01X1506321D02*
Y907963D01*
G01X1495221Y914372D02*
X1495220Y914371D01*
Y912262D01*
G01X1497070Y917576D02*
Y915467D01*
X1497071Y915466D01*
G01X1502621Y933598D02*
Y931488D01*
G01X1500770Y930393D02*
X1500771Y930392D01*
Y928283D01*
G01X1506321Y933598D02*
Y931488D01*
G01X1508170Y930393D02*
Y928284D01*
X1508171Y928283D01*
G01X1500770Y923985D02*
X1500771Y923984D01*
Y921875D01*
G01X1502621Y920780D02*
Y918670D01*
G01X1508170Y923985D02*
Y921876D01*
X1508171Y921875D01*
G01X1506321Y920780D02*
Y918670D01*
G01X1502621Y927189D02*
Y925079D01*
G01X1498921Y927189D02*
X1498920Y927188D01*
Y925079D01*
G01X1506321Y927189D02*
Y925079D01*
G01X1495221Y933598D02*
X1495220Y933597D01*
Y931488D01*
G01X1495221Y920780D02*
X1495220Y920779D01*
Y918670D01*
G01X1500770Y943210D02*
X1500771Y943209D01*
Y941100D01*
G01X1502621Y940006D02*
Y937896D01*
G01X1508170Y943210D02*
Y941101D01*
X1508171Y941100D01*
G01X1506321Y940006D02*
Y937896D01*
G01X1500770Y949619D02*
Y947510D01*
X1500771Y947509D01*
G01X1508170Y949619D02*
Y947510D01*
X1508171Y947509D01*
G01X1495221Y940006D02*
X1495220Y940005D01*
Y937896D01*
G01X1497070Y936801D02*
X1497071Y934691D01*
G01X1502621Y946414D02*
Y944304D01*
G01X1506321Y946414D02*
Y944305D01*
X1506320Y944304D01*
G01X1493370Y936801D02*
X1493371D01*
Y934691D01*
G01X1498921Y946414D02*
Y944305D01*
X1498920Y944304D01*
G01X1498921Y965640D02*
X1498920Y965639D01*
Y963530D01*
G01X1502621Y952823D02*
Y950713D01*
G01X1506321Y952823D02*
X1506320Y952822D01*
Y950713D01*
G01X1508170Y962436D02*
Y960327D01*
X1508171Y960326D01*
G01X1506321Y959232D02*
X1506320Y959231D01*
Y957122D01*
G01X1500770Y962436D02*
X1500771Y962435D01*
Y960326D01*
G01X1502621Y959232D02*
Y957122D01*
G01X1495221Y952823D02*
X1495220Y952822D01*
Y950713D01*
G01X1495221Y959232D02*
X1495220Y959231D01*
Y957122D01*
G01X1497070Y956027D02*
X1497071Y956026D01*
Y953917D01*
G01X1548336Y1011133D02*
X1563135D01*
X1590869Y1022621D01*
X1594675Y1026427D01*
X1597827D01*
X1599222Y1027822D01*
X1601391D01*
G01X1547959Y1008615D02*
X1564030D01*
X1594241Y1021129D01*
X1601391D01*
G01X1555323Y981238D02*
X1570630Y996545D01*
X1597253D01*
X1599441Y994357D01*
X1601391D01*
G01X1557663Y979999D02*
X1571492Y993828D01*
X1596587D01*
X1597369Y993046D01*
G01X1605369Y992755D02*
X1610769D01*
X1612513Y991011D01*
X1617533D01*
G01X1502621Y972049D02*
Y969939D01*
G01X1506321Y972049D02*
Y969939D01*
G01X1500770Y968845D02*
X1500771Y968844D01*
Y966735D01*
G01X1508170Y968845D02*
X1508171Y968844D01*
Y966735D01*
G01X1495221Y978457D02*
Y976348D01*
X1495220Y976347D01*
G01X1495221Y972049D02*
X1495220Y972048D01*
Y969939D01*
G01X1497070Y975253D02*
X1497071Y975252D01*
Y973143D01*
G01X1544264Y1002971D02*
X1546078Y1004785D01*
X1548481D01*
X1548966Y1004300D01*
X1551336D01*
X1551821Y1004785D01*
X1554191D01*
X1554676Y1004300D01*
X1557046D01*
X1557531Y1004785D01*
X1559901D01*
X1560386Y1004300D01*
X1562756D01*
X1563241Y1004785D01*
X1570155D01*
X1574904Y1006060D01*
X1575504Y1005714D01*
X1577794Y1006328D01*
X1578140Y1006929D01*
X1580428Y1007543D01*
X1581029Y1007197D01*
X1583319Y1007812D01*
X1583665Y1008413D01*
X1585953Y1009027D01*
X1586554Y1008681D01*
X1588844Y1009295D01*
X1589190Y1009897D01*
X1591478Y1010511D01*
X1592079Y1010165D01*
X1594369Y1010779D01*
X1594715Y1011381D01*
X1597003Y1011995D01*
X1597604Y1011649D01*
X1599894Y1012263D01*
X1600239Y1012862D01*
X1605931Y1014391D01*
X1607912Y1015536D01*
X1611784Y1019408D01*
X1612437Y1021057D01*
X1613453Y1022073D01*
X1614328D01*
X1615272Y1021129D01*
X1617533D01*
G01X1553578Y1001782D02*
X1567690D01*
X1569328Y1001931D01*
X1595206Y1006671D01*
X1596770Y1007029D01*
Y1007028D01*
X1598333Y1007385D01*
X1598332Y1007386D01*
X1635608Y1015898D01*
X1635728Y1015942D01*
X1636536Y1016471D01*
X1636599Y1016539D01*
X1642554Y1022954D01*
X1643500Y1023347D01*
X1644284D01*
X1645412Y1024475D01*
X1647233D01*
G01X1543351Y1003883D02*
X1545543Y1006075D01*
X1569984D01*
X1574569Y1007306D01*
Y1007307D01*
X1605435Y1015596D01*
X1607117Y1016567D01*
X1610684Y1020134D01*
X1611335Y1021781D01*
X1612917Y1023363D01*
X1614296D01*
X1615408Y1024475D01*
X1617533D01*
G01X1493803Y997574D02*
Y999684D01*
G01X1508603Y997574D02*
Y999684D01*
G01X1501203Y997574D02*
X1501204Y997575D01*
Y999684D01*
G01X1493803Y1003983D02*
Y1006092D01*
X1493804Y1006093D01*
G01X1497503Y1003983D02*
Y1006092D01*
X1497504Y1006093D01*
G01X1499354Y1013595D02*
Y1015704D01*
X1499353Y1015705D01*
G01X1501203Y1010391D02*
Y1012500D01*
X1501204Y1012501D01*
G01X1508603D02*
Y1010391D01*
G01X1503054Y1007187D02*
X1503053Y1007188D01*
Y1009297D01*
G01X1506754Y1007187D02*
Y1009296D01*
X1506753Y1009297D01*
G01X1493803Y1010391D02*
Y1012500D01*
X1493804Y1012501D01*
G01X1495654Y1007187D02*
Y1009296D01*
X1495653Y1009297D01*
G01X1495654Y1000778D02*
Y1002887D01*
X1495655Y1002888D01*
G01X1506754Y1000778D02*
Y1002887D01*
X1506753Y1002888D01*
G01X1503054Y1000778D02*
Y1002887D01*
X1503053Y1002888D01*
G01X1501203Y1029617D02*
X1501204Y1029618D01*
Y1031727D01*
G01X1503054Y1026413D02*
Y1028521D01*
X1503053Y1028522D01*
Y1028523D01*
G01X1508603Y1029617D02*
Y1031727D01*
G01X1506754Y1026413D02*
Y1028521D01*
X1506753Y1028522D01*
Y1028523D01*
G01X1506754Y1020004D02*
Y1020053D01*
X1506753Y1022114D01*
G01X1508603Y1016800D02*
Y1018910D01*
G01X1503054Y1020004D02*
Y1022113D01*
X1503053Y1022114D01*
G01X1501203Y1016800D02*
X1501204Y1016801D01*
Y1018910D01*
G01X1493803Y1029617D02*
X1493804Y1029618D01*
Y1031727D01*
G01X1495654Y1026413D02*
Y1028521D01*
X1495653Y1028522D01*
Y1028523D01*
G01X1495654Y1020004D02*
Y1020053D01*
X1495653Y1022114D01*
G01X1493803Y1016800D02*
X1493804Y1016801D01*
Y1018910D01*
G01X1497503Y1023208D02*
X1497504Y1023209D01*
Y1025318D01*
G01X1493803Y1023208D02*
X1493804Y1023209D01*
Y1025318D01*
G01X1503054Y1039230D02*
Y1041339D01*
X1503053Y1041340D01*
G01X1501203Y1036026D02*
X1501204Y1036027D01*
Y1038136D01*
G01X1506754Y1039230D02*
Y1041339D01*
X1506753Y1041340D01*
G01X1508603Y1036026D02*
Y1038136D01*
G01X1503054Y1045639D02*
Y1047747D01*
X1503053Y1047748D01*
Y1047749D01*
G01X1506754Y1045639D02*
Y1047748D01*
X1506753Y1047749D01*
G01X1503054Y1032821D02*
Y1034930D01*
X1503053Y1034931D01*
G01X1499354Y1032821D02*
Y1034930D01*
X1499353Y1034931D01*
G01X1506754Y1032821D02*
Y1034930D01*
X1506753Y1034931D01*
G01X1495654Y1045639D02*
Y1047748D01*
X1495653Y1047749D01*
G01X1495654Y1039230D02*
Y1041339D01*
X1495653Y1041340D01*
G01X1493803Y1036026D02*
Y1038135D01*
X1493804Y1038136D01*
G01X1497503Y1042434D02*
Y1044543D01*
X1497504Y1044544D01*
G01X1493803Y1042434D02*
Y1044543D01*
X1493804Y1044544D01*
G01X1495654Y1058455D02*
Y1060564D01*
X1495653Y1060565D01*
G01X1493803Y1055251D02*
Y1057360D01*
X1493804Y1057361D01*
G01X1503054Y1058455D02*
Y1060564D01*
X1503053Y1060565D01*
G01X1501203Y1055251D02*
Y1057360D01*
X1501204Y1057361D01*
G01X1506754Y1058455D02*
Y1060564D01*
X1506753Y1060565D01*
G01X1508603Y1055251D02*
Y1057360D01*
X1508604Y1057361D01*
G01X1501203Y1048842D02*
Y1050952D01*
G01X1508603Y1048842D02*
X1508604Y1050953D01*
G01X1499354Y1052047D02*
Y1054156D01*
X1499353Y1054157D01*
G01X1497503Y1061660D02*
X1497504Y1063653D01*
Y1063770D01*
G01X1503054Y1052047D02*
Y1054156D01*
X1503053Y1054157D01*
G01X1493803Y1061660D02*
X1493804Y1063653D01*
Y1063770D01*
G01X1506754Y1052047D02*
Y1054156D01*
X1506753Y1054157D01*
G01X1493803Y1048842D02*
Y1050951D01*
X1493804Y1050952D01*
G01X1506754Y1077681D02*
Y1079790D01*
X1506753Y1079791D01*
G01X1508603Y1074477D02*
Y1076586D01*
X1508604Y1076587D01*
G01X1501203Y1068068D02*
X1501204Y1070178D01*
G01X1503054Y1064864D02*
Y1066973D01*
X1503053Y1066974D01*
G01X1508603Y1068068D02*
X1508604Y1070178D01*
G01X1506754Y1064864D02*
Y1066973D01*
X1506753Y1066974D01*
G01X1503054Y1077681D02*
Y1079790D01*
X1503053Y1079791D01*
G01X1501203Y1074477D02*
Y1076586D01*
X1501204Y1076587D01*
G01X1499354Y1071273D02*
Y1073382D01*
X1499353Y1073383D01*
G01X1503054Y1071273D02*
Y1073382D01*
X1503053Y1073383D01*
G01X1506754Y1071273D02*
Y1073382D01*
X1506753Y1073383D01*
G01X1493803Y1068068D02*
X1493804Y1070178D01*
G01X1495654Y1064864D02*
Y1066973D01*
X1495653Y1066974D01*
G01X1495654Y1077681D02*
Y1079790D01*
X1495653Y1079791D01*
G01X1493803Y1074477D02*
Y1076586D01*
X1493804Y1076587D01*
G01X1497503Y1093703D02*
Y1095812D01*
X1497504Y1095813D01*
G01X1508603Y1093703D02*
Y1095813D01*
G01X1501203Y1093703D02*
Y1095812D01*
X1501204Y1095813D01*
G01X1501203Y1087294D02*
X1501204Y1089404D01*
G01X1503054Y1084090D02*
Y1086199D01*
X1503053Y1086200D01*
G01X1508603Y1087294D02*
Y1089403D01*
X1508604Y1089404D01*
G01X1506754Y1084090D02*
Y1086199D01*
X1506753Y1086200D01*
G01X1503054Y1090498D02*
Y1092607D01*
X1503053Y1092608D01*
G01X1499354Y1090498D02*
Y1092607D01*
X1499353Y1092608D01*
G01X1506754Y1090498D02*
Y1092607D01*
X1506753Y1092608D01*
G01X1493803Y1087294D02*
X1493804Y1089404D01*
G01X1495654Y1084090D02*
Y1086199D01*
X1495653Y1086200D01*
G01X1497503Y1080885D02*
X1497504Y1080886D01*
Y1082995D01*
G01X1493803Y1080885D02*
X1493804Y1080886D01*
Y1082995D01*
G01X1506754Y1096907D02*
Y1099016D01*
X1506753Y1099017D01*
G01X1493803Y1100111D02*
Y1102220D01*
X1493804Y1102221D01*
G01X1524427Y845844D02*
X1521384Y842801D01*
X1518063Y834782D01*
Y819845D01*
X1518918Y815545D01*
X1524532Y801993D01*
X1535810Y790715D01*
X1555687Y777434D01*
X1561167Y774841D01*
X1566848Y773118D01*
X1575334Y771859D01*
X1597369D01*
G01X1605369Y771880D02*
X1607108D01*
X1611300Y770144D01*
X1617533D01*
G01X1526207Y844007D02*
X1523480Y841280D01*
X1520581Y834280D01*
Y820097D01*
X1521341Y816277D01*
X1526635Y803497D01*
X1537549Y792583D01*
X1556938Y779629D01*
X1561255Y777586D01*
X1562309Y777266D01*
X1568825D01*
X1570379Y775712D01*
X1571499D01*
X1573053Y777266D01*
X1574225D01*
X1575015Y776476D01*
Y775286D01*
X1575805Y774496D01*
X1576925D01*
X1577715Y775286D01*
Y776476D01*
X1578505Y777266D01*
X1579625D01*
X1580415Y776476D01*
Y775365D01*
X1581205Y774575D01*
X1582325D01*
X1583115Y775365D01*
Y776476D01*
X1583905Y777266D01*
X1585206D01*
X1586050Y776422D01*
Y775167D01*
X1586822Y774395D01*
X1596580D01*
X1597484Y773491D01*
X1601391D01*
G01X1528173Y842040D02*
X1525353Y839220D01*
X1523099Y833779D01*
Y820350D01*
X1523764Y817008D01*
X1528738Y805000D01*
X1539287Y794451D01*
X1558181Y781827D01*
X1561182Y780407D01*
X1563031Y779846D01*
X1586802D01*
X1589735Y776913D01*
X1594506D01*
X1596142Y778549D01*
X1597169D01*
G01X1605669Y778573D02*
X1607186D01*
X1608922Y776837D01*
X1617533D01*
G01X1527729Y837984D02*
X1527454Y837709D01*
X1525618Y833277D01*
Y820597D01*
X1526186Y817742D01*
X1530842Y806502D01*
X1541023Y796321D01*
X1543564Y794622D01*
X1544593Y794828D01*
X1545934Y793932D01*
X1546138Y792903D01*
X1547396Y792063D01*
X1548490Y792281D01*
X1549701Y794093D01*
X1550796Y794311D01*
X1551729Y793688D01*
X1551947Y792593D01*
X1550736Y790781D01*
X1550954Y789687D01*
X1551888Y789063D01*
X1552982Y789281D01*
X1553689Y790339D01*
X1554785Y790557D01*
X1555717Y789934D01*
X1555935Y788839D01*
X1555228Y787781D01*
X1555446Y786686D01*
X1558415Y784702D01*
X1563273Y782404D01*
X1587873D01*
X1590846Y779431D01*
X1593605D01*
X1594358Y780184D01*
X1601391D01*
G01X1519271Y851380D02*
Y853490D01*
G01X1515570D02*
X1515571Y853489D01*
Y851380D01*
G01X1511871Y866307D02*
Y864197D01*
G01X1519271Y866307D02*
Y864198D01*
X1519270Y864197D01*
G01X1522970Y866307D02*
Y864197D01*
G01X1511871Y857789D02*
Y859899D01*
G01X1510021Y856694D02*
Y854584D01*
G01X1519271Y859899D02*
Y857789D01*
G01X1515570Y859899D02*
X1515571Y857789D01*
G01X1517421Y863103D02*
X1517440Y861012D01*
X1517421Y860993D01*
G01Y854584D02*
Y856694D01*
G01X1515570Y885533D02*
Y883424D01*
X1515571Y883423D01*
G01X1513721Y882329D02*
Y880220D01*
X1513720Y880219D01*
G01X1519271Y885533D02*
Y883423D01*
G01X1521121Y882329D02*
Y880219D01*
G01X1513721Y875920D02*
Y873811D01*
X1513720Y873810D01*
G01X1515570Y872716D02*
Y870607D01*
X1515571Y870606D01*
G01X1521121Y875920D02*
Y873810D01*
G01X1519271Y870606D02*
Y872716D01*
G01X1515570Y879124D02*
Y877014D01*
G01X1522970Y879124D02*
Y877014D01*
G01X1511871Y879124D02*
Y877014D01*
G01X1519271Y879124D02*
Y877014D01*
G01X1532452Y830178D02*
Y820447D01*
X1536528Y810606D01*
X1538568Y808566D01*
X1538567D01*
X1545699Y801435D01*
X1547508Y800686D01*
X1554687D01*
X1566113Y789260D01*
X1591471D01*
X1593071Y787659D01*
X1594518Y787059D01*
X1594524Y787057D01*
X1594973Y786885D01*
X1596452D01*
X1596460Y786877D01*
X1601391D01*
G01X1529426Y831289D02*
Y827425D01*
X1529916Y826935D01*
Y824565D01*
X1529426Y824075D01*
Y822592D01*
X1530468Y817358D01*
X1531067Y815912D01*
X1531707Y815647D01*
X1532615Y813456D01*
X1532350Y812816D01*
X1534022Y808779D01*
X1534985Y807816D01*
X1535678D01*
X1537355Y806139D01*
Y805446D01*
X1539030Y803771D01*
X1539723D01*
X1541400Y802094D01*
Y801401D01*
X1543180Y799621D01*
X1546688Y798168D01*
X1551471D01*
X1553976Y797131D01*
X1555939Y795168D01*
X1556632D01*
X1558309Y793491D01*
Y792798D01*
X1559984Y791123D01*
X1560677D01*
X1562354Y789446D01*
Y788753D01*
X1564873Y786234D01*
X1566693D01*
X1567183Y786724D01*
X1569553D01*
X1570043Y786234D01*
X1572413D01*
X1572903Y786724D01*
X1575273D01*
X1575763Y786234D01*
X1578133D01*
X1578623Y786724D01*
X1580993D01*
X1581483Y786234D01*
X1583853D01*
X1584343Y786724D01*
X1586713D01*
X1587203Y786234D01*
X1588824D01*
X1594107Y784045D01*
X1595032D01*
X1596273Y785286D01*
X1597369D01*
G01X1605369Y785272D02*
X1606648D01*
X1607683Y784237D01*
X1609610D01*
X1613400Y785808D01*
X1614472D01*
X1615541Y786877D01*
X1617533D01*
G01X1533742Y830178D02*
Y825774D01*
X1534232Y825284D01*
Y822914D01*
X1533742Y822424D01*
Y820704D01*
X1537622Y811337D01*
X1539103Y809856D01*
X1539796D01*
X1541473Y808179D01*
Y807486D01*
X1543148Y805811D01*
X1543841D01*
X1545518Y804134D01*
Y803441D01*
X1546430Y802529D01*
X1547765Y801976D01*
X1555222D01*
X1556897Y800301D01*
X1557590D01*
X1559267Y798624D01*
Y797931D01*
X1560942Y796256D01*
X1561635D01*
X1563312Y794579D01*
Y793886D01*
X1566648Y790550D01*
X1567984D01*
X1568474Y791040D01*
X1570844D01*
X1571334Y790550D01*
X1573704D01*
X1574194Y791040D01*
X1576564D01*
X1577054Y790550D01*
X1579818D01*
X1580308Y791040D01*
X1582678D01*
X1583168Y790550D01*
X1585538D01*
X1586028Y791040D01*
X1588398D01*
X1588888Y790550D01*
X1592006D01*
X1593803Y788753D01*
X1594518Y788457D01*
X1595002Y788256D01*
X1595213Y788175D01*
X1597193D01*
X1599241Y790223D01*
X1601391D01*
G01X1528136Y831288D02*
Y822464D01*
X1529227Y816981D01*
X1530079Y814924D01*
X1530080Y814923D01*
X1532928Y808048D01*
X1542449Y798527D01*
X1546431Y796878D01*
X1551214D01*
X1553245Y796037D01*
X1564338Y784944D01*
X1588567D01*
X1593850Y782755D01*
X1594932D01*
X1595885Y781802D01*
X1597369D01*
G01X1605369Y781774D02*
X1606579D01*
X1607752Y782947D01*
X1609867D01*
X1613657Y784518D01*
X1614558D01*
X1615546Y783530D01*
X1617533D01*
G01X1601391Y816995D02*
X1594500D01*
X1594118Y816613D01*
X1579711D01*
X1574264Y818869D01*
X1559030Y834103D01*
X1557912D01*
X1556867Y833058D01*
X1555749D01*
X1554957Y833850D01*
Y834968D01*
X1556002Y836013D01*
Y837131D01*
X1555210Y837923D01*
X1554092D01*
X1553047Y836878D01*
X1551929D01*
X1551137Y837670D01*
Y838788D01*
X1552182Y839833D01*
Y840951D01*
X1546475Y846658D01*
G01X1543954Y841838D02*
X1545425Y840367D01*
Y836082D01*
X1554638Y826869D01*
X1555756D01*
X1556654Y827767D01*
X1557990D01*
X1559220Y826537D01*
Y825421D01*
X1558177Y824379D01*
Y823263D01*
X1558971Y822469D01*
X1560087D01*
X1561130Y823511D01*
X1562246D01*
X1571404Y814353D01*
X1580099Y810752D01*
X1592675D01*
X1592966Y811043D01*
X1597051D01*
X1597792Y810302D01*
X1601391D01*
G01X1544964Y844461D02*
X1547998Y841427D01*
Y837195D01*
X1554679Y830514D01*
X1559023D01*
X1573083Y816454D01*
X1578868Y814058D01*
X1594194D01*
X1595499Y815363D01*
X1597369D01*
G01X1605369Y815384D02*
X1609070D01*
X1610806Y813648D01*
X1617533D01*
G01X1542100Y839984D02*
X1542817Y839267D01*
Y835040D01*
X1557906Y819951D01*
X1562042D01*
X1569695Y812298D01*
X1579508Y808234D01*
X1594047D01*
X1594483Y808670D01*
X1597369D01*
G01X1605369Y808691D02*
X1607838D01*
X1609574Y806955D01*
X1617533D01*
G01X1540360Y832557D02*
X1546697Y826223D01*
Y824548D01*
X1544901Y822752D01*
Y820770D01*
X1545573Y819148D01*
X1552495Y812226D01*
X1553613D01*
X1554405Y813018D01*
Y814136D01*
X1547844Y820697D01*
Y821815D01*
X1548636Y822607D01*
X1549754D01*
X1555900Y816461D01*
X1560538D01*
X1567792Y809207D01*
X1573136Y806996D01*
X1573563Y805965D01*
X1573155Y804979D01*
X1573582Y803947D01*
X1574619Y803517D01*
X1575649Y803944D01*
X1576058Y804931D01*
X1577089Y805358D01*
X1578571Y804744D01*
X1596490D01*
X1597625Y803609D01*
X1601391D01*
G01X1539679Y825348D02*
Y820040D01*
X1541493Y815661D01*
X1550104Y807050D01*
X1555560D01*
X1558526Y810016D01*
X1559645D01*
X1561013Y808648D01*
Y807530D01*
X1559906Y806423D01*
Y805305D01*
X1560698Y804513D01*
X1561816D01*
X1562923Y805620D01*
X1564041D01*
X1564833Y804828D01*
Y803710D01*
X1563783Y802660D01*
Y801542D01*
X1564575Y800750D01*
X1565693D01*
X1566743Y801800D01*
X1567861D01*
X1568653Y801008D01*
Y799890D01*
X1567512Y798749D01*
Y797631D01*
X1568304Y796839D01*
X1569422D01*
X1570563Y797980D01*
X1571681D01*
X1573497Y796164D01*
X1575186D01*
X1576030Y797008D01*
X1578724D01*
X1579568Y796164D01*
X1582066D01*
X1585557Y799655D01*
X1593129D01*
X1596518Y798251D01*
X1596659Y798193D01*
X1597936Y796916D01*
X1601391D01*
G01X1541202Y827591D02*
X1542972Y825821D01*
Y824703D01*
X1542231Y823962D01*
Y820633D01*
X1543640Y817232D01*
X1551220Y809652D01*
X1554600D01*
X1558012Y813064D01*
X1560295D01*
X1568043Y805316D01*
X1569398D01*
X1570920Y803794D01*
Y802439D01*
X1573681Y799678D01*
X1575958D01*
X1576750Y800470D01*
Y801385D01*
X1577540Y802175D01*
X1578660D01*
X1579450Y801385D01*
Y799809D01*
X1580240Y799019D01*
X1581360D01*
X1582150Y799809D01*
Y801383D01*
X1582940Y802173D01*
X1596123D01*
X1596318Y801978D01*
X1597369D01*
G01X1605369Y801999D02*
X1605835D01*
X1606421Y802585D01*
X1607565D01*
X1608044Y802106D01*
Y800688D01*
X1608469Y800263D01*
X1611096D01*
X1611596Y799763D01*
Y799130D01*
X1612096Y798630D01*
X1613796D01*
X1615429Y800263D01*
X1617533D01*
G01X1536957Y825348D02*
Y819859D01*
X1539377Y814016D01*
X1548861Y804532D01*
X1556983D01*
X1567268Y794247D01*
X1571853D01*
X1572538Y793562D01*
X1583026D01*
X1586601Y797137D01*
X1588139D01*
X1588929Y796347D01*
Y793986D01*
X1589719Y793196D01*
X1590839D01*
X1591629Y793986D01*
Y795978D01*
X1592419Y796768D01*
X1593410D01*
X1594584Y796281D01*
X1595580Y795285D01*
X1597369D01*
G01X1605369Y795306D02*
X1605835D01*
X1606102Y795573D01*
X1607221D01*
X1607769Y795025D01*
Y792747D01*
X1608188Y792328D01*
X1609436D01*
X1610678Y793570D01*
X1617533D01*
G01X1550289Y852820D02*
X1578609Y824500D01*
X1598470D01*
X1599282Y823688D01*
X1601391D01*
G01X1549270Y849454D02*
X1552718Y846006D01*
X1553410D01*
X1555087Y844329D01*
Y843636D01*
X1556762Y841961D01*
X1557455D01*
X1559132Y840284D01*
Y839591D01*
X1560807Y837916D01*
X1561500D01*
X1563177Y836239D01*
Y835546D01*
X1564852Y833871D01*
X1565545D01*
X1567222Y832194D01*
Y831501D01*
X1568897Y829826D01*
X1569590D01*
X1571267Y828149D01*
Y827456D01*
X1572942Y825781D01*
X1573635D01*
X1575311Y824105D01*
Y823412D01*
X1576653Y822070D01*
X1580067Y820656D01*
X1583132D01*
X1583622Y821146D01*
X1585992D01*
X1586482Y820656D01*
X1588852D01*
X1589342Y821146D01*
X1591712D01*
X1592202Y820656D01*
X1594941D01*
X1596325Y822040D01*
X1597369D01*
G01X1605369Y822071D02*
X1606459D01*
X1607499Y821031D01*
X1608102D01*
X1613780Y822755D01*
X1614637D01*
X1615570Y823688D01*
X1617533D01*
G01X1548357Y848541D02*
X1575922Y820976D01*
X1579810Y819366D01*
X1595563D01*
X1596303Y818626D01*
X1597369D01*
G01X1605369Y818647D02*
X1606462D01*
X1607556Y819741D01*
X1608294D01*
X1613972Y821465D01*
X1614985D01*
X1616109Y820341D01*
X1617533D01*
G01X1510021Y907963D02*
Y905853D01*
G01X1560321Y885903D02*
X1560618Y885606D01*
Y883827D01*
X1561769Y882676D01*
X1563425D01*
X1564215Y881886D01*
Y880766D01*
X1563425Y879976D01*
X1561436D01*
X1560646Y879186D01*
Y876837D01*
X1561458Y876025D01*
X1563596D01*
X1564437Y875184D01*
Y873046D01*
X1565278Y872205D01*
X1567416D01*
X1568257Y871364D01*
Y869226D01*
X1588899Y848584D01*
X1596171D01*
X1597642Y847113D01*
X1601391D01*
G01X1557846Y879248D02*
Y875835D01*
X1588168Y845513D01*
X1597369D01*
G01X1605369Y845479D02*
X1609093D01*
X1610806Y843766D01*
X1617533D01*
G01X1556213Y869596D02*
X1556802Y869007D01*
X1559695Y869003D01*
X1583582Y845111D01*
Y843995D01*
X1582789Y843202D01*
X1581673D01*
X1575799Y849076D01*
X1574682D01*
X1573890Y848284D01*
Y847167D01*
X1580925Y840130D01*
X1589660D01*
X1591405Y841875D01*
X1596193D01*
X1597648Y840420D01*
X1601391D01*
G01X1554014Y859596D02*
X1558381Y855229D01*
X1559499D01*
X1560291Y856021D01*
Y857139D01*
X1558560Y858870D01*
Y859988D01*
X1559352Y860780D01*
X1560470D01*
X1568686Y852564D01*
Y851236D01*
X1566788Y849338D01*
Y846822D01*
X1580523Y833087D01*
X1591614D01*
X1593815Y835288D01*
X1596247D01*
X1597808Y833727D01*
X1601391D01*
G01X1555065Y864911D02*
X1560183D01*
X1572804Y852290D01*
Y851172D01*
X1570519Y848887D01*
Y846681D01*
X1580561Y836639D01*
X1590058D01*
X1592247Y838828D01*
X1597369D01*
G01X1605369Y838770D02*
X1606298D01*
X1607019Y839491D01*
X1607856D01*
X1608428Y838919D01*
Y835965D01*
X1609190Y835203D01*
X1610268D01*
X1611390Y836325D01*
X1612374D01*
X1613165Y835534D01*
X1614059D01*
X1615599Y837074D01*
X1617533D01*
G01X1554429Y855499D02*
X1558813Y851115D01*
X1559931D01*
X1562005Y853189D01*
X1563123D01*
X1563915Y852397D01*
Y851279D01*
X1561841Y849205D01*
Y848087D01*
X1580030Y829898D01*
X1593306D01*
X1595490Y832082D01*
X1597369D01*
G01X1605369Y832113D02*
X1606529D01*
X1607580Y831062D01*
Y829725D01*
X1608083Y829222D01*
X1609449D01*
X1610608Y830381D01*
X1617533D01*
G01X1510021Y927189D02*
Y925079D01*
G01X1551201Y853733D02*
X1553267Y851667D01*
X1553960D01*
X1555637Y849990D01*
Y849297D01*
X1557312Y847622D01*
X1558005D01*
X1559682Y845945D01*
Y845252D01*
X1561357Y843577D01*
X1562050D01*
X1563727Y841900D01*
Y841207D01*
X1565402Y839532D01*
X1566095D01*
X1567772Y837855D01*
Y837162D01*
X1569447Y835487D01*
X1570140D01*
X1571817Y833810D01*
Y833117D01*
X1573492Y831442D01*
X1574185D01*
X1575862Y829765D01*
Y829072D01*
X1579144Y825790D01*
X1581152D01*
X1581642Y826280D01*
X1584012D01*
X1584502Y825790D01*
X1586872D01*
X1587362Y826280D01*
X1589732D01*
X1590222Y825790D01*
X1592592D01*
X1593082Y826280D01*
X1595452D01*
X1595942Y825790D01*
X1598339D01*
X1599583Y827034D01*
X1601391D01*
G01X1559887Y922069D02*
X1566749Y915207D01*
X1579034D01*
X1582494Y918667D01*
X1594248D01*
X1594722Y919141D01*
X1596616D01*
G01X1606187Y919062D02*
X1606712D01*
X1608385Y917389D01*
X1617533D01*
G01X1571165Y908430D02*
X1581645D01*
X1584258Y911043D01*
X1585663D01*
X1592125Y904581D01*
Y879442D01*
X1595955Y875612D01*
X1597369D01*
G01X1605369Y875592D02*
X1608285D01*
X1609992Y873885D01*
X1617533D01*
G01X1571565Y903079D02*
X1576504D01*
X1578083Y901500D01*
Y900382D01*
X1577114Y899413D01*
Y898295D01*
X1577906Y897503D01*
X1579024D01*
X1579993Y898472D01*
X1581111D01*
X1581903Y897680D01*
Y896562D01*
X1580934Y895593D01*
Y894475D01*
X1581726Y893683D01*
X1582844D01*
X1583813Y894652D01*
X1584931D01*
X1586950Y892633D01*
Y877315D01*
X1595348Y868917D01*
X1597369D01*
G01X1605369Y868904D02*
X1607238D01*
X1608950Y867192D01*
X1617533D01*
G01X1564113Y889696D02*
X1566475Y887334D01*
X1567453D01*
X1574547Y880240D01*
Y879122D01*
X1573755Y878330D01*
X1572637D01*
X1571408Y879559D01*
X1570290D01*
X1569498Y878767D01*
Y877649D01*
X1571511Y875636D01*
X1573758D01*
X1574548Y874846D01*
Y870169D01*
X1590911Y853806D01*
X1601391D01*
G01X1562126Y887709D02*
X1567540Y882295D01*
Y880541D01*
X1566153Y879154D01*
Y877290D01*
X1571629Y871814D01*
Y869484D01*
X1589894Y851219D01*
X1593637D01*
X1594597Y852179D01*
X1597342D01*
X1597369Y852152D01*
G01X1605369Y852133D02*
X1606121D01*
X1606176Y852188D01*
X1608561D01*
X1610290Y850459D01*
X1617533D01*
G01X1571166Y911606D02*
X1580728D01*
X1583780Y914658D01*
X1593785D01*
X1594575Y913868D01*
Y912748D01*
X1593785Y911958D01*
X1591467D01*
X1590677Y911168D01*
Y910048D01*
X1591467Y909258D01*
X1593877D01*
X1594728Y908407D01*
Y880443D01*
X1597940Y877231D01*
X1601391D01*
G01X1571565Y905665D02*
X1587402D01*
X1588244Y904823D01*
Y903703D01*
X1587454Y902913D01*
X1583316D01*
X1582526Y902123D01*
Y901003D01*
X1583316Y900213D01*
X1588778D01*
X1589568Y899423D01*
Y878369D01*
X1596477Y871460D01*
X1597073D01*
X1597995Y870538D01*
X1601391D01*
G01X1567487Y898894D02*
X1582028Y884353D01*
Y875381D01*
X1592277Y865132D01*
Y862387D01*
X1594167Y860497D01*
X1597536D01*
X1597538Y860499D01*
X1601391D01*
G01X1566201Y894384D02*
X1570350Y890235D01*
X1571043D01*
X1572720Y888558D01*
Y887865D01*
X1574395Y886190D01*
X1575088D01*
X1576765Y884513D01*
Y883820D01*
X1578440Y882145D01*
Y878919D01*
X1578930Y878429D01*
Y876059D01*
X1578440Y875569D01*
Y871778D01*
X1579567Y870651D01*
X1580260D01*
X1581937Y868974D01*
Y868281D01*
X1583612Y866606D01*
X1584305D01*
X1585982Y864929D01*
Y864237D01*
X1588658Y861561D01*
X1589351D01*
X1591027Y859885D01*
Y859191D01*
X1591849Y858369D01*
Y857559D01*
X1592640Y856768D01*
X1593758D01*
X1594548Y857558D01*
Y858010D01*
X1595442Y858904D01*
X1597369D01*
G01X1605369Y858825D02*
X1606054D01*
X1606102Y858873D01*
X1607489D01*
X1608503Y857859D01*
X1609610D01*
X1613400Y859430D01*
X1614472D01*
X1615541Y860499D01*
X1617533D01*
G01X1568400Y899807D02*
X1570279Y897928D01*
X1570972D01*
X1572649Y896251D01*
Y895558D01*
X1574324Y893883D01*
X1575017D01*
X1576694Y892206D01*
Y891513D01*
X1578369Y889838D01*
X1579062D01*
X1580739Y888161D01*
Y887468D01*
X1583318Y884889D01*
Y882519D01*
X1583808Y882029D01*
Y879659D01*
X1583318Y879169D01*
Y875916D01*
X1585004Y874230D01*
X1585697D01*
X1587374Y872553D01*
Y871860D01*
X1589150Y870084D01*
X1589843D01*
X1591520Y868407D01*
Y867714D01*
X1593567Y865667D01*
Y862922D01*
X1594702Y861787D01*
X1596351D01*
X1597132Y862568D01*
Y863409D01*
X1597568Y863845D01*
X1601391D01*
G01X1565288Y893471D02*
X1577150Y881609D01*
Y871243D01*
X1590559Y857834D01*
Y857024D01*
X1592105Y855478D01*
X1593801D01*
X1593864Y855415D01*
X1597369D01*
G01X1605369Y855479D02*
X1605412Y855436D01*
X1607531D01*
X1608664Y856569D01*
X1609867D01*
X1613657Y858140D01*
X1614558D01*
X1615546Y857152D01*
X1617533D01*
G01X1510021Y946414D02*
Y944304D01*
G01X1558666Y929734D02*
X1566033D01*
X1566823Y928944D01*
Y927202D01*
X1567613Y926412D01*
X1568733D01*
X1569523Y927202D01*
Y928955D01*
X1570313Y929745D01*
X1571433D01*
X1572223Y928955D01*
Y927202D01*
X1573013Y926412D01*
X1574133D01*
X1574923Y927202D01*
Y928765D01*
X1575713Y929555D01*
X1576833D01*
X1577623Y928765D01*
Y927361D01*
X1578413Y926571D01*
X1579533D01*
X1580323Y927361D01*
Y928705D01*
X1581113Y929495D01*
X1586964D01*
X1587754Y928705D01*
Y927282D01*
X1588544Y926492D01*
X1594929D01*
X1595865Y927428D01*
X1601391D01*
G01X1559866Y924610D02*
X1561387D01*
X1564621Y921376D01*
X1568831D01*
X1569621Y920586D01*
Y918524D01*
X1570411Y917734D01*
X1571531D01*
X1572321Y918524D01*
Y920586D01*
X1573111Y921376D01*
X1574231D01*
X1575021Y920586D01*
Y918524D01*
X1575811Y917734D01*
X1576931D01*
X1577721Y918524D01*
Y920586D01*
X1578511Y921376D01*
X1593370D01*
X1594011Y920735D01*
X1601391D01*
G01X1559866Y927143D02*
X1562462D01*
X1565711Y923894D01*
X1580417D01*
X1583316Y926793D01*
X1584793D01*
X1585416Y926170D01*
Y924724D01*
X1586206Y923934D01*
X1594321D01*
X1595882Y922373D01*
X1596701D01*
G01X1605951Y922326D02*
X1606617D01*
X1607983Y923692D01*
X1613929D01*
X1614318Y924081D01*
X1617533D01*
G01X1552266Y949575D02*
X1553011D01*
X1553801Y950365D01*
Y951731D01*
X1554591Y952521D01*
X1555801D01*
X1556591Y951731D01*
Y950365D01*
X1557381Y949575D01*
X1558591D01*
X1559381Y950365D01*
Y951731D01*
X1560171Y952521D01*
X1561381D01*
X1562171Y951731D01*
Y950365D01*
X1562961Y949575D01*
X1565960D01*
X1568438Y952053D01*
X1571100D01*
X1575685Y956638D01*
X1587911D01*
X1589224Y956094D01*
X1594465Y950853D01*
X1601391D01*
G01X1556166Y944363D02*
X1568797D01*
X1570943Y946509D01*
X1573109D01*
X1577377Y950777D01*
X1579126D01*
X1579916Y949987D01*
Y947480D01*
X1580706Y946690D01*
X1581826D01*
X1582616Y947480D01*
Y949987D01*
X1583406Y950777D01*
X1585739D01*
X1586762Y950353D01*
X1593987Y943128D01*
X1598247D01*
X1599279Y944160D01*
X1601391D01*
G01X1554766Y946939D02*
X1566969D01*
X1569215Y949185D01*
X1572181D01*
X1576319Y953323D01*
X1586849D01*
X1587798Y952930D01*
X1594983Y945745D01*
X1596531D01*
X1596544Y945758D01*
G01X1605946D02*
X1607801D01*
X1609550Y947507D01*
X1617533D01*
G01X1556166Y941755D02*
X1570373D01*
X1572474Y943856D01*
X1574549D01*
X1575339Y943066D01*
Y941907D01*
X1576129Y941117D01*
X1577249D01*
X1578039Y941907D01*
Y943066D01*
X1578829Y943856D01*
X1579949D01*
X1580739Y943066D01*
Y941907D01*
X1581529Y941117D01*
X1582649D01*
X1583439Y941907D01*
Y943066D01*
X1584229Y943856D01*
X1589295D01*
X1594732Y938419D01*
X1596005D01*
X1596726Y939140D01*
X1597369D01*
G01X1605369Y939077D02*
X1607724D01*
X1609461Y940814D01*
X1617533D01*
G01X1558666Y933618D02*
X1566095D01*
X1566580Y934103D01*
X1568950D01*
X1569435Y933618D01*
X1571805D01*
X1572290Y934103D01*
X1574660D01*
X1575145Y933618D01*
X1577515D01*
X1578000Y934103D01*
X1580370D01*
X1580855Y933618D01*
X1583225D01*
X1583710Y934103D01*
X1586080D01*
X1586565Y933618D01*
X1588935D01*
X1592162Y930391D01*
X1593275D01*
X1594064Y931180D01*
Y931707D01*
X1594888Y932531D01*
X1595396D01*
G01X1607169Y932447D02*
X1607647D01*
X1608613Y931481D01*
X1609611D01*
X1613400Y933052D01*
X1614472D01*
X1615541Y934121D01*
X1617533D01*
G01X1558666Y936621D02*
X1591033D01*
X1593532Y934122D01*
X1601390D01*
X1601391Y934121D01*
G01X1558666Y932328D02*
X1588400D01*
X1591627Y929101D01*
X1595396D01*
G01X1607169D02*
X1607570D01*
X1608660Y930191D01*
X1609868D01*
X1613657Y931762D01*
X1614558D01*
X1615546Y930774D01*
X1617533D01*
G01X1558666Y937911D02*
X1562218D01*
X1562708Y938401D01*
X1565078D01*
X1565568Y937911D01*
X1567938D01*
X1568428Y938401D01*
X1570798D01*
X1571288Y937911D01*
X1573658D01*
X1574148Y938401D01*
X1576518D01*
X1577008Y937911D01*
X1579378D01*
X1579868Y938401D01*
X1582238D01*
X1582728Y937911D01*
X1585098D01*
X1585588Y938401D01*
X1587958D01*
X1588448Y937911D01*
X1591568D01*
X1594067Y935412D01*
X1596503D01*
X1597008Y935917D01*
Y937123D01*
X1597349Y937467D01*
X1601391D01*
G01X1510021Y965640D02*
Y963530D01*
G01X1561263Y980038D02*
X1570838Y989613D01*
X1572316D01*
X1573983Y991280D01*
X1575183D01*
X1576850Y989613D01*
X1580400D01*
X1581925Y991138D01*
X1583792D01*
X1585317Y989613D01*
X1595040D01*
X1595689Y988964D01*
X1597987D01*
X1599287Y987664D01*
X1601391D01*
G01X1561263Y976835D02*
X1561266Y976838D01*
X1561624D01*
X1570864Y986078D01*
X1597369D01*
G01X1605369Y986033D02*
X1611247D01*
X1612962Y984318D01*
X1617533D01*
G01X1555331Y975267D02*
X1556339Y974259D01*
X1562606D01*
X1570928Y982581D01*
X1596663D01*
X1598273Y980971D01*
X1601391D01*
G01X1553143Y973879D02*
X1555308Y971714D01*
X1563623D01*
X1571478Y979569D01*
X1595747D01*
X1595924Y979392D01*
X1597369D01*
G01X1605369Y979371D02*
X1611439D01*
X1612011Y978799D01*
Y978335D01*
X1612721Y977625D01*
X1617533D01*
G01X1551345Y972081D02*
X1554230Y969196D01*
X1564666D01*
X1572521Y977051D01*
X1594660D01*
X1596068Y975643D01*
X1596454D01*
X1597819Y974278D01*
X1601391D01*
G01X1546719Y969457D02*
X1552016Y964160D01*
X1566753D01*
X1572916Y970323D01*
X1593667D01*
X1594811Y969179D01*
X1597369D01*
G01X1605266Y968804D02*
X1605688Y968382D01*
Y967242D01*
X1608173Y964757D01*
X1609149D01*
X1610524Y966132D01*
Y967251D01*
X1608171Y969596D01*
X1608169Y970783D01*
X1609153Y971767D01*
X1610271D01*
X1612683Y969355D01*
X1613511D01*
G01X1621511Y969356D02*
X1625572D01*
X1627343Y967585D01*
X1631091D01*
G01X1543241Y965199D02*
X1549316Y959124D01*
X1568841D01*
X1573057Y963340D01*
X1589684D01*
X1592964Y961981D01*
X1595726Y959219D01*
X1596597D01*
G01X1605293D02*
X1606266D01*
X1612912Y965865D01*
X1613511D01*
G01X1621511Y965815D02*
X1622259D01*
X1625509Y962565D01*
X1626306D01*
G01X1635069Y962528D02*
X1636211D01*
X1637047Y961692D01*
Y960458D01*
X1637837Y959668D01*
X1639296D01*
X1640087Y960459D01*
Y963553D01*
X1640773Y964239D01*
X1647233D01*
G01X1545129Y967467D02*
X1550954Y961642D01*
X1567797D01*
X1573960Y967805D01*
X1576531D01*
X1578478Y965858D01*
X1579688D01*
X1581360Y967530D01*
X1582478D01*
X1584150Y965858D01*
X1587458D01*
X1589405Y967805D01*
X1592624D01*
X1593830Y966599D01*
X1598096D01*
X1599082Y967585D01*
X1601391D01*
G01X1539653Y965199D02*
X1548246Y956606D01*
X1569884D01*
X1574045Y960767D01*
X1589025D01*
X1591287Y959830D01*
X1595244Y955873D01*
X1596555D01*
G01X1605193Y955975D02*
X1607043D01*
X1607811Y955207D01*
Y953909D01*
X1608501Y953219D01*
X1610321D01*
X1611011Y953909D01*
Y961463D01*
X1613787Y964239D01*
X1617533D01*
G01Y970932D02*
X1615141D01*
X1613654Y972419D01*
X1612408D01*
X1610439Y974388D01*
X1608570D01*
X1608111Y973929D01*
Y973509D01*
X1607284Y972682D01*
X1605193D01*
G01X1597493Y972654D02*
X1594683D01*
X1592804Y974533D01*
X1573565D01*
X1565710Y966678D01*
X1553158D01*
X1549150Y970686D01*
G01X1553578Y1000492D02*
X1562222D01*
X1562707Y1000007D01*
X1565007D01*
X1565492Y1000492D01*
X1567749D01*
X1569503Y1000651D01*
X1595466Y1005407D01*
X1598620Y1006127D01*
X1599195Y1005766D01*
X1601507Y1006293D01*
X1601868Y1006869D01*
X1604178Y1007396D01*
X1604753Y1007035D01*
X1607065Y1007562D01*
X1607426Y1008138D01*
X1609736Y1008665D01*
X1610311Y1008304D01*
X1612623Y1008831D01*
X1612984Y1009407D01*
X1615294Y1009934D01*
X1615869Y1009573D01*
X1618181Y1010100D01*
X1618542Y1010676D01*
X1620852Y1011203D01*
X1621426Y1010842D01*
X1623738Y1011369D01*
X1624099Y1011945D01*
X1626409Y1012472D01*
X1626984Y1012111D01*
X1629295Y1012639D01*
X1629656Y1013215D01*
X1635970Y1014656D01*
X1636313Y1014782D01*
X1637376Y1015478D01*
X1638361Y1016539D01*
X1643308Y1021870D01*
X1643758Y1022057D01*
X1644306D01*
X1645234Y1021129D01*
X1647233D01*
G01X1562028Y1016673D02*
X1586240Y1026703D01*
X1592194Y1032671D01*
X1594876D01*
X1595595Y1033390D01*
X1598002D01*
X1599127Y1034515D01*
X1601391D01*
G01X1548336Y1013651D02*
X1562328D01*
X1588674Y1024564D01*
X1593564Y1029454D01*
X1597369D01*
G01X1605369Y1029081D02*
X1606553Y1027897D01*
X1609085D01*
X1609487Y1028299D01*
Y1029065D01*
X1607861Y1030691D01*
Y1031669D01*
X1608500Y1032308D01*
X1613145D01*
X1614285Y1031168D01*
X1617533D01*
G01X1552925Y1022662D02*
X1556938Y1026675D01*
X1581550Y1036870D01*
X1589247Y1044567D01*
X1594492D01*
X1597066Y1047141D01*
X1598545D01*
X1599304Y1047900D01*
X1601391D01*
G01X1555730Y1021470D02*
X1558754Y1024494D01*
X1582623Y1034381D01*
X1590001Y1041759D01*
X1594732D01*
X1595786Y1042813D01*
X1597369D01*
G01X1605369Y1042823D02*
X1607380D01*
X1608161Y1043604D01*
Y1044770D01*
X1608719Y1045328D01*
X1611002D01*
X1611776Y1044554D01*
X1617533D01*
G01X1558261Y1020440D02*
X1559566Y1021745D01*
X1583457Y1031641D01*
X1589886Y1038070D01*
Y1038069D01*
X1590926Y1039109D01*
X1595762D01*
X1596827Y1040174D01*
X1598188D01*
X1599221Y1041207D01*
X1601391D01*
G01X1560042Y1018659D02*
X1560574Y1019191D01*
X1585029Y1029321D01*
X1591832Y1036124D01*
X1597369D01*
G01X1605369Y1036104D02*
X1609438D01*
X1610228Y1036894D01*
Y1038469D01*
X1610728Y1038969D01*
X1614009D01*
X1615117Y1037861D01*
X1617533D01*
G01X1546288Y1030613D02*
X1552423Y1036748D01*
X1576922Y1046896D01*
X1584680Y1054654D01*
Y1054653D01*
X1585377Y1055350D01*
X1591059D01*
X1592847Y1057138D01*
X1595053D01*
X1595964Y1056227D01*
X1597369D01*
G01X1605369Y1056194D02*
X1606150D01*
X1607369Y1054975D01*
X1608919D01*
X1609450Y1055506D01*
X1611147D01*
X1611946Y1056305D01*
X1613693D01*
G01X1621293Y1056313D02*
X1622749D01*
X1624469Y1054593D01*
X1631091D01*
G01X1549495Y1026601D02*
X1554440Y1031546D01*
X1579084Y1041754D01*
X1587557Y1050227D01*
X1593222D01*
X1595974Y1052979D01*
X1597369D01*
G01X1605369D02*
X1606687D01*
X1606944Y1052722D01*
X1610066D01*
X1610211Y1052867D01*
X1613793D01*
G01X1621193Y1052821D02*
X1625200D01*
X1625327Y1052948D01*
X1627193D01*
G01X1635069Y1052993D02*
X1637658D01*
X1638961Y1051690D01*
Y1050509D01*
X1639651Y1049819D01*
X1640861D01*
X1642289Y1051247D01*
X1647233D01*
G01X1548118Y1028846D02*
X1553341Y1034069D01*
X1577934Y1044256D01*
X1586506Y1052828D01*
X1592190D01*
X1593955Y1054593D01*
X1601391D01*
G01X1551343Y1024752D02*
X1555766Y1029175D01*
X1580412Y1039384D01*
X1588698Y1047670D01*
X1594839D01*
X1596691Y1049522D01*
X1597369D01*
G01X1605369Y1049501D02*
X1606129D01*
X1606780Y1048850D01*
X1608149D01*
X1608487Y1049188D01*
Y1050173D01*
X1609184Y1050870D01*
X1610624D01*
X1611001Y1051247D01*
X1617533D01*
G01X1510453Y1013595D02*
Y1015705D01*
G01X1571870Y1093474D02*
X1572881D01*
X1575537Y1096130D01*
X1576655D01*
X1577445Y1095340D01*
Y1094335D01*
X1578235Y1093545D01*
X1579355D01*
X1580145Y1094335D01*
Y1095340D01*
X1580935Y1096130D01*
X1582055D01*
X1583932Y1094253D01*
X1586348D01*
X1588652Y1096557D01*
X1594758D01*
X1596709Y1098508D01*
X1597828D01*
X1598239Y1098097D01*
X1601391D01*
G01X1575970Y1088377D02*
X1583125D01*
X1583835Y1089087D01*
X1586972D01*
X1587682Y1088377D01*
X1589123D01*
X1589913Y1089167D01*
Y1090650D01*
X1590639Y1091376D01*
X1592655D01*
X1593742Y1090289D01*
X1595211D01*
X1596326Y1091404D01*
X1601391D01*
G01X1575970Y1090997D02*
X1580881D01*
X1581556Y1091672D01*
X1587329D01*
X1589613Y1093956D01*
X1594739D01*
X1595618Y1093077D01*
X1596264D01*
G01X1606073D02*
X1606848D01*
X1608200Y1094429D01*
X1611563D01*
X1613893Y1094751D01*
X1617533D01*
G01X1575969Y1085796D02*
X1590363D01*
X1591823Y1087256D01*
X1593685D01*
X1594557Y1086384D01*
X1596264D01*
G01X1606073D02*
X1606902D01*
X1608576Y1088058D01*
X1617533D01*
G01X1575453Y1073063D02*
X1577195Y1074805D01*
X1578313D01*
X1579103Y1074015D01*
Y1073497D01*
X1579893Y1072707D01*
X1581013D01*
X1583067Y1074761D01*
X1584316D01*
X1585799Y1073278D01*
Y1072160D01*
X1584667Y1071028D01*
X1583394D01*
X1582604Y1070238D01*
Y1069118D01*
X1583394Y1068328D01*
X1585794D01*
X1588537Y1071071D01*
Y1073402D01*
X1589327Y1074192D01*
X1590445D01*
X1590909Y1073728D01*
X1594154D01*
X1595098Y1074672D01*
X1601391D01*
G01X1571068Y1058635D02*
X1571665D01*
X1578078Y1065048D01*
X1579196D01*
X1579988Y1064256D01*
Y1063138D01*
X1574464Y1057614D01*
Y1056496D01*
X1575256Y1055704D01*
X1576374D01*
X1582833Y1062163D01*
X1588104D01*
X1589951Y1064010D01*
X1591127D01*
X1592315Y1065198D01*
Y1065934D01*
X1594360Y1067979D01*
X1601391D01*
G01X1575868Y1067201D02*
X1577036Y1068369D01*
Y1069615D01*
X1577595Y1070174D01*
X1579442D01*
X1579865Y1069751D01*
Y1068257D01*
X1583424Y1064698D01*
X1586347D01*
X1591071Y1069422D01*
Y1070342D01*
X1591925Y1071196D01*
X1593645D01*
X1595189Y1069652D01*
X1595775D01*
G01X1606894D02*
X1607515D01*
X1608200Y1070337D01*
Y1070937D01*
X1608955Y1071692D01*
X1610128D01*
X1610959Y1070861D01*
X1613892D01*
X1614357Y1071326D01*
X1617533D01*
G01X1570918Y1055498D02*
X1571609D01*
X1572290Y1054817D01*
Y1053915D01*
X1573788Y1052417D01*
X1576648D01*
X1583724Y1059493D01*
X1589428D01*
X1591298Y1061363D01*
X1593592D01*
X1594814Y1062585D01*
Y1064854D01*
X1596266Y1066306D01*
X1596709D01*
G01X1606134D02*
X1606982D01*
X1607773Y1065515D01*
Y1062573D01*
X1608483Y1061863D01*
X1610760D01*
X1613530Y1064633D01*
X1617533D01*
G01X1575969Y1081946D02*
X1577669D01*
X1578159Y1081456D01*
X1579859D01*
X1580349Y1081946D01*
X1582049D01*
X1582539Y1081456D01*
X1584239D01*
X1584729Y1081946D01*
X1586429D01*
X1586919Y1081456D01*
X1588619D01*
X1589109Y1081946D01*
X1592381D01*
X1593262Y1082827D01*
X1593713Y1083014D01*
X1594694Y1083421D01*
X1597042D01*
X1597385Y1083078D01*
Y1081704D01*
X1597724Y1081365D01*
X1601391D01*
G01X1579768Y1078717D02*
X1591439D01*
X1592522Y1077634D01*
X1594137D01*
X1594529Y1078026D01*
Y1079195D01*
X1595025Y1079691D01*
X1596280D01*
G01X1605903Y1079763D02*
X1606661D01*
X1607699Y1078725D01*
X1608743D01*
X1610314Y1080296D01*
X1614472D01*
X1615541Y1081365D01*
X1617533D01*
G01X1575969Y1083236D02*
X1591846D01*
X1592531Y1083921D01*
X1593713Y1084411D01*
X1594437Y1084711D01*
X1601391D01*
G01X1579768Y1077427D02*
X1590904D01*
X1591987Y1076344D01*
X1596280D01*
G01X1605912Y1076259D02*
X1606664D01*
X1607840Y1077435D01*
X1609278D01*
X1610849Y1079006D01*
X1614558D01*
X1615546Y1078018D01*
X1617533D01*
G01X1561422Y1116695D02*
X1571935Y1127208D01*
X1573264D01*
X1574054Y1127998D01*
Y1129433D01*
X1574880Y1130259D01*
X1578088D01*
X1579952Y1128395D01*
X1581072D01*
X1582853Y1130176D01*
X1583971D01*
X1585696Y1128451D01*
X1586882D01*
X1588690Y1130259D01*
X1590164D01*
X1591840Y1128583D01*
X1592958D01*
X1594501Y1130126D01*
X1595619D01*
X1596449Y1129296D01*
X1598226D01*
X1599307Y1128215D01*
X1601391D01*
G01X1563203Y1114914D02*
X1572124Y1123835D01*
X1577015Y1125861D01*
X1594443D01*
X1595258Y1126676D01*
X1597369D01*
G01X1605369Y1126611D02*
X1606564D01*
X1607078Y1127125D01*
X1608196D01*
X1608986Y1126335D01*
Y1125145D01*
X1609752Y1124379D01*
X1610870D01*
X1611360Y1124869D01*
X1617533D01*
G01X1568769Y1105168D02*
X1576558Y1112957D01*
X1577695D01*
X1578486Y1113748D01*
Y1114439D01*
X1579276Y1115229D01*
X1580396D01*
X1581186Y1114439D01*
Y1113747D01*
X1581976Y1112957D01*
X1583137D01*
X1583950Y1113770D01*
Y1114436D01*
X1584740Y1115226D01*
X1586232D01*
X1587695Y1113763D01*
Y1113425D01*
X1589943Y1111177D01*
X1590518Y1109790D01*
X1591026Y1109282D01*
X1592145D01*
X1593904Y1111041D01*
X1595165D01*
X1595607Y1111483D01*
X1601391D01*
G01X1569424Y1098593D02*
X1578752Y1107921D01*
X1585375D01*
X1586165Y1107131D01*
Y1106011D01*
X1585375Y1105221D01*
X1579941D01*
X1579151Y1104431D01*
Y1103311D01*
X1579941Y1102521D01*
X1586666D01*
X1587392Y1103247D01*
X1588511D01*
X1589153Y1102605D01*
X1592781D01*
X1596604Y1106428D01*
X1597504D01*
X1599142Y1104790D01*
X1601391D01*
G01X1568770Y1101586D02*
X1577623Y1110439D01*
X1584206D01*
X1585103Y1111336D01*
X1586222D01*
X1587808Y1109750D01*
X1588683Y1107638D01*
Y1106630D01*
X1590174Y1105139D01*
X1591563D01*
X1596269Y1109845D01*
X1597369D01*
G01X1605369Y1109859D02*
X1606870D01*
X1607709Y1109020D01*
Y1107615D01*
X1608650Y1106674D01*
X1609975D01*
X1611438Y1108137D01*
X1617533D01*
G01X1571819Y1097398D02*
X1576085Y1101664D01*
X1577204D01*
X1578070Y1100798D01*
Y1100410D01*
X1578901Y1099579D01*
X1580400D01*
X1580484Y1099663D01*
X1583454D01*
X1584426Y1098691D01*
X1585849D01*
X1587007Y1099849D01*
X1587555Y1100076D01*
X1594354D01*
X1595013Y1100735D01*
Y1102326D01*
X1595804Y1103117D01*
X1596709D01*
G01X1606518Y1103244D02*
X1607257D01*
X1608041Y1102460D01*
Y1099583D01*
X1608831Y1098793D01*
X1610703D01*
X1611493Y1099583D01*
Y1102271D01*
X1612203Y1102981D01*
X1613971D01*
X1615508Y1101444D01*
X1617533D01*
G01X1564028Y1109589D02*
X1574592Y1120153D01*
X1579162Y1122046D01*
X1588742D01*
X1591795Y1120006D01*
X1591796Y1120005D01*
X1594348Y1118301D01*
X1597628D01*
X1597753Y1118176D01*
X1601391D01*
G01X1565823Y1107793D02*
X1574949Y1116919D01*
X1577469Y1118604D01*
X1578517Y1119037D01*
X1581191D01*
X1581681Y1119527D01*
X1584051D01*
X1584541Y1119037D01*
X1586985D01*
X1588390Y1118455D01*
X1589131Y1117714D01*
X1589824D01*
X1591501Y1116037D01*
Y1115344D01*
X1592400Y1114445D01*
X1593836D01*
X1594506Y1115115D01*
Y1115819D01*
X1595296Y1116609D01*
X1597369D01*
G01X1605369Y1116573D02*
X1607528D01*
X1608565Y1115536D01*
X1609610D01*
X1612908Y1116903D01*
X1614268D01*
X1615541Y1118176D01*
X1617533D01*
G01X1563115Y1110501D02*
X1564790Y1112176D01*
Y1112862D01*
X1566467Y1114539D01*
X1567153D01*
X1568828Y1116214D01*
Y1116900D01*
X1570505Y1118577D01*
X1571191D01*
X1573861Y1121247D01*
X1578905Y1123336D01*
X1589134D01*
X1589815Y1122881D01*
X1590170Y1122644D01*
X1590850Y1122779D01*
X1592821Y1121462D01*
X1592957Y1120782D01*
X1594740Y1119591D01*
X1597093D01*
X1597353Y1119851D01*
Y1121201D01*
X1597674Y1121522D01*
X1601391D01*
G01X1566736Y1106881D02*
X1575769Y1115914D01*
X1578080Y1117460D01*
X1578774Y1117747D01*
X1586728D01*
X1587659Y1117361D01*
X1591891Y1113129D01*
X1597369D01*
G01X1605369Y1113075D02*
X1607475D01*
X1608646Y1114246D01*
X1609867D01*
X1613165Y1115613D01*
X1614762D01*
X1615546Y1114829D01*
X1617533D01*
G01X1510453Y1032821D02*
Y1034931D01*
G01X1549669Y1134069D02*
X1569629Y1154029D01*
X1570747D01*
X1572331Y1152445D01*
X1583343D01*
X1584133Y1153235D01*
Y1154355D01*
X1583343Y1155145D01*
X1573436D01*
X1572646Y1155935D01*
Y1157055D01*
X1573436Y1157845D01*
X1575054D01*
X1576091Y1158882D01*
X1577783D01*
X1578791Y1157874D01*
X1580083D01*
X1581091Y1158882D01*
X1582028D01*
X1583510Y1158269D01*
X1585059Y1157234D01*
X1589255Y1153038D01*
X1590265Y1151527D01*
X1590551Y1150836D01*
Y1149178D01*
X1591900Y1147829D01*
X1592622D01*
X1593743Y1148294D01*
X1601391D01*
G01X1553660Y1124757D02*
X1554500Y1125597D01*
Y1126716D01*
X1552596Y1128620D01*
Y1129738D01*
X1553388Y1130530D01*
X1554506D01*
X1556457Y1128579D01*
X1557575D01*
X1558367Y1129371D01*
Y1130489D01*
X1556416Y1132440D01*
Y1133558D01*
X1557208Y1134350D01*
X1558326D01*
X1560277Y1132399D01*
X1561395D01*
X1562187Y1133191D01*
Y1134309D01*
X1560236Y1136260D01*
Y1137378D01*
X1561028Y1138170D01*
X1562146D01*
X1564097Y1136219D01*
X1565215D01*
X1566007Y1137011D01*
Y1138129D01*
X1564056Y1140080D01*
Y1141198D01*
X1564848Y1141990D01*
X1565966D01*
X1567442Y1140514D01*
X1568560D01*
X1569352Y1141306D01*
Y1142424D01*
X1567876Y1143900D01*
Y1145018D01*
X1570040Y1147182D01*
X1583589D01*
X1586315Y1144456D01*
Y1142139D01*
X1587134Y1141320D01*
X1593632D01*
X1595023Y1142711D01*
X1598041D01*
X1599151Y1141601D01*
X1601391D01*
G01X1550869Y1131708D02*
X1569474Y1150313D01*
X1570991D01*
X1571570Y1149734D01*
X1584194D01*
X1585829Y1151369D01*
X1586948D01*
X1588033Y1150284D01*
Y1146300D01*
X1589004Y1145329D01*
Y1144642D01*
X1589794Y1143852D01*
X1592419D01*
X1594132Y1145565D01*
X1595120D01*
X1596244Y1146689D01*
X1597369D01*
G01X1605369Y1146700D02*
X1606659D01*
X1607587Y1145772D01*
Y1143894D01*
X1608238Y1143243D01*
X1609788D01*
X1610313Y1143768D01*
Y1144448D01*
X1610813Y1144948D01*
X1611931D01*
X1613343Y1143536D01*
X1614461D01*
X1615873Y1144948D01*
X1617533D01*
G01X1555488Y1122928D02*
X1571362Y1138802D01*
X1580317D01*
X1581107Y1139592D01*
Y1140712D01*
X1580317Y1141502D01*
X1572660D01*
X1571870Y1142292D01*
Y1143412D01*
X1572660Y1144202D01*
X1583007D01*
X1583797Y1143412D01*
Y1139575D01*
X1584570Y1138802D01*
X1594639D01*
X1595912Y1140075D01*
X1597369D01*
G01X1605369Y1140038D02*
X1606530D01*
X1607302Y1139266D01*
X1609856D01*
X1610253Y1138869D01*
Y1137260D01*
X1610910Y1136603D01*
X1613847D01*
X1615499Y1138255D01*
X1617533D01*
G01X1557807Y1120310D02*
X1572809Y1135312D01*
X1595205D01*
X1596363Y1136470D01*
X1597482D01*
X1599044Y1134908D01*
X1601391D01*
G01X1559588Y1118529D02*
X1573836Y1132777D01*
X1595821D01*
X1596380Y1133336D01*
X1597369D01*
G01X1605369Y1133288D02*
X1606579D01*
X1609163Y1131562D01*
X1617533D01*
G01X1546356Y1139722D02*
X1571914Y1165280D01*
Y1165281D01*
X1586532D01*
X1595519Y1156294D01*
X1597828D01*
X1599135Y1154987D01*
X1601391D01*
G01X1547644Y1137440D02*
X1571028Y1160824D01*
X1571983Y1161464D01*
X1574249Y1162406D01*
X1575767Y1162708D01*
X1582743D01*
X1585314Y1161645D01*
X1586402Y1160918D01*
X1587487Y1160193D01*
X1592214Y1155466D01*
X1593744Y1153175D01*
X1593971Y1152627D01*
X1594490Y1152108D01*
X1595111D01*
X1596367Y1153364D01*
X1597369D01*
G01X1605369Y1153339D02*
X1606623D01*
X1607677Y1152285D01*
X1609460D01*
X1613400Y1153918D01*
X1614472D01*
X1615541Y1154987D01*
X1617533D01*
G01X1548557Y1136527D02*
X1571854Y1159824D01*
X1572596Y1160321D01*
X1574627Y1161165D01*
X1575895Y1161418D01*
X1582486D01*
X1584703Y1160501D01*
X1586664Y1159190D01*
X1591211Y1154643D01*
X1592600Y1152565D01*
X1592876Y1151896D01*
X1593955Y1150817D01*
X1595443D01*
X1596346Y1149914D01*
X1597369D01*
G01X1605369Y1149884D02*
X1606647D01*
X1607758Y1150995D01*
X1609717D01*
X1613657Y1152628D01*
X1614558D01*
X1615545Y1151641D01*
X1617533D01*
G01X1510453Y1052047D02*
Y1054157D01*
G01X1541839Y1151679D02*
X1572754Y1182573D01*
X1576097D01*
X1576887Y1183363D01*
Y1184982D01*
X1577677Y1185772D01*
X1578797D01*
X1579587Y1184982D01*
Y1183363D01*
X1580377Y1182573D01*
X1581497D01*
X1582287Y1183363D01*
Y1184982D01*
X1583077Y1185772D01*
X1584197D01*
X1584987Y1184982D01*
Y1183363D01*
X1585777Y1182573D01*
X1586897D01*
X1587687Y1183363D01*
Y1184982D01*
X1588477Y1185772D01*
X1589597D01*
X1590387Y1184982D01*
Y1183363D01*
X1591177Y1182573D01*
X1592532D01*
X1593858Y1181247D01*
Y1174587D01*
X1595149Y1173296D01*
X1596590D01*
X1598167Y1171719D01*
X1601391D01*
G01X1545585Y1148133D02*
X1574989Y1177537D01*
X1582198D01*
X1582988Y1176747D01*
Y1172468D01*
X1583778Y1171678D01*
X1584898D01*
X1585688Y1172468D01*
Y1176747D01*
X1586478Y1177537D01*
X1588032D01*
X1588822Y1176747D01*
Y1171938D01*
X1593620Y1167140D01*
X1595210D01*
X1596061Y1166289D01*
X1596822D01*
X1598085Y1165026D01*
X1601391D01*
G01X1543750Y1149968D02*
X1573837Y1180055D01*
X1589777D01*
X1591340Y1178492D01*
Y1172982D01*
X1593630Y1170692D01*
X1596742D01*
X1597369Y1170065D01*
G01X1605369Y1170189D02*
X1608990D01*
X1610806Y1168373D01*
X1617533D01*
G01X1547444Y1146274D02*
X1575682Y1174512D01*
X1578934D01*
X1579724Y1173722D01*
Y1172602D01*
X1578934Y1171812D01*
X1576997D01*
X1576207Y1171022D01*
Y1169902D01*
X1576997Y1169112D01*
X1588087D01*
X1593434Y1163765D01*
X1597110D01*
X1597369Y1163506D01*
G01X1605369Y1163353D02*
X1607031D01*
X1608704Y1161680D01*
X1617533D01*
G01X1540454Y1158790D02*
X1573528Y1191864D01*
X1583600D01*
X1584390Y1192654D01*
Y1194320D01*
X1585180Y1195110D01*
X1590707D01*
X1591684Y1196087D01*
Y1198541D01*
X1590750Y1199475D01*
X1587178D01*
X1586388Y1200265D01*
Y1201385D01*
X1587178Y1202175D01*
X1590894D01*
X1591684Y1202965D01*
Y1211768D01*
X1595139Y1215223D01*
X1601391D01*
G01X1540821Y1155596D02*
X1574571Y1189346D01*
X1587084D01*
X1588887Y1191149D01*
X1590207D01*
X1591491Y1189865D01*
X1593392D01*
X1594308Y1190781D01*
Y1210804D01*
X1595073Y1211569D01*
X1595603Y1212849D01*
X1596330Y1213576D01*
X1597369D01*
G01X1605369D02*
X1607524D01*
X1609223Y1211877D01*
X1617533D01*
G01X1510453Y1071273D02*
Y1073383D01*
G01X1545512Y1140704D02*
X1571379Y1166571D01*
X1587067D01*
X1596054Y1157584D01*
X1598307D01*
X1599041Y1158324D01*
X1601391Y1158333D01*
G01X1527813Y1170582D02*
Y1175248D01*
X1532918Y1180353D01*
Y1181651D01*
X1534179Y1182912D01*
X1535477D01*
X1536738Y1184173D01*
Y1185471D01*
X1537999Y1186732D01*
X1539297D01*
X1540558Y1187993D01*
Y1189291D01*
X1541819Y1190552D01*
X1543117D01*
X1544378Y1191813D01*
Y1193111D01*
X1545639Y1194372D01*
X1546937D01*
X1548198Y1195633D01*
Y1196931D01*
X1549459Y1198192D01*
X1550757D01*
X1552018Y1199453D01*
Y1200751D01*
X1553279Y1202012D01*
X1554577D01*
X1555838Y1203273D01*
Y1204571D01*
X1557099Y1205832D01*
X1558397D01*
X1559658Y1207093D01*
Y1208391D01*
X1560919Y1209652D01*
X1562217D01*
X1563478Y1210913D01*
Y1212211D01*
X1564739Y1213472D01*
X1566037D01*
X1567298Y1214733D01*
Y1216031D01*
X1568559Y1217292D01*
X1569857D01*
X1571118Y1218553D01*
Y1219707D01*
X1572523Y1221112D01*
X1573677D01*
X1574938Y1222373D01*
Y1223353D01*
X1576517Y1224932D01*
X1577497D01*
X1578758Y1226193D01*
Y1227129D01*
X1580381Y1228752D01*
X1581317D01*
X1582578Y1230013D01*
Y1231093D01*
X1584057Y1232572D01*
X1585137D01*
X1589449Y1236884D01*
X1592692Y1239051D01*
X1594994Y1240004D01*
X1595384Y1240166D01*
X1596612D01*
X1598130Y1238648D01*
X1601391D01*
G01X1530335Y1170582D02*
Y1173965D01*
X1587745Y1231375D01*
X1591582Y1234524D01*
X1594994Y1236805D01*
X1595561Y1237040D01*
X1597369D01*
G01X1605369Y1237011D02*
X1609041D01*
X1610750Y1235302D01*
X1617533D01*
G01X1538101Y1163624D02*
X1571839Y1197362D01*
Y1199278D01*
X1572629Y1200068D01*
X1573749D01*
X1574539Y1199278D01*
Y1197690D01*
X1575329Y1196900D01*
X1577996D01*
X1579058Y1197962D01*
Y1199388D01*
X1576112Y1202334D01*
Y1203452D01*
X1576904Y1204244D01*
X1578022D01*
X1579106Y1203160D01*
X1580282D01*
X1581074Y1203952D01*
Y1205070D01*
X1579961Y1206183D01*
Y1207301D01*
X1591104Y1218444D01*
X1591874Y1219076D01*
X1594994Y1221160D01*
X1596822Y1221916D01*
X1601391D01*
G01X1538672Y1160572D02*
X1572482Y1194382D01*
X1579770D01*
X1583616Y1198228D01*
Y1204062D01*
X1584406Y1204852D01*
X1587440D01*
X1588062Y1205474D01*
Y1206855D01*
X1587173Y1207744D01*
Y1210865D01*
X1593252Y1216944D01*
X1594358Y1217684D01*
X1594994Y1217622D01*
X1595471Y1217575D01*
X1596173Y1216873D01*
X1597593D01*
G01X1605193Y1216876D02*
X1606673D01*
X1608367Y1218570D01*
X1617533D01*
G01X1533558Y1168060D02*
X1534878Y1169380D01*
X1551030Y1189059D01*
X1577987Y1216016D01*
X1578679D01*
X1580356Y1217693D01*
Y1218386D01*
X1582031Y1220061D01*
X1582724D01*
X1584401Y1221738D01*
Y1222430D01*
X1586039Y1224068D01*
X1592657Y1228489D01*
X1594921Y1229513D01*
X1598154D01*
X1599058Y1228609D01*
X1601391D01*
G01X1535354Y1166266D02*
X1536866Y1167779D01*
X1547097Y1180234D01*
X1585967Y1219036D01*
X1587705Y1220607D01*
X1591825Y1223983D01*
X1594356Y1225858D01*
X1595221D01*
X1596325Y1226962D01*
X1597369D01*
G01X1605369Y1226956D02*
X1605372Y1226959D01*
X1606585D01*
X1607496Y1226048D01*
X1608321D01*
X1613686Y1227677D01*
X1614609D01*
X1615541Y1228609D01*
X1617533D01*
G01X1532645Y1168973D02*
X1533920Y1170248D01*
X1550072Y1189927D01*
X1585216Y1225071D01*
X1592029Y1229621D01*
X1594642Y1230803D01*
X1597978D01*
X1599130Y1231955D01*
X1601391D01*
G01X1536266Y1165353D02*
X1537824Y1166911D01*
X1548054Y1179365D01*
X1549410Y1180719D01*
X1550103D01*
X1551782Y1182394D01*
Y1183087D01*
X1553459Y1184761D01*
X1554152Y1184760D01*
X1555831Y1186435D01*
Y1187128D01*
X1557508Y1188802D01*
X1558201D01*
X1559880Y1190477D01*
Y1191170D01*
X1561557Y1192844D01*
X1562250D01*
X1563929Y1194519D01*
Y1195212D01*
X1565606Y1196886D01*
X1566299Y1196885D01*
X1567977Y1198561D01*
X1567978Y1199254D01*
X1586857Y1218100D01*
X1588547Y1219629D01*
X1592618Y1222965D01*
X1594782Y1224568D01*
X1595320D01*
X1596319Y1223569D01*
X1597369D01*
G01X1605369Y1223568D02*
X1606549D01*
X1607739Y1224758D01*
X1608513D01*
X1613878Y1226387D01*
X1614367D01*
X1615491Y1225263D01*
X1617533D01*
G01X1510453Y1090498D02*
Y1092607D01*
X1510452Y1092608D01*
G01X1522700Y1169393D02*
X1522241Y1169852D01*
Y1180828D01*
X1582766Y1241353D01*
X1585341Y1242420D01*
X1585768Y1243451D01*
X1585391Y1244361D01*
X1585818Y1245392D01*
X1586855Y1245822D01*
X1587886Y1245395D01*
X1588263Y1244485D01*
X1589294Y1244058D01*
X1593780Y1245916D01*
X1597234D01*
X1597809Y1245341D01*
X1601391D01*
G01X1525287Y1170582D02*
Y1175783D01*
X1526568Y1178875D01*
X1585245Y1237552D01*
X1592201Y1242197D01*
X1594994Y1243354D01*
X1595809Y1243691D01*
X1597369D01*
G01X1605369Y1243707D02*
X1606871D01*
X1611598Y1241749D01*
X1613983D01*
X1614229Y1241995D01*
X1617533D01*
G01X1631091Y780184D02*
X1624911D01*
X1623175Y778448D01*
X1621511D01*
G01X1613511Y778469D02*
X1612119D01*
X1611329Y779259D01*
Y780276D01*
X1610538Y781067D01*
X1609473D01*
X1608590Y780184D01*
X1601391D01*
G01X1631091Y773491D02*
X1624911D01*
X1623175Y771755D01*
X1621511D01*
G01X1613511Y771776D02*
X1611758D01*
X1610968Y772566D01*
Y773730D01*
X1610324Y774374D01*
X1609473D01*
X1608590Y773491D01*
X1601391D01*
G01X1631091Y786877D02*
X1628771D01*
X1627824Y787824D01*
X1626515D01*
X1624702Y789637D01*
X1623895D01*
X1622776Y788518D01*
X1621511D01*
G01X1613511Y788498D02*
X1612311D01*
X1611191Y789618D01*
X1610528D01*
X1606587Y787986D01*
X1604660D01*
X1603551Y786877D01*
X1601391D01*
G01X1631091Y796916D02*
X1624531D01*
X1622795Y795180D01*
X1621511D01*
G01X1613511Y795201D02*
X1610606D01*
X1610012Y795795D01*
Y797168D01*
X1609381Y797799D01*
X1604593D01*
X1603710Y796916D01*
X1601391D01*
G01X1631091Y790223D02*
X1628931D01*
X1627822Y789114D01*
X1627050D01*
X1625237Y790927D01*
X1623782D01*
X1622772Y791937D01*
X1621511D01*
G01X1613511Y791972D02*
X1612418D01*
X1611354Y790908D01*
X1610271D01*
X1606330Y789276D01*
X1604658D01*
X1603711Y790223D01*
X1601391D01*
G01X1631091Y816995D02*
X1625349D01*
X1623612Y815258D01*
X1621511D01*
G01X1613511Y815279D02*
X1611702D01*
X1610968Y816013D01*
Y817234D01*
X1610324Y817878D01*
X1609473D01*
X1608590Y816995D01*
X1601391D01*
G01X1631091Y810302D02*
X1625399D01*
X1625398Y810303D01*
X1623660Y808565D01*
X1621511D01*
G01X1613511Y808586D02*
X1611150D01*
X1610416Y809320D01*
Y810541D01*
X1609772Y811185D01*
X1608921D01*
X1608038Y810302D01*
X1601391D01*
G01X1631091Y803609D02*
X1624531D01*
X1622795Y801873D01*
X1621511D01*
G01X1613511Y801894D02*
X1610606D01*
X1610012Y802488D01*
Y803637D01*
X1609157Y804492D01*
X1604593D01*
X1603710Y803609D01*
X1601391D01*
G01X1631091Y833727D02*
X1627857D01*
X1627119Y834465D01*
X1625649D01*
X1623180Y831996D01*
X1621511D01*
G01X1613511Y831993D02*
X1611853D01*
X1610417Y833429D01*
X1607525D01*
X1605728Y835226D01*
X1605001D01*
X1603502Y833727D01*
X1601391D01*
G01X1631091Y823688D02*
X1629199D01*
X1628252Y824635D01*
X1626863D01*
X1625139Y826359D01*
X1623778D01*
X1622739Y825320D01*
X1621511D01*
G01X1613511Y825246D02*
X1612368D01*
X1611345Y826269D01*
X1610274D01*
X1609034Y825755D01*
X1608076Y824797D01*
X1604660D01*
X1603551Y823688D01*
X1601391D01*
G01X1631091Y827034D02*
X1629349D01*
X1628240Y825925D01*
X1627398D01*
X1625674Y827649D01*
X1623753D01*
X1622619Y828783D01*
X1621511D01*
G01X1613511Y828770D02*
X1612433D01*
X1611222Y827559D01*
X1610016D01*
X1608303Y826849D01*
X1607541Y826087D01*
X1604658D01*
X1603711Y827034D01*
X1601391D01*
G01X1631091Y847113D02*
X1624911D01*
X1623215Y845417D01*
X1621514D01*
X1621511Y845420D01*
G01X1613511Y845379D02*
X1611758D01*
X1610968Y846169D01*
Y847352D01*
X1610324Y847996D01*
X1608359D01*
X1607476Y847113D01*
X1601391D01*
G01X1631091Y840420D02*
X1624913D01*
X1624912Y840421D01*
X1623180Y838689D01*
X1621511D01*
G01X1613511Y838695D02*
X1611758D01*
X1610968Y839485D01*
Y839989D01*
X1609271Y841686D01*
X1605894D01*
X1604628Y840420D01*
X1601391D01*
G01X1631091Y853806D02*
X1625359D01*
X1623618Y852065D01*
X1621511D01*
G01X1613511Y852079D02*
X1611375D01*
X1610584Y852870D01*
Y854037D01*
X1609913Y854708D01*
X1609062D01*
X1608160Y853806D01*
X1601391D01*
G01X1631091Y860499D02*
X1628771D01*
X1627824Y861446D01*
X1626515D01*
X1624960Y863001D01*
X1623841D01*
X1622946Y862106D01*
X1621511D01*
G01X1613511Y862066D02*
X1611791D01*
X1610617Y863240D01*
X1608941D01*
X1607309Y861608D01*
X1604660D01*
X1603551Y860499D01*
X1601391D01*
G01X1631091Y863845D02*
X1628931D01*
X1627822Y862736D01*
X1627050D01*
X1625495Y864291D01*
X1624116D01*
X1622824Y865583D01*
X1621511D01*
G01X1613511Y865570D02*
X1611612D01*
X1610572Y864530D01*
X1608406D01*
X1606774Y862898D01*
X1604658D01*
X1603711Y863845D01*
X1601391D01*
G01X1596941Y883924D02*
X1601391D01*
G01D02*
X1607378D01*
X1608357Y884903D01*
X1610228D01*
X1610968Y884163D01*
Y882716D01*
X1611433Y882251D01*
X1612790D01*
G01X1621511Y882226D02*
X1623125D01*
X1624824Y883925D01*
X1631090D01*
X1631091Y883924D01*
G01Y877231D02*
X1624913D01*
X1624887Y877257D01*
X1623130Y875500D01*
X1621511D01*
G01X1613511Y875520D02*
X1610718D01*
X1610125Y876113D01*
Y877372D01*
X1609257Y878240D01*
X1607602D01*
X1606593Y877231D01*
X1601391D01*
G01X1631091Y870538D02*
X1624325D01*
X1622594Y868807D01*
X1621511D01*
G01X1613511Y868831D02*
X1610714D01*
X1610125Y869420D01*
Y870679D01*
X1609257Y871547D01*
X1606100D01*
X1605091Y870538D01*
X1601391D01*
G01X1596941Y890617D02*
X1601391D01*
G01D02*
X1607378D01*
X1608357Y891596D01*
X1610228D01*
X1610968Y890856D01*
Y889409D01*
X1611433Y888944D01*
X1612790D01*
G01X1621511Y888919D02*
X1623125D01*
X1624824Y890618D01*
X1631090D01*
X1631091Y890617D01*
G01Y897310D02*
X1628771D01*
X1627794Y898287D01*
X1626459D01*
X1624652Y900094D01*
X1623751D01*
X1622545Y898888D01*
X1621511D01*
G01X1612741Y898983D02*
X1612311D01*
X1611243Y900051D01*
X1609064D01*
X1607432Y898419D01*
X1604660D01*
X1603551Y897310D01*
X1601391D01*
G01D02*
X1596941D01*
G01X1631091Y900656D02*
X1628931D01*
X1627852Y899577D01*
X1626994D01*
X1625187Y901384D01*
X1623754D01*
X1622734Y902404D01*
X1621511D01*
G01X1612764Y902330D02*
X1612343D01*
X1611354Y901341D01*
X1608529D01*
X1606897Y899709D01*
X1604658D01*
X1603711Y900656D01*
X1601391D01*
G01D02*
X1596941D01*
G01Y914042D02*
X1601391D01*
G01D02*
X1607378D01*
X1608223Y914887D01*
X1610228D01*
X1610968Y914147D01*
Y912834D01*
X1611433Y912369D01*
X1612790D01*
G01X1622336D02*
X1623150D01*
X1624824Y914043D01*
X1631090D01*
X1631091Y914042D01*
G01X1596941Y907349D02*
X1601391D01*
G01D02*
X1607378D01*
X1608357Y908328D01*
X1610228D01*
X1610968Y907588D01*
Y906141D01*
X1611433Y905676D01*
X1612790D01*
G01X1621511Y905651D02*
X1623125D01*
X1624824Y907350D01*
X1631090D01*
X1631091Y907349D01*
G01Y927428D02*
X1625242D01*
X1623569Y925755D01*
X1622744D01*
G01X1611786Y925654D02*
X1611368D01*
X1609580Y927442D01*
X1608462D01*
X1606823Y925803D01*
X1605202D01*
X1603577Y927428D01*
X1601391D01*
G01X1631091Y920735D02*
X1627353D01*
X1627010Y921078D01*
X1625593D01*
X1623508Y918993D01*
X1622153D01*
G01X1612836Y919010D02*
X1611428D01*
X1610638Y919800D01*
Y920976D01*
X1609855Y921759D01*
X1608737D01*
X1607714Y920736D01*
X1601392D01*
X1601391Y920735D01*
G01X1631091Y944160D02*
X1624544D01*
X1622798Y942414D01*
X1622272D01*
G01X1612837Y942412D02*
X1612200D01*
X1610151Y944461D01*
X1608766D01*
X1608266Y943961D01*
Y943320D01*
X1607566Y942620D01*
X1606066D01*
X1604525Y944161D01*
X1601392D01*
X1601391Y944160D01*
G01Y934121D02*
X1603551D01*
X1604660Y935230D01*
X1608096D01*
X1609677Y936811D01*
X1610526D01*
X1611609Y935728D01*
X1611920D01*
G01X1623144Y935794D02*
X1623664D01*
X1624451Y936581D01*
X1625690D01*
X1626950Y935321D01*
X1627855D01*
X1629055Y934121D01*
X1631091D01*
G01Y937467D02*
X1629459D01*
X1628603Y936611D01*
X1627485D01*
X1626225Y937871D01*
X1624848D01*
X1623578Y939141D01*
X1623144D01*
G01X1611920Y939217D02*
X1611469D01*
X1610353Y938101D01*
X1609142D01*
X1607561Y936520D01*
X1604658D01*
X1603711Y937467D01*
X1601391D01*
G01Y960892D02*
X1596941D01*
G01X1631091Y950853D02*
X1627464D01*
X1626993Y951324D01*
X1625495D01*
X1624705Y950534D01*
Y949884D01*
X1623915Y949094D01*
X1621963D01*
G01X1612697Y949180D02*
X1612094D01*
X1610873Y950401D01*
X1609754D01*
X1608619Y949266D01*
X1607501D01*
X1605913Y950854D01*
X1601392D01*
X1601391Y950853D01*
G01Y957546D02*
X1596941D01*
G01X1631091Y980971D02*
X1627647D01*
X1625898Y982720D01*
X1621511D01*
G01X1613511Y982728D02*
X1612332D01*
X1611245Y981641D01*
X1609542D01*
X1609172Y982011D01*
Y982478D01*
X1608582Y983068D01*
X1607234D01*
X1605137Y980971D01*
X1601391D01*
G01X1631091Y974278D02*
X1627519D01*
X1625037Y976760D01*
X1623919D01*
X1623148Y975989D01*
X1621511D01*
G01X1613511Y976007D02*
X1611583D01*
X1609992Y977598D01*
X1608601D01*
X1606794Y975791D01*
X1604831D01*
X1603318Y974278D01*
X1601391D01*
G01X1631091Y994357D02*
X1624432D01*
X1622759Y992684D01*
X1621511D01*
G01X1613511Y993441D02*
X1613011Y993941D01*
Y994819D01*
X1611411Y996419D01*
X1605639D01*
X1603577Y994357D01*
X1601391D01*
G01X1631091Y987664D02*
X1625731D01*
X1624004Y989391D01*
X1621511D01*
G01X1613511Y989389D02*
X1611435D01*
X1610256Y990568D01*
X1608603D01*
X1607962Y989927D01*
Y989068D01*
X1606558Y987664D01*
X1601391D01*
G01X1631091Y1027822D02*
X1625827D01*
X1624089Y1029560D01*
X1621511D01*
G01X1613511Y1029648D02*
X1612363D01*
X1611209Y1028494D01*
Y1026525D01*
X1610038Y1025354D01*
X1607751D01*
X1606936Y1026169D01*
X1605060D01*
X1603407Y1027822D01*
X1601391D01*
G01X1631091Y1021129D02*
X1625935D01*
X1621370Y1025694D01*
G01X1613695D02*
X1613507Y1025506D01*
X1612597D01*
X1608220Y1021129D01*
X1601391D01*
G01X1631091Y1047900D02*
X1627562D01*
X1626596Y1048866D01*
X1625590D01*
X1624894Y1048170D01*
X1624010D01*
X1622561Y1049619D01*
X1621511D01*
G01X1613511Y1049636D02*
X1612389D01*
X1611897Y1049144D01*
X1610508D01*
X1610162Y1048798D01*
Y1047549D01*
X1609732Y1047119D01*
X1604323D01*
X1603542Y1047900D01*
X1601391D01*
G01X1631091Y1041207D02*
X1626669D01*
X1624957Y1042919D01*
X1621511D01*
G01X1613511Y1042947D02*
X1612323D01*
X1608933Y1039557D01*
X1605337D01*
X1603687Y1041207D01*
X1601391D01*
G01Y1034515D02*
X1603543D01*
X1605112Y1032946D01*
X1606454D01*
X1607632Y1034124D01*
X1610291D01*
X1612442Y1036275D01*
X1613511D01*
G01X1621511Y1036304D02*
X1625069D01*
X1626379Y1034994D01*
X1630612D01*
X1631091Y1034515D01*
G01Y1061286D02*
X1628766D01*
X1627170Y1062882D01*
X1625808D01*
X1624058Y1061132D01*
Y1060482D01*
X1623189Y1059613D01*
X1622215D01*
G01X1612790D02*
X1612069D01*
X1610781Y1058325D01*
X1608083D01*
X1605122Y1061286D01*
X1601391D01*
G01D02*
X1597041D01*
G01X1631091Y1074672D02*
X1625426D01*
X1623753Y1072999D01*
X1623036D01*
G01X1611917D02*
X1611495D01*
X1610573Y1073921D01*
Y1074703D01*
X1609782Y1075494D01*
X1608528D01*
X1607231Y1074197D01*
X1605771D01*
X1605296Y1074672D01*
X1601391D01*
G01X1631091Y1067979D02*
X1624894D01*
X1623221Y1066306D01*
X1622215D01*
G01X1612406Y1065991D02*
X1610717Y1064302D01*
X1609894D01*
X1609477Y1064719D01*
Y1067289D01*
X1608787Y1067979D01*
X1601391D01*
G01X1631091Y1091404D02*
X1624312D01*
X1622639Y1089731D01*
X1622215D01*
G01X1612406D02*
X1611963D01*
X1611406Y1090288D01*
Y1091652D01*
X1610616Y1092442D01*
X1609335D01*
X1607723Y1090830D01*
X1606604D01*
X1606029Y1091405D01*
X1601392D01*
X1601391Y1091404D01*
G01X1631091Y1081365D02*
X1628931D01*
X1627984Y1082312D01*
X1626515D01*
X1624899Y1083928D01*
X1623698D01*
X1622758Y1082988D01*
X1622116D01*
G01X1612081Y1082976D02*
X1611091D01*
X1610033Y1084034D01*
X1608740D01*
X1607180Y1082474D01*
X1604660D01*
X1603551Y1081365D01*
X1601391D01*
G01X1631091Y1084711D02*
X1628875D01*
X1627794Y1083630D01*
X1627022D01*
X1625434Y1085218D01*
X1623975D01*
X1622727Y1086466D01*
X1622116D01*
G01X1612102Y1086429D02*
X1611149D01*
X1610044Y1085324D01*
X1608205D01*
X1606645Y1083764D01*
X1604658D01*
X1603711Y1084711D01*
X1601391D01*
G01X1631091Y1098097D02*
X1626356D01*
X1625653Y1098800D01*
X1624425D01*
X1623634Y1098009D01*
Y1096812D01*
X1622844Y1096022D01*
X1622215D01*
G01X1612406Y1096424D02*
X1611472D01*
X1611217Y1096169D01*
X1607915D01*
X1605986Y1098098D01*
X1601392D01*
X1601391Y1098097D01*
G01X1631091Y1111483D02*
X1624861D01*
X1623112Y1109734D01*
X1621511D01*
G01X1613511Y1109773D02*
X1612291D01*
X1611464Y1110600D01*
Y1111905D01*
X1610773Y1112596D01*
X1609450D01*
X1608337Y1111483D01*
X1601391D01*
G01X1631091Y1104790D02*
X1624324D01*
X1622612Y1106502D01*
X1621511D01*
G01X1613511Y1106534D02*
X1612208D01*
X1610128Y1104454D01*
X1608530D01*
X1606563Y1106421D01*
X1605037D01*
X1603406Y1104790D01*
X1601391D01*
G01X1631091Y1128215D02*
X1624507D01*
X1622767Y1126475D01*
X1621511D01*
G01X1613511Y1126498D02*
X1611758D01*
X1610968Y1127288D01*
Y1128454D01*
X1610324Y1129098D01*
X1605897D01*
X1605014Y1128215D01*
X1601391D01*
G01X1631091Y1118176D02*
X1628931D01*
X1627984Y1119123D01*
X1626515D01*
X1624899Y1120739D01*
X1623698D01*
X1622782Y1119823D01*
X1621511D01*
G01X1613511Y1119787D02*
X1612373D01*
X1611243Y1120917D01*
X1609552D01*
X1607920Y1119285D01*
X1604660D01*
X1603551Y1118176D01*
X1601391D01*
G01X1631091Y1121522D02*
X1628931D01*
X1627822Y1120413D01*
X1627050D01*
X1625434Y1122029D01*
X1623975D01*
X1622735Y1123269D01*
X1621511D01*
G01X1613511Y1123242D02*
X1612389D01*
X1611354Y1122207D01*
X1609017D01*
X1607385Y1120575D01*
X1604658D01*
X1603711Y1121522D01*
X1601391D01*
G01X1631091Y1141601D02*
X1627503D01*
X1626998Y1142106D01*
X1625410D01*
X1623196Y1139892D01*
X1621512D01*
X1621511Y1139893D01*
G01X1613511Y1139902D02*
X1611995D01*
X1611469Y1140428D01*
Y1141101D01*
X1610969Y1141601D01*
X1606938D01*
X1605845Y1142694D01*
X1604398D01*
X1603305Y1141601D01*
X1601391D01*
G01X1631091Y1134908D02*
X1627452D01*
X1626592Y1135768D01*
X1625065D01*
X1624655Y1135358D01*
Y1134056D01*
X1623863Y1133264D01*
X1621511D01*
G01X1613511Y1133201D02*
X1610751D01*
X1607788Y1136164D01*
X1606288D01*
X1605032Y1134908D01*
X1601391D01*
G01X1631091Y1148294D02*
X1624455D01*
X1622758Y1146597D01*
X1621519D01*
X1621511Y1146605D01*
G01X1613511Y1146589D02*
X1611998D01*
X1611406Y1147181D01*
Y1148677D01*
X1610764Y1149319D01*
X1609645D01*
X1608620Y1148294D01*
X1601391D01*
G01X1631091Y1154987D02*
X1628931D01*
X1627984Y1155934D01*
X1626515D01*
X1624899Y1157550D01*
X1623698D01*
X1622782Y1156634D01*
X1621511D01*
G01X1613511Y1156598D02*
X1612373D01*
X1611243Y1157728D01*
X1609552D01*
X1607920Y1156096D01*
X1604660D01*
X1603551Y1154987D01*
X1601391D01*
G01X1631091Y1158333D02*
X1628931D01*
X1627822Y1157224D01*
X1627050D01*
X1625434Y1158840D01*
X1623975D01*
X1622735Y1160080D01*
X1621511D01*
G01X1613511Y1160053D02*
X1612389D01*
X1611354Y1159018D01*
X1609017D01*
X1607385Y1157386D01*
X1604658D01*
X1603711Y1158333D01*
X1601391D01*
G01X1631091Y1171719D02*
X1624677D01*
X1622959Y1170001D01*
X1621511D01*
G01X1613511Y1170017D02*
X1611796D01*
X1610968Y1170845D01*
Y1171958D01*
X1610228Y1172698D01*
X1605659D01*
X1604680Y1171719D01*
X1601391D01*
G01X1631091Y1165026D02*
X1624519D01*
X1622801Y1163308D01*
X1621511D01*
G01X1613511Y1163324D02*
X1611949D01*
X1611138Y1164135D01*
Y1165976D01*
X1610700Y1166414D01*
X1610103D01*
X1608616Y1167901D01*
X1607725D01*
X1604850Y1165026D01*
X1601391D01*
G01X1596941Y1185105D02*
X1601391D01*
G01D02*
X1607378D01*
X1608357Y1186084D01*
X1610228D01*
X1610968Y1185344D01*
Y1183897D01*
X1611433Y1183432D01*
X1612790D01*
G01X1621511Y1183407D02*
X1623125D01*
X1624824Y1185106D01*
X1631090D01*
X1631091Y1185105D01*
G01X1596941Y1178412D02*
X1601391D01*
G01D02*
X1607378D01*
X1608357Y1179391D01*
X1610228D01*
X1610968Y1178651D01*
Y1177204D01*
X1611433Y1176739D01*
X1612790D01*
G01X1621511Y1176714D02*
X1623125D01*
X1624824Y1178413D01*
X1631090D01*
X1631091Y1178412D01*
G01Y1191798D02*
X1628771D01*
X1627786Y1192783D01*
X1626597D01*
X1625019Y1194361D01*
X1623698D01*
X1622743Y1193406D01*
X1621511D01*
G01X1612732Y1193471D02*
X1612311D01*
X1611243Y1194539D01*
X1609285D01*
X1607653Y1192907D01*
X1604660D01*
X1603551Y1191798D01*
X1601391D01*
G01D02*
X1596941D01*
G01X1631091Y1208530D02*
X1627675D01*
X1627000Y1209205D01*
X1625260D01*
X1622874Y1206819D01*
X1621511D01*
G01X1612529Y1206857D02*
X1611603D01*
X1610381Y1205635D01*
X1608529D01*
X1607433Y1206731D01*
Y1207264D01*
X1606167Y1208530D01*
X1601391D01*
G01D02*
X1596941D01*
G01X1631091Y1201837D02*
X1624615D01*
X1622907Y1200129D01*
X1621511D01*
G01X1612798Y1200164D02*
X1611571D01*
X1610968Y1200767D01*
Y1202732D01*
X1610134Y1203566D01*
X1608477D01*
X1606748Y1201837D01*
X1601391D01*
G01D02*
X1596941D01*
G01X1631091Y1195144D02*
X1628931D01*
X1627860Y1194073D01*
X1627132D01*
X1625554Y1195651D01*
X1623773D01*
X1622561Y1196863D01*
X1621511D01*
G01X1612732Y1196818D02*
X1612343D01*
X1611354Y1195829D01*
X1608750D01*
X1607118Y1194197D01*
X1604658D01*
X1603711Y1195144D01*
X1601391D01*
G01D02*
X1596941D01*
G01X1631091Y1221916D02*
X1625221D01*
X1623510Y1220205D01*
X1621511D01*
G01X1613511Y1220200D02*
X1610768D01*
X1610207Y1220761D01*
Y1222122D01*
X1609563Y1222766D01*
X1608702D01*
X1607400Y1221464D01*
X1605052D01*
X1604600Y1221916D01*
X1601391D01*
G01X1631091Y1215223D02*
X1627681D01*
X1626829Y1216075D01*
X1625443D01*
X1622896Y1213528D01*
X1621511D01*
G01X1613511D02*
X1611702D01*
X1610968Y1214262D01*
Y1215288D01*
X1610178Y1216078D01*
X1608693D01*
X1607838Y1215223D01*
X1601391D01*
G01X1631091Y1238648D02*
X1624347D01*
X1622635Y1236936D01*
X1621511D01*
G01X1613511Y1236940D02*
X1611758D01*
X1610968Y1237730D01*
Y1239179D01*
X1610177Y1239970D01*
X1606144D01*
X1604822Y1238648D01*
X1601391D01*
G01X1631091Y1228609D02*
X1629071D01*
X1628124Y1229556D01*
X1626863D01*
X1625139Y1231280D01*
X1624434D01*
X1623413Y1230259D01*
X1621511D01*
G01X1613511Y1230167D02*
X1611330D01*
X1610147Y1231350D01*
X1607970D01*
X1606338Y1229718D01*
X1604660D01*
X1603551Y1228609D01*
X1601391D01*
G01X1631091Y1231955D02*
X1629349D01*
X1628240Y1230846D01*
X1627398D01*
X1625674Y1232570D01*
X1624557D01*
X1623476Y1233651D01*
X1621514D01*
X1621511Y1233648D01*
G01X1613511Y1233629D02*
X1611463D01*
X1610474Y1232640D01*
X1607435D01*
X1605803Y1231008D01*
X1604658D01*
X1603711Y1231955D01*
X1601391D01*
G01X1631091Y1245341D02*
X1624765D01*
X1623054Y1243630D01*
X1621511D01*
G01X1613511Y1243521D02*
X1611845D01*
X1611041Y1244325D01*
Y1245447D01*
X1610037Y1246451D01*
X1604784D01*
X1603674Y1245341D01*
X1601391D01*
G01X1647233Y770144D02*
X1642030D01*
X1641038Y769152D01*
X1639526D01*
X1638604Y770074D01*
Y771108D01*
X1637832Y771880D01*
X1635069D01*
G01X1627069Y771859D02*
X1625908D01*
X1624193Y770144D01*
X1617533D01*
G01X1647233Y776837D02*
X1642030D01*
X1641038Y775845D01*
X1639526D01*
X1638604Y776767D01*
Y777783D01*
X1637814Y778573D01*
X1635069D01*
G01X1627069Y778552D02*
X1625908D01*
X1624193Y776837D01*
X1617533D01*
G01X1647233Y786877D02*
X1645250D01*
X1644249Y785876D01*
X1641132D01*
X1639378Y784122D01*
X1637449D01*
X1636324Y785247D01*
X1635069D01*
G01X1627069Y785228D02*
X1625840D01*
X1624748Y784136D01*
X1624266D01*
X1622593Y785809D01*
X1620690D01*
X1619622Y786877D01*
X1617533D01*
G01X1647233Y783530D02*
X1644997D01*
X1643941Y784586D01*
X1641667D01*
X1639913Y782832D01*
X1637340D01*
X1636336Y781828D01*
X1635069D01*
G01X1627069Y781829D02*
X1625844D01*
X1624827Y782846D01*
X1623731D01*
X1622058Y784519D01*
X1620502D01*
X1619513Y783530D01*
X1617533D01*
G01X1647233Y800263D02*
X1642030D01*
X1641038Y799271D01*
X1639526D01*
X1638604Y800193D01*
Y801208D01*
X1637813Y801999D01*
X1635069D01*
G01X1627069Y801978D02*
X1625908D01*
X1624193Y800263D01*
X1617533D01*
G01X1647233Y793570D02*
X1642030D01*
X1641038Y792578D01*
X1639526D01*
X1638604Y793500D01*
Y794515D01*
X1637813Y795306D01*
X1635069D01*
G01X1627069Y795285D02*
X1625908D01*
X1624193Y793570D01*
X1617533D01*
G01X1647233Y813648D02*
X1642030D01*
X1641038Y812656D01*
X1639526D01*
X1638604Y813578D01*
Y814594D01*
X1637814Y815384D01*
X1635069D01*
G01X1627069Y815363D02*
X1626018D01*
X1624303Y813648D01*
X1617533D01*
G01X1647233Y806955D02*
X1642030D01*
X1641038Y805963D01*
X1639526D01*
X1638604Y806885D01*
Y807901D01*
X1637814Y808691D01*
X1635069D01*
G01X1627069Y808670D02*
X1626040D01*
X1624325Y806955D01*
X1617533D01*
G01X1647233Y820341D02*
X1645268D01*
X1644213Y821396D01*
X1642521D01*
X1640767Y819642D01*
X1638080D01*
X1637080Y818642D01*
X1635069D01*
G01X1627069Y818588D02*
X1625869D01*
X1624887Y819570D01*
X1623133D01*
X1621374Y821329D01*
X1620562D01*
X1619574Y820341D01*
X1617533D01*
G01X1647233Y830381D02*
X1642030D01*
X1641038Y829389D01*
X1639390D01*
X1638604Y830175D01*
Y831344D01*
X1637831Y832117D01*
X1635069D01*
G01X1627069Y832096D02*
X1625908D01*
X1624193Y830381D01*
X1617533D01*
G01X1647233Y823688D02*
X1645393D01*
X1644391Y822686D01*
X1641986D01*
X1640232Y820932D01*
X1638153D01*
X1637032Y822053D01*
X1635069D01*
G01X1627069Y822037D02*
X1625955D01*
X1624778Y820860D01*
X1623668D01*
X1621909Y822619D01*
X1620470D01*
X1619401Y823688D01*
X1617533D01*
G01X1647233Y850459D02*
X1642030D01*
X1641038Y849467D01*
X1639526D01*
X1638604Y850389D01*
Y851396D01*
X1637814Y852186D01*
X1635069D01*
G01X1627069Y852197D02*
X1626079D01*
X1624341Y850459D01*
X1617533D01*
G01X1647233Y843766D02*
X1642030D01*
X1641038Y842774D01*
X1639526D01*
X1638604Y843696D01*
Y844712D01*
X1637814Y845502D01*
X1635069D01*
G01X1627069Y845481D02*
X1625908D01*
X1624193Y843766D01*
X1617533D01*
G01X1647233Y837074D02*
X1642030D01*
X1640677Y835721D01*
X1639394D01*
X1638604Y836511D01*
Y838019D01*
X1637813Y838810D01*
X1635069D01*
G01X1627069Y838789D02*
X1625908D01*
X1624193Y837074D01*
X1617533D01*
G01X1647233Y867192D02*
X1642030D01*
X1641038Y866200D01*
X1639526D01*
X1638604Y867122D01*
Y868256D01*
X1637921Y868939D01*
X1635069D01*
G01X1627069Y868922D02*
X1625011D01*
X1623281Y867192D01*
X1617533D01*
G01X1647233Y860499D02*
X1645250D01*
X1644249Y859498D01*
X1641132D01*
X1639378Y857744D01*
X1637449D01*
X1636324Y858869D01*
X1635069D01*
G01X1627069Y858850D02*
X1625840D01*
X1624748Y857758D01*
X1624266D01*
X1623445Y858579D01*
X1621388Y859431D01*
X1620690D01*
X1619622Y860499D01*
X1617533D01*
G01X1647233Y857152D02*
X1644997D01*
X1643941Y858208D01*
X1641667D01*
X1639913Y856454D01*
X1637340D01*
X1636336Y855450D01*
X1635069D01*
G01X1627069Y855451D02*
X1625844D01*
X1624827Y856468D01*
X1623731D01*
X1622714Y857485D01*
X1621131Y858141D01*
X1620518D01*
X1619529Y857152D01*
X1617533D01*
G01X1647233Y873885D02*
X1642030D01*
X1641038Y872893D01*
X1639526D01*
X1638604Y873815D01*
Y874949D01*
X1637921Y875632D01*
X1635069D01*
G01X1627069Y875615D02*
X1625755D01*
X1624025Y873885D01*
X1617533D01*
G01X1647233Y880577D02*
X1642030D01*
X1641038Y879585D01*
X1639526D01*
X1638604Y880507D01*
Y881641D01*
X1637921Y882324D01*
X1635069D01*
G01X1627069Y882307D02*
X1625787D01*
X1624057Y880577D01*
X1617533D01*
G01D02*
X1613083D01*
G01X1647233Y887270D02*
X1642030D01*
X1641038Y886278D01*
X1639526D01*
X1638604Y887200D01*
Y888334D01*
X1637921Y889017D01*
X1635069D01*
G01X1627069Y889000D02*
X1625647D01*
X1623917Y887270D01*
X1617533D01*
G01D02*
X1613083D01*
G01X1647233Y897310D02*
X1645250D01*
X1644249Y896309D01*
X1641132D01*
X1639378Y894555D01*
X1637449D01*
X1636324Y895680D01*
X1635069D01*
G01X1627069Y895661D02*
X1625840D01*
X1624748Y894569D01*
X1624266D01*
X1622593Y896242D01*
X1620690D01*
X1619622Y897310D01*
X1617533D01*
G01D02*
X1613083D01*
G01X1647233Y893963D02*
X1644997D01*
X1643941Y895019D01*
X1641667D01*
X1639913Y893265D01*
X1637340D01*
X1636336Y892261D01*
X1635069D01*
G01X1627069Y892262D02*
X1625844D01*
X1624827Y893279D01*
X1623731D01*
X1622058Y894952D01*
X1620858D01*
X1619869Y893963D01*
X1617533D01*
G01D02*
X1613083D01*
G01X1647233Y917389D02*
X1642904D01*
X1640936Y915421D01*
X1639535D01*
X1638607Y916349D01*
Y917059D01*
X1638614Y917066D01*
Y918284D01*
X1637836Y919062D01*
X1635939D01*
G01X1626268D02*
X1625874D01*
X1623905Y917093D01*
X1621272D01*
X1620975Y917390D01*
X1617534D01*
X1617533Y917389D01*
G01X1647233Y910696D02*
X1642030D01*
X1641038Y909704D01*
X1639526D01*
X1638604Y910626D01*
Y911648D01*
X1637832Y912420D01*
X1635069D01*
G01X1627069Y912428D02*
X1625925D01*
X1624193Y910696D01*
X1617533D01*
G01D02*
X1613083D01*
G01X1647233Y904003D02*
X1642030D01*
X1641038Y903011D01*
X1639526D01*
X1638604Y903933D01*
Y904995D01*
X1637832Y905767D01*
X1635069D01*
G01X1627069Y905731D02*
X1625921D01*
X1624193Y904003D01*
X1617533D01*
G01D02*
X1613083D01*
G01X1647233Y924081D02*
X1642210D01*
X1640968Y922839D01*
X1639701D01*
X1638911Y923629D01*
Y925031D01*
X1638121Y925821D01*
X1637003D01*
G01X1626369Y925810D02*
X1625873D01*
X1623789Y923726D01*
X1621640D01*
X1621283Y924083D01*
X1617535D01*
X1617533Y924081D01*
G01X1647233Y934121D02*
X1645250D01*
X1644197Y933068D01*
X1642144D01*
X1640442Y931366D01*
X1638313D01*
X1637188Y932491D01*
X1636636D01*
G01X1625395Y932472D02*
X1624988D01*
X1623901Y931385D01*
X1622991D01*
X1621323Y933053D01*
X1620020D01*
X1618952Y934121D01*
X1617533D01*
G01X1647233Y930774D02*
X1644997D01*
X1643993Y931778D01*
X1642679D01*
X1640977Y930076D01*
X1638342D01*
X1637338Y929072D01*
X1636636D01*
G01X1625395Y929101D02*
X1624956D01*
X1623962Y930095D01*
X1622456D01*
X1620788Y931763D01*
X1619972D01*
X1618983Y930774D01*
X1617533D01*
G01X1647233Y947507D02*
X1641787D01*
X1640991Y948303D01*
X1639755D01*
X1638965Y947513D01*
Y945510D01*
X1638175Y944720D01*
X1636111D01*
X1635452Y945379D01*
G01X1626373Y945834D02*
X1625723D01*
X1624427Y947130D01*
X1621090D01*
X1620713Y947507D01*
X1617533D01*
G01X1647233Y940814D02*
X1641193D01*
X1640084Y939705D01*
X1638966D01*
X1638176Y940495D01*
Y941883D01*
X1637479Y942580D01*
X1635856D01*
G01X1626336Y942525D02*
X1625655D01*
X1623944Y940814D01*
X1617533D01*
G01X1647233Y977625D02*
X1643955D01*
X1642972Y978608D01*
X1640992D01*
X1639802Y977418D01*
X1637876D01*
X1637512Y977782D01*
Y978492D01*
X1636613Y979391D01*
X1635069D01*
G01X1627069Y979330D02*
X1622916D01*
X1621211Y977625D01*
X1617533D01*
G01X1647233Y970932D02*
X1641759D01*
X1640251Y972440D01*
Y973445D01*
X1639461Y974235D01*
X1637535D01*
X1635955Y972655D01*
X1635069D01*
G01X1627069Y972667D02*
X1622461D01*
X1618271Y970932D01*
X1617533D01*
G01X1647233Y991011D02*
X1643739D01*
X1640062Y994688D01*
X1638282D01*
X1636330Y992736D01*
X1635069D01*
G01X1627069Y992761D02*
X1625505D01*
X1623755Y991011D01*
X1617533D01*
G01X1647233Y984318D02*
X1642612D01*
X1641462Y983168D01*
X1640112D01*
X1639112Y984168D01*
Y985541D01*
X1638612Y986041D01*
X1635069D01*
G01X1627069Y986028D02*
X1624527D01*
X1623667Y985168D01*
X1620603D01*
X1619753Y984318D01*
X1617533D01*
G01X1647233Y1031168D02*
X1642842D01*
X1641162Y1029488D01*
X1639522D01*
X1636105Y1032905D01*
X1635069D01*
G01X1627069Y1032903D02*
X1624701D01*
X1622966Y1031168D01*
X1617533D01*
G01X1647233Y1044554D02*
X1643116D01*
X1642332Y1045338D01*
X1641392D01*
X1640332Y1044278D01*
X1638112D01*
X1637632Y1044758D01*
Y1045602D01*
X1636922Y1046312D01*
X1635069D01*
G01X1627069Y1046260D02*
X1624138D01*
X1622432Y1044554D01*
X1617533D01*
G01X1647233Y1037861D02*
X1642182D01*
X1640479Y1036158D01*
X1639212D01*
X1638542Y1036828D01*
Y1038821D01*
X1637752Y1039611D01*
X1635069D01*
G01X1627069Y1039589D02*
X1622613D01*
X1620885Y1037861D01*
X1617533D01*
G01X1647233Y1071326D02*
X1644109D01*
X1643712Y1071723D01*
X1642745D01*
X1640463Y1069441D01*
X1638944D01*
X1638607Y1069778D01*
Y1072129D01*
X1637737Y1072999D01*
X1636218D01*
G01X1626409D02*
X1626016D01*
X1623976Y1070959D01*
X1619875D01*
X1619507Y1071327D01*
X1617534D01*
X1617533Y1071326D01*
G01X1647233Y1064633D02*
X1642326D01*
X1641434Y1063741D01*
X1639667D01*
X1638724Y1064684D01*
Y1065516D01*
X1637934Y1066306D01*
X1636218D01*
G01X1626409D02*
X1625614D01*
X1623586Y1064278D01*
X1621639D01*
X1621283Y1064634D01*
X1617534D01*
X1617533Y1064633D01*
G01X1647233Y1081365D02*
X1645250D01*
X1644223Y1080338D01*
X1641778D01*
X1640050Y1078610D01*
X1638135D01*
X1637053Y1079692D01*
X1636720D01*
G01X1625660D02*
X1625168D01*
X1624153Y1078677D01*
X1623858D01*
X1622490Y1079244D01*
X1621437Y1080297D01*
X1620202D01*
X1619134Y1081365D01*
X1617533D01*
G01X1647233Y1078018D02*
X1644997D01*
X1643967Y1079048D01*
X1642313D01*
X1640585Y1077320D01*
X1638084D01*
X1637109Y1076345D01*
X1636788D01*
G01X1625639D02*
X1625160D01*
X1624118Y1077387D01*
X1623601D01*
X1621759Y1078150D01*
X1620902Y1079007D01*
X1620150D01*
X1619161Y1078018D01*
X1617533D01*
G01X1647233Y1094751D02*
X1641148D01*
X1640111Y1093714D01*
Y1092614D01*
X1639461Y1091964D01*
X1636021D01*
X1635352Y1092633D01*
G01X1625964Y1093078D02*
X1624201D01*
X1622922Y1094357D01*
X1620323D01*
X1619929Y1094751D01*
X1617533D01*
G01X1647233Y1088058D02*
X1641413D01*
X1640324Y1086969D01*
X1639206D01*
X1638416Y1087759D01*
Y1088941D01*
X1637626Y1089731D01*
X1637192D01*
G01X1625660D02*
X1624935D01*
X1623262Y1088058D01*
X1617533D01*
G01X1647233Y1108137D02*
X1642030D01*
X1640738Y1106845D01*
X1639426D01*
X1638604Y1107667D01*
Y1109048D01*
X1637818Y1109834D01*
X1635122D01*
X1635108Y1109830D01*
X1635089Y1109839D01*
X1635069D01*
G01X1627069Y1109845D02*
X1625891D01*
X1624183Y1108137D01*
X1617533D01*
G01X1647233Y1101444D02*
X1644890D01*
X1643340Y1102994D01*
X1641691D01*
X1640936Y1102239D01*
Y1101214D01*
X1640157Y1100435D01*
X1638438D01*
X1637648Y1101225D01*
Y1102359D01*
X1636858Y1103149D01*
X1635069D01*
G01X1627069D02*
X1624387D01*
X1622682Y1101444D01*
X1617533D01*
G01X1647233Y1124869D02*
X1642030D01*
X1641038Y1123877D01*
X1639526D01*
X1638604Y1124799D01*
Y1125868D01*
X1637885Y1126587D01*
X1635069D01*
G01X1627069Y1126571D02*
X1625541D01*
X1623839Y1124869D01*
X1617533D01*
G01X1647233Y1118176D02*
X1645250D01*
X1644249Y1117175D01*
X1641132D01*
X1639378Y1115421D01*
X1637449D01*
X1636324Y1116546D01*
X1635069D01*
G01X1627069Y1116527D02*
X1625840D01*
X1624748Y1115435D01*
X1624266D01*
X1622593Y1117108D01*
X1620690D01*
X1619622Y1118176D01*
X1617533D01*
G01X1647233Y1114829D02*
X1644997D01*
X1643941Y1115885D01*
X1641667D01*
X1639913Y1114131D01*
X1637340D01*
X1636336Y1113127D01*
X1635069D01*
G01X1627069Y1113128D02*
X1625844D01*
X1624827Y1114145D01*
X1623731D01*
X1622058Y1115818D01*
X1620858D01*
X1619869Y1114829D01*
X1617533D01*
G01X1647233Y1144948D02*
X1642030D01*
X1641038Y1143956D01*
X1639526D01*
X1638604Y1144878D01*
Y1145876D01*
X1637814Y1146666D01*
X1635069D01*
G01X1627069Y1146650D02*
X1625363D01*
X1622748Y1144035D01*
X1620558D01*
X1619645Y1144948D01*
X1617533D01*
G01X1647233Y1138255D02*
X1642030D01*
X1641038Y1137263D01*
X1639526D01*
X1638604Y1138185D01*
Y1139207D01*
X1637838Y1139973D01*
X1635069D01*
G01X1627069Y1139957D02*
X1625923D01*
X1624221Y1138255D01*
X1617533D01*
G01X1647233Y1131562D02*
X1642030D01*
X1641038Y1130570D01*
X1639526D01*
X1638604Y1131492D01*
Y1132626D01*
X1637950Y1133280D01*
X1635069D01*
G01X1627069Y1133264D02*
X1626363D01*
X1624661Y1131562D01*
X1617533D01*
G01X1647233Y1154987D02*
X1645250D01*
X1644249Y1153986D01*
X1642121D01*
X1640436Y1153288D01*
X1639380Y1152232D01*
X1637449D01*
X1636324Y1153357D01*
X1635069D01*
G01X1627069Y1153338D02*
X1625840D01*
X1624748Y1152246D01*
X1624112D01*
X1622439Y1153919D01*
X1620690D01*
X1619622Y1154987D01*
X1617533D01*
G01X1647233Y1151641D02*
X1644996D01*
X1643941Y1152696D01*
X1642378D01*
X1641167Y1152194D01*
X1639915Y1150942D01*
X1637340D01*
X1636337Y1149939D01*
X1635069D01*
G01X1627069Y1149940D02*
X1625843D01*
X1624827Y1150956D01*
X1623577D01*
X1621904Y1152629D01*
X1620858D01*
X1619870Y1151641D01*
X1617533D01*
G01X1647233Y1175066D02*
X1642030D01*
X1641038Y1174074D01*
X1639526D01*
X1638604Y1174996D01*
Y1176092D01*
X1637912Y1176784D01*
X1635069D01*
G01X1627069Y1176768D02*
X1626035D01*
X1624333Y1175066D01*
X1617533D01*
G01D02*
X1613083D01*
G01X1647233Y1168373D02*
X1642030D01*
X1641038Y1167381D01*
X1639526D01*
X1638604Y1168303D01*
Y1169301D01*
X1637814Y1170091D01*
X1635069D01*
G01X1627069Y1170075D02*
X1625507D01*
X1623805Y1168373D01*
X1617533D01*
G01X1647233Y1161680D02*
X1642030D01*
X1640785Y1160435D01*
X1639451D01*
X1638604Y1161282D01*
Y1162492D01*
X1637698Y1163398D01*
X1635069D01*
G01X1627069Y1163382D02*
X1625363D01*
X1623661Y1161680D01*
X1617533D01*
G01X1647233Y1181759D02*
X1642030D01*
X1641038Y1180767D01*
X1639526D01*
X1638604Y1181689D01*
Y1182680D01*
X1637814Y1183470D01*
X1635069D01*
G01X1627069Y1183454D02*
X1625476D01*
X1623781Y1181759D01*
X1617533D01*
G01D02*
X1613083D01*
G01X1647233Y1191798D02*
X1645250D01*
X1644249Y1190797D01*
X1642002D01*
X1640248Y1189043D01*
X1637449D01*
X1636344Y1190148D01*
X1635072D01*
X1635069Y1190145D01*
G01X1627069D02*
X1627066Y1190148D01*
X1625839D01*
X1624748Y1189057D01*
X1624266D01*
X1622593Y1190730D01*
X1620690D01*
X1619622Y1191798D01*
X1617533D01*
G01D02*
X1613083D01*
G01X1647233Y1188452D02*
X1644996D01*
X1643941Y1189507D01*
X1642537D01*
X1640783Y1187753D01*
X1637340D01*
X1636343Y1186756D01*
X1635072D01*
X1635069Y1186759D01*
G01X1627069Y1186756D02*
X1625838D01*
X1624827Y1187767D01*
X1623731D01*
X1622058Y1189440D01*
X1620858D01*
X1619870Y1188452D01*
X1617533D01*
G01X1613083Y1188451D02*
X1617532D01*
X1617533Y1188452D01*
G01X1647233Y1205184D02*
X1642030D01*
X1641038Y1204192D01*
X1639526D01*
X1638604Y1205114D01*
Y1206117D01*
X1637818Y1206903D01*
X1635069D01*
G01X1627069Y1206893D02*
X1625662D01*
X1623953Y1205184D01*
X1617533D01*
G01D02*
X1613083D01*
G01X1647233Y1198491D02*
X1642030D01*
X1641038Y1197499D01*
X1639526D01*
X1638604Y1198421D01*
Y1199407D01*
X1637802Y1200209D01*
X1635069D01*
G01X1627069Y1200206D02*
X1625860D01*
X1624145Y1198491D01*
X1617533D01*
G01D02*
X1613083D01*
G01X1647233Y1218570D02*
X1642030D01*
X1640898Y1217438D01*
X1639214D01*
X1638604Y1218048D01*
Y1219503D01*
X1637818Y1220289D01*
X1635069D01*
G01X1627069Y1220269D02*
X1626004D01*
X1624305Y1218570D01*
X1617533D01*
G01X1647233Y1211877D02*
X1642030D01*
X1641038Y1210885D01*
X1639526D01*
X1638604Y1211807D01*
Y1212781D01*
X1637814Y1213571D01*
X1635069D01*
G01X1627069Y1213570D02*
X1627067Y1213572D01*
X1625902D01*
X1624207Y1211877D01*
X1617533D01*
G01X1647233Y1228609D02*
X1645218D01*
X1644217Y1227608D01*
X1642088D01*
X1640623Y1227001D01*
X1640028Y1226406D01*
X1638696Y1225854D01*
X1638081D01*
X1636960Y1226975D01*
X1635069D01*
G01X1627069Y1226966D02*
X1625338D01*
X1624137Y1225765D01*
X1623407D01*
X1621631Y1227541D01*
X1620470D01*
X1619402Y1228609D01*
X1617533D01*
G01X1647233Y1225263D02*
X1645268D01*
X1644213Y1226318D01*
X1642345D01*
X1641354Y1225907D01*
X1640759Y1225312D01*
X1638953Y1224564D01*
X1637980D01*
X1636980Y1223564D01*
X1635069D01*
G01X1627069Y1223569D02*
X1625124D01*
X1624218Y1224475D01*
X1622872D01*
X1621096Y1226251D01*
X1620562D01*
X1619574Y1225263D01*
X1617533D01*
G01X1647233Y1241995D02*
X1642030D01*
X1641038Y1241003D01*
X1639526D01*
X1638604Y1241925D01*
Y1242904D01*
X1637793Y1243715D01*
X1635069D01*
G01X1627069Y1243716D02*
X1625902D01*
X1623532Y1241346D01*
X1621450D01*
X1620801Y1241995D01*
X1617533D01*
G01X1647233Y1235302D02*
X1642030D01*
X1640752Y1234024D01*
X1639104D01*
X1638604Y1234524D01*
Y1236256D01*
X1637847Y1237013D01*
X1635069D01*
G01X1627069Y1237014D02*
X1625021D01*
X1623309Y1235302D01*
X1617533D01*
G01X1631091Y960892D02*
X1626641D01*
G01X1631091Y957546D02*
X1626641D01*
G01X1690491Y780184D02*
X1690490Y780185D01*
X1684224D01*
X1682525Y778486D01*
X1680911D01*
G01X1672190Y778511D02*
X1670833D01*
X1670368Y778976D01*
Y780423D01*
X1669628Y781163D01*
X1667757D01*
X1666778Y780184D01*
X1660791D01*
G01D02*
X1656441D01*
G01X1690491Y773491D02*
X1690490Y773492D01*
X1684224D01*
X1682525Y771793D01*
X1680911D01*
G01X1672190Y771818D02*
X1670833D01*
X1670368Y772283D01*
Y773730D01*
X1669628Y774470D01*
X1667757D01*
X1666778Y773491D01*
X1660791D01*
G01D02*
X1656441D01*
G01Y786877D02*
X1660791D01*
G01D02*
X1662951D01*
X1664060Y787986D01*
X1666957D01*
X1668589Y789618D01*
X1670643D01*
X1671711Y788550D01*
X1672292D01*
G01X1680911Y788529D02*
X1682187D01*
X1683098Y789440D01*
X1684299D01*
X1685915Y787824D01*
X1687224D01*
X1688171Y786877D01*
X1690491D01*
G01Y803609D02*
X1690490Y803610D01*
X1684224D01*
X1682525Y801911D01*
X1680911D01*
G01X1672190Y801936D02*
X1670833D01*
X1670368Y802401D01*
Y803848D01*
X1669628Y804588D01*
X1667757D01*
X1666778Y803609D01*
X1660791D01*
G01X1690491Y796916D02*
X1690490Y796917D01*
X1684224D01*
X1682525Y795218D01*
X1680911D01*
G01X1672190Y795243D02*
X1670833D01*
X1670368Y795708D01*
Y797155D01*
X1669628Y797895D01*
X1667757D01*
X1666778Y796916D01*
X1660791D01*
G01D02*
X1656441D01*
G01Y790223D02*
X1660791D01*
G01D02*
X1663111D01*
X1664058Y789276D01*
X1666422D01*
X1668054Y790908D01*
X1670754D01*
X1671743Y791897D01*
X1672292D01*
G01X1680911Y791921D02*
X1682184D01*
X1683375Y790730D01*
X1684834D01*
X1686450Y789114D01*
X1687222D01*
X1688331Y790223D01*
X1690491D01*
G01Y816995D02*
X1690490Y816996D01*
X1684224D01*
X1682525Y815297D01*
X1680911D01*
G01X1672190Y815322D02*
X1670833D01*
X1670368Y815787D01*
Y817234D01*
X1669628Y817974D01*
X1667757D01*
X1666778Y816995D01*
X1660791D01*
G01D02*
X1656441D01*
G01X1690491Y810302D02*
X1690490Y810303D01*
X1684224D01*
X1682525Y808604D01*
X1680911D01*
G01X1672190Y808629D02*
X1670833D01*
X1670368Y809094D01*
Y810541D01*
X1669628Y811281D01*
X1667757D01*
X1666778Y810302D01*
X1660791D01*
G01D02*
X1656441D01*
G01X1660791Y803609D02*
X1656441D01*
G01X1690491Y833727D02*
X1690490Y833728D01*
X1684224D01*
X1682525Y832029D01*
X1680911D01*
G01X1672190Y832054D02*
X1670833D01*
X1670368Y832519D01*
Y833966D01*
X1669628Y834706D01*
X1667757D01*
X1666778Y833727D01*
X1660791D01*
G01D02*
X1656441D01*
G01Y823688D02*
X1660791D01*
G01D02*
X1662951D01*
X1664060Y824797D01*
X1666957D01*
X1668589Y826429D01*
X1670643D01*
X1671711Y825361D01*
X1672292D01*
G01X1680911Y825340D02*
X1682187D01*
X1683098Y826251D01*
X1684299D01*
X1685915Y824635D01*
X1687224D01*
X1688171Y823688D01*
X1690491D01*
G01X1656441Y827034D02*
X1660791D01*
G01D02*
X1663111D01*
X1664058Y826087D01*
X1666422D01*
X1668054Y827719D01*
X1670754D01*
X1671743Y828708D01*
X1672292D01*
G01X1680911Y828732D02*
X1682184D01*
X1683375Y827541D01*
X1684834D01*
X1686450Y825925D01*
X1687222D01*
X1688331Y827034D01*
X1690491D01*
G01Y853806D02*
X1690490Y853807D01*
X1684224D01*
X1682525Y852108D01*
X1680911D01*
G01X1672190Y852133D02*
X1670833D01*
X1670368Y852598D01*
Y854045D01*
X1669628Y854785D01*
X1667757D01*
X1666778Y853806D01*
X1660791D01*
G01X1690491Y847113D02*
X1690490Y847114D01*
X1684224D01*
X1682525Y845415D01*
X1680911D01*
G01X1672190Y845440D02*
X1670833D01*
X1670368Y845905D01*
Y847352D01*
X1669628Y848092D01*
X1667757D01*
X1666778Y847113D01*
X1660791D01*
G01D02*
X1656441D01*
G01X1690491Y840420D02*
X1690490Y840421D01*
X1684224D01*
X1682525Y838722D01*
X1680911D01*
G01X1672190Y838747D02*
X1670833D01*
X1670368Y839212D01*
Y840659D01*
X1669628Y841399D01*
X1667757D01*
X1666778Y840420D01*
X1660791D01*
G01D02*
X1656441D01*
G01X1660791Y853806D02*
X1656441D01*
G01Y860499D02*
X1660791D01*
G01D02*
X1662951D01*
X1664060Y861608D01*
X1666957D01*
X1668589Y863240D01*
X1670643D01*
X1671711Y862172D01*
X1672292D01*
G01X1680911Y862151D02*
X1682187D01*
X1683098Y863062D01*
X1684299D01*
X1685915Y861446D01*
X1687224D01*
X1688171Y860499D01*
X1690491D01*
G01X1656441Y863845D02*
X1660791D01*
G01D02*
X1663111D01*
X1664058Y862898D01*
X1666422D01*
X1668054Y864530D01*
X1670754D01*
X1671743Y865519D01*
X1672292D01*
G01X1680911Y865543D02*
X1682184D01*
X1683375Y864352D01*
X1684834D01*
X1686450Y862736D01*
X1687222D01*
X1688331Y863845D01*
X1690491D01*
G01Y883924D02*
X1690490Y883925D01*
X1684224D01*
X1682525Y882226D01*
X1680911D01*
G01X1672190Y882251D02*
X1670833D01*
X1670368Y882716D01*
Y884163D01*
X1669628Y884903D01*
X1667757D01*
X1666778Y883924D01*
X1660791D01*
G01D02*
X1656441D01*
G01X1690491Y877231D02*
X1690490Y877232D01*
X1684224D01*
X1682525Y875533D01*
X1680911D01*
G01X1672190Y875558D02*
X1670833D01*
X1670368Y876023D01*
Y877470D01*
X1669628Y878210D01*
X1667757D01*
X1666778Y877231D01*
X1660791D01*
G01D02*
X1656441D01*
G01X1690491Y870538D02*
X1690490Y870539D01*
X1684224D01*
X1682525Y868840D01*
X1680911D01*
G01X1672190Y868865D02*
X1670833D01*
X1670368Y869330D01*
Y870777D01*
X1669628Y871517D01*
X1667757D01*
X1666778Y870538D01*
X1660791D01*
G01D02*
X1656441D01*
G01X1690491Y890617D02*
X1690490Y890618D01*
X1684224D01*
X1682525Y888919D01*
X1680911D01*
G01X1672190Y888944D02*
X1670833D01*
X1670368Y889409D01*
Y890856D01*
X1669628Y891596D01*
X1667757D01*
X1666778Y890617D01*
X1660791D01*
G01D02*
X1656441D01*
G01Y897310D02*
X1660791D01*
G01D02*
X1662951D01*
X1664060Y898419D01*
X1666957D01*
X1668589Y900051D01*
X1670643D01*
X1671711Y898983D01*
X1672292D01*
G01X1680911Y898962D02*
X1682187D01*
X1683098Y899873D01*
X1684299D01*
X1685915Y898257D01*
X1687224D01*
X1688171Y897310D01*
X1690491D01*
G01X1656441Y900656D02*
X1660791D01*
G01D02*
X1663111D01*
X1664058Y899709D01*
X1666422D01*
X1668054Y901341D01*
X1670754D01*
X1671743Y902330D01*
X1672292D01*
G01X1680911Y902354D02*
X1682184D01*
X1683375Y901163D01*
X1684834D01*
X1686450Y899547D01*
X1687222D01*
X1688331Y900656D01*
X1690491D01*
G01Y914042D02*
X1690490Y914043D01*
X1684224D01*
X1682525Y912344D01*
X1680911D01*
G01X1672190Y912369D02*
X1670833D01*
X1670368Y912834D01*
Y914281D01*
X1669628Y915021D01*
X1667757D01*
X1666778Y914042D01*
X1660791D01*
G01D02*
X1656441D01*
G01X1690491Y907349D02*
X1690490Y907350D01*
X1684224D01*
X1682525Y905651D01*
X1680911D01*
G01X1672190Y905676D02*
X1670833D01*
X1670368Y906141D01*
Y907588D01*
X1669628Y908328D01*
X1667757D01*
X1666778Y907349D01*
X1660791D01*
G01D02*
X1656441D01*
G01X1690491Y927428D02*
X1690490Y927429D01*
X1684224D01*
X1682525Y925730D01*
X1680911D01*
G01X1672190Y925755D02*
X1670833D01*
X1670368Y926220D01*
Y927667D01*
X1669628Y928407D01*
X1667757D01*
X1666778Y927428D01*
X1660791D01*
G01D02*
X1656441D01*
G01X1690491Y920735D02*
X1690490Y920736D01*
X1684224D01*
X1682525Y919037D01*
X1680911D01*
G01X1672190Y919062D02*
X1670833D01*
X1670368Y919527D01*
Y920974D01*
X1669628Y921714D01*
X1667757D01*
X1666778Y920735D01*
X1660791D01*
G01D02*
X1656441D01*
G01X1690491Y950853D02*
X1690490Y950854D01*
X1684224D01*
X1682525Y949155D01*
X1680911D01*
G01X1672190Y949180D02*
X1670833D01*
X1670368Y949645D01*
Y951092D01*
X1669628Y951832D01*
X1667757D01*
X1666778Y950853D01*
X1660791D01*
G01X1690491Y944160D02*
X1690490Y944161D01*
X1684224D01*
X1682525Y942462D01*
X1680911D01*
G01X1672190Y942487D02*
X1670833D01*
X1670368Y942952D01*
Y944399D01*
X1669628Y945139D01*
X1667757D01*
X1666778Y944160D01*
X1660791D01*
G01D02*
X1656441D01*
G01Y934121D02*
X1660791D01*
G01D02*
X1662951D01*
X1664060Y935230D01*
X1666957D01*
X1668589Y936862D01*
X1670643D01*
X1671711Y935794D01*
X1672292D01*
G01X1680911Y935773D02*
X1682187D01*
X1683098Y936684D01*
X1684299D01*
X1685915Y935068D01*
X1687224D01*
X1688171Y934121D01*
X1690491D01*
G01X1656441Y937467D02*
X1660791D01*
G01D02*
X1663111D01*
X1664058Y936520D01*
X1666422D01*
X1668054Y938152D01*
X1670754D01*
X1671743Y939141D01*
X1672292D01*
G01X1680911Y939165D02*
X1682184D01*
X1683375Y937974D01*
X1684834D01*
X1686450Y936358D01*
X1687222D01*
X1688331Y937467D01*
X1690491D01*
G01X1660791Y960892D02*
X1656441D01*
G01X1660791Y950853D02*
X1656441D01*
G01Y957546D02*
X1660791D01*
G01X1656441Y980971D02*
X1660791D01*
G01D02*
X1664986D01*
X1666932Y979025D01*
X1668213D01*
X1671832Y982644D01*
X1672255D01*
G01X1680911Y982693D02*
X1682549D01*
X1684272Y980970D01*
X1690490D01*
X1690491Y980971D01*
G01X1656441Y974278D02*
X1660791D01*
G01D02*
X1664986D01*
X1666932Y972332D01*
X1668213D01*
X1671832Y975951D01*
X1672255D01*
G01X1680911Y976000D02*
X1682549D01*
X1684272Y974277D01*
X1690490D01*
X1690491Y974278D01*
G01X1660791Y967585D02*
X1656441D01*
G01Y994357D02*
X1660791D01*
G01D02*
X1669311D01*
X1671746Y996792D01*
X1677136D01*
X1679312Y998968D01*
X1682045D01*
X1686656Y994357D01*
X1690491D01*
G01X1656441Y987664D02*
X1660791D01*
G01D02*
X1664986D01*
X1666932Y985718D01*
X1668213D01*
X1671832Y989337D01*
X1672255D01*
G01X1680911Y989386D02*
X1682549D01*
X1684272Y987663D01*
X1690490D01*
X1690491Y987664D01*
G01X1656141Y1027822D02*
X1660791D01*
G01D02*
X1664986D01*
X1666932Y1025876D01*
X1668213D01*
X1671832Y1029495D01*
X1672255D01*
G01X1680911Y1029544D02*
X1682549D01*
X1684272Y1027821D01*
X1690490D01*
X1690491Y1027822D01*
G01X1656441Y1021129D02*
X1660791D01*
G01D02*
X1664286D01*
X1667799Y1017616D01*
X1669281D01*
X1671121Y1019456D01*
X1672219D01*
G01X1680911Y1019505D02*
X1683094D01*
X1684718Y1021129D01*
X1690491D01*
G01X1660791Y1047900D02*
X1664986D01*
X1666932Y1045954D01*
X1668213D01*
X1671832Y1049573D01*
X1672255D01*
G01X1680911Y1049622D02*
X1682549D01*
X1684272Y1047899D01*
X1690490D01*
X1690491Y1047900D01*
G01X1656141Y1041207D02*
X1660791D01*
G01D02*
X1664414D01*
X1666265Y1039356D01*
X1667384D01*
X1670908Y1042880D01*
X1671776D01*
G01X1680911Y1042929D02*
X1682549D01*
X1684272Y1041206D01*
X1690490D01*
X1690491Y1041207D01*
G01Y1034515D02*
X1690490Y1034514D01*
X1684272D01*
X1682549Y1036237D01*
X1680911D01*
G01X1671871Y1036188D02*
X1670810D01*
X1667276Y1032654D01*
X1666157D01*
X1664296Y1034515D01*
X1660791D01*
G01X1656141Y1034514D02*
X1660790D01*
X1660791Y1034515D01*
G01X1656441Y1061286D02*
X1660791D01*
G01D02*
X1662970D01*
X1663949Y1062265D01*
X1669628D01*
X1670368Y1061525D01*
Y1060078D01*
X1670890Y1059556D01*
X1672719D01*
G01X1680911Y1059588D02*
X1682153D01*
X1684650Y1062085D01*
X1687708D01*
X1688507Y1061286D01*
X1690491D01*
G01X1656141Y1047900D02*
X1660791D01*
G01X1656141Y1054593D02*
X1660791D01*
G01X1690491Y1074672D02*
X1690490Y1074673D01*
X1684224D01*
X1682525Y1072974D01*
X1680911D01*
G01X1672190Y1072999D02*
X1670833D01*
X1670368Y1073464D01*
Y1074911D01*
X1669628Y1075651D01*
X1667757D01*
X1666778Y1074672D01*
X1660791D01*
G01D02*
X1656441D01*
G01X1690491Y1067979D02*
X1690490Y1067980D01*
X1684224D01*
X1682525Y1066281D01*
X1680911D01*
G01X1672190Y1066306D02*
X1670833D01*
X1670368Y1066771D01*
Y1068218D01*
X1669628Y1068958D01*
X1667757D01*
X1666778Y1067979D01*
X1660791D01*
G01D02*
X1656441D01*
G01X1690491Y1091404D02*
X1690490Y1091405D01*
X1684224D01*
X1682525Y1089706D01*
X1680911D01*
G01X1672190Y1089731D02*
X1670833D01*
X1670368Y1090196D01*
Y1091643D01*
X1669628Y1092383D01*
X1667757D01*
X1666778Y1091404D01*
X1660791D01*
G01D02*
X1656441D01*
G01Y1081365D02*
X1660791D01*
G01D02*
X1662951D01*
X1664060Y1082474D01*
X1666957D01*
X1668589Y1084106D01*
X1670643D01*
X1671711Y1083038D01*
X1672292D01*
G01X1680911Y1083017D02*
X1682187D01*
X1683098Y1083928D01*
X1684299D01*
X1685915Y1082312D01*
X1687224D01*
X1688171Y1081365D01*
X1690491D01*
G01X1656441Y1084711D02*
X1660791D01*
G01D02*
X1663111D01*
X1664058Y1083764D01*
X1666422D01*
X1668054Y1085396D01*
X1670754D01*
X1671743Y1086385D01*
X1672292D01*
G01X1680911Y1086409D02*
X1682184D01*
X1683375Y1085218D01*
X1684834D01*
X1686450Y1083602D01*
X1687222D01*
X1688331Y1084711D01*
X1690491D01*
G01Y1098097D02*
X1690490Y1098098D01*
X1684224D01*
X1682525Y1096399D01*
X1680911D01*
G01X1672190Y1096424D02*
X1670833D01*
X1670368Y1096889D01*
Y1098336D01*
X1669628Y1099076D01*
X1667757D01*
X1666778Y1098097D01*
X1660791D01*
G01D02*
X1656441D01*
G01X1690491Y1111483D02*
X1690490Y1111484D01*
X1684224D01*
X1682525Y1109785D01*
X1680911D01*
G01X1672190Y1109810D02*
X1670833D01*
X1670368Y1110275D01*
Y1111722D01*
X1669628Y1112462D01*
X1667757D01*
X1666778Y1111483D01*
X1660791D01*
G01D02*
X1656441D01*
G01X1690491Y1104790D02*
X1690490Y1104791D01*
X1684224D01*
X1682525Y1103092D01*
X1680911D01*
G01X1672190Y1103117D02*
X1670833D01*
X1670368Y1103582D01*
Y1105029D01*
X1669628Y1105769D01*
X1667757D01*
X1666778Y1104790D01*
X1660791D01*
G01D02*
X1656441D01*
G01X1690491Y1128215D02*
X1690490Y1128216D01*
X1684224D01*
X1682525Y1126517D01*
X1680911D01*
G01X1672190Y1126542D02*
X1670833D01*
X1670368Y1127007D01*
Y1128454D01*
X1669628Y1129194D01*
X1667757D01*
X1666778Y1128215D01*
X1660791D01*
G01D02*
X1656441D01*
G01Y1118176D02*
X1660791D01*
G01D02*
X1662951D01*
X1664060Y1119285D01*
X1666957D01*
X1668589Y1120917D01*
X1670643D01*
X1671711Y1119849D01*
X1672292D01*
G01X1680911Y1119828D02*
X1682187D01*
X1683098Y1120739D01*
X1684299D01*
X1685915Y1119123D01*
X1687224D01*
X1688171Y1118176D01*
X1690491D01*
G01X1656441Y1121522D02*
X1660791D01*
G01D02*
X1663111D01*
X1664058Y1120575D01*
X1666422D01*
X1668054Y1122207D01*
X1670754D01*
X1671743Y1123196D01*
X1672292D01*
G01X1680911Y1123220D02*
X1682184D01*
X1683375Y1122029D01*
X1684834D01*
X1686450Y1120413D01*
X1687222D01*
X1688331Y1121522D01*
X1690491D01*
G01Y1141601D02*
X1690490Y1141602D01*
X1684224D01*
X1682525Y1139903D01*
X1680911D01*
G01X1672190Y1139928D02*
X1670833D01*
X1670368Y1140393D01*
Y1141840D01*
X1669628Y1142580D01*
X1667757D01*
X1666778Y1141601D01*
X1660791D01*
G01D02*
X1656441D01*
G01X1690491Y1134908D02*
X1690490Y1134909D01*
X1684224D01*
X1682525Y1133210D01*
X1680911D01*
G01X1672190Y1133235D02*
X1670833D01*
X1670368Y1133700D01*
Y1135147D01*
X1669628Y1135887D01*
X1667757D01*
X1666778Y1134908D01*
X1660791D01*
G01D02*
X1656441D01*
G01X1690491Y1148294D02*
X1690490Y1148295D01*
X1684224D01*
X1682525Y1146596D01*
X1680911D01*
G01X1672190Y1146621D02*
X1670833D01*
X1670368Y1147086D01*
Y1148533D01*
X1669628Y1149273D01*
X1667757D01*
X1666778Y1148294D01*
X1660791D01*
G01D02*
X1656441D01*
G01Y1154987D02*
X1660791D01*
G01D02*
X1662951D01*
X1664060Y1156096D01*
X1666957D01*
X1668589Y1157728D01*
X1670643D01*
X1671711Y1156660D01*
X1672292D01*
G01X1680911Y1156639D02*
X1682187D01*
X1683098Y1157550D01*
X1684299D01*
X1685915Y1155934D01*
X1687224D01*
X1688171Y1154987D01*
X1690491D01*
G01X1656441Y1158333D02*
X1660791D01*
G01D02*
X1663111D01*
X1664058Y1157386D01*
X1666422D01*
X1668054Y1159018D01*
X1670754D01*
X1671743Y1160007D01*
X1672292D01*
G01X1680911Y1160031D02*
X1682184D01*
X1683375Y1158840D01*
X1684834D01*
X1686450Y1157224D01*
X1687222D01*
X1688331Y1158333D01*
X1690491D01*
G01Y1178412D02*
X1690490Y1178413D01*
X1684224D01*
X1682525Y1176714D01*
X1680911D01*
G01X1672190Y1176739D02*
X1670833D01*
X1670368Y1177204D01*
Y1178651D01*
X1669628Y1179391D01*
X1667757D01*
X1666778Y1178412D01*
X1660791D01*
G01X1690491Y1171719D02*
X1690490Y1171720D01*
X1684224D01*
X1682525Y1170021D01*
X1680911D01*
G01X1672190Y1170046D02*
X1670833D01*
X1670368Y1170511D01*
Y1171958D01*
X1669628Y1172698D01*
X1667757D01*
X1666778Y1171719D01*
X1660791D01*
G01D02*
X1656441D01*
G01X1690491Y1165026D02*
X1690490Y1165027D01*
X1684224D01*
X1682525Y1163328D01*
X1680911D01*
G01X1672190Y1163353D02*
X1670833D01*
X1670368Y1163818D01*
Y1165265D01*
X1669628Y1166005D01*
X1667757D01*
X1666778Y1165026D01*
X1660791D01*
G01D02*
X1656441D01*
G01X1690491Y1185105D02*
X1690490Y1185106D01*
X1684224D01*
X1682525Y1183407D01*
X1680911D01*
G01X1672190Y1183432D02*
X1670833D01*
X1670368Y1183897D01*
Y1185344D01*
X1669628Y1186084D01*
X1667757D01*
X1666778Y1185105D01*
X1660791D01*
G01D02*
X1656441D01*
G01X1660791Y1178412D02*
X1656441D01*
G01Y1191798D02*
X1660791D01*
G01D02*
X1662951D01*
X1664060Y1192907D01*
X1666957D01*
X1668589Y1194539D01*
X1670643D01*
X1671711Y1193471D01*
X1672292D01*
G01X1680911Y1193450D02*
X1682187D01*
X1683098Y1194361D01*
X1684299D01*
X1685915Y1192745D01*
X1687224D01*
X1688171Y1191798D01*
X1690491D01*
G01Y1208530D02*
X1690490Y1208531D01*
X1684224D01*
X1682525Y1206832D01*
X1680911D01*
G01X1672190Y1206857D02*
X1670833D01*
X1670368Y1207322D01*
Y1208769D01*
X1669628Y1209509D01*
X1667757D01*
X1666778Y1208530D01*
X1660791D01*
G01D02*
X1656441D01*
G01X1690491Y1201837D02*
X1690490Y1201838D01*
X1684224D01*
X1682525Y1200139D01*
X1680911D01*
G01X1672190Y1200164D02*
X1670833D01*
X1670368Y1200629D01*
Y1202076D01*
X1669628Y1202816D01*
X1667757D01*
X1666778Y1201837D01*
X1660791D01*
G01D02*
X1656441D01*
G01Y1195144D02*
X1660791D01*
G01D02*
X1663111D01*
X1664058Y1194197D01*
X1666422D01*
X1668054Y1195829D01*
X1670754D01*
X1671743Y1196818D01*
X1672292D01*
G01X1680911Y1196842D02*
X1682184D01*
X1683375Y1195651D01*
X1684834D01*
X1686450Y1194035D01*
X1687222D01*
X1688331Y1195144D01*
X1690491D01*
G01Y1221916D02*
X1690490Y1221917D01*
X1684224D01*
X1682525Y1220218D01*
X1680911D01*
G01X1672190Y1220243D02*
X1670833D01*
X1670368Y1220708D01*
Y1222155D01*
X1669628Y1222895D01*
X1667757D01*
X1666778Y1221916D01*
X1660791D01*
G01D02*
X1656441D01*
G01X1690491Y1215223D02*
X1690490Y1215224D01*
X1684224D01*
X1682525Y1213525D01*
X1680911D01*
G01X1672190Y1213550D02*
X1670833D01*
X1670368Y1214015D01*
Y1215462D01*
X1669628Y1216202D01*
X1667757D01*
X1666778Y1215223D01*
X1660791D01*
G01D02*
X1656441D01*
G01X1690491Y1238648D02*
X1690490Y1238649D01*
X1684224D01*
X1682525Y1236950D01*
X1680911D01*
G01X1672190Y1236975D02*
X1670833D01*
X1670368Y1237440D01*
Y1238887D01*
X1669628Y1239627D01*
X1667757D01*
X1666778Y1238648D01*
X1660791D01*
G01D02*
X1656441D01*
G01Y1228609D02*
X1660791D01*
G01D02*
X1662951D01*
X1664060Y1229718D01*
X1666957D01*
X1668589Y1231350D01*
X1670643D01*
X1671711Y1230282D01*
X1672292D01*
G01X1680911Y1230261D02*
X1682187D01*
X1683098Y1231172D01*
X1684299D01*
X1685915Y1229556D01*
X1687224D01*
X1688171Y1228609D01*
X1690491D01*
G01X1656441Y1231955D02*
X1660791D01*
G01D02*
X1663111D01*
X1664058Y1231008D01*
X1666422D01*
X1668054Y1232640D01*
X1670754D01*
X1671743Y1233629D01*
X1672292D01*
G01X1680911Y1233653D02*
X1682184D01*
X1683375Y1232462D01*
X1684834D01*
X1686450Y1230846D01*
X1687222D01*
X1688331Y1231955D01*
X1690491D01*
G01Y1245341D02*
X1690490Y1245342D01*
X1684224D01*
X1682525Y1243643D01*
X1680911D01*
G01X1672190Y1243668D02*
X1670833D01*
X1670368Y1244133D01*
Y1245580D01*
X1669628Y1246320D01*
X1667757D01*
X1666778Y1245341D01*
X1660791D01*
G01D02*
X1656441D01*
G01X1672583Y770144D02*
X1676933D01*
G01D02*
X1683619D01*
X1685320Y771845D01*
X1686469D01*
G01X1694469Y771865D02*
X1697151D01*
X1697954Y771062D01*
Y770074D01*
X1698876Y769152D01*
X1700388D01*
X1701380Y770144D01*
X1706633D01*
G01X1672583Y776837D02*
X1676933D01*
G01D02*
X1683619D01*
X1685320Y778538D01*
X1686469D01*
G01X1694469Y778558D02*
X1697151D01*
X1697954Y777755D01*
Y776767D01*
X1698876Y775845D01*
X1700388D01*
X1701380Y776837D01*
X1706633D01*
G01X1672583Y786877D02*
X1676933D01*
G01D02*
X1679022D01*
X1680090Y785809D01*
X1681993D01*
X1683666Y784136D01*
X1684148D01*
X1685240Y785228D01*
X1686469D01*
G01X1694469Y785247D02*
X1695724D01*
X1696849Y784122D01*
X1698778D01*
X1700532Y785876D01*
X1703649D01*
X1704650Y786877D01*
X1706633D01*
G01X1672583Y783530D02*
X1676933D01*
G01D02*
X1679269D01*
X1680258Y784519D01*
X1681458D01*
X1683131Y782846D01*
X1684227D01*
X1685244Y781829D01*
X1686469D01*
G01X1694469Y781828D02*
X1695736D01*
X1696740Y782832D01*
X1699313D01*
X1701067Y784586D01*
X1703341D01*
X1704397Y783530D01*
X1706633D01*
G01X1672583Y800263D02*
X1676933D01*
G01D02*
X1683619D01*
X1685320Y801964D01*
X1686469D01*
G01X1694469Y801984D02*
X1697151D01*
X1697954Y801181D01*
Y800193D01*
X1698876Y799271D01*
X1700388D01*
X1701380Y800263D01*
X1706633D01*
G01X1672583Y793570D02*
X1676933D01*
G01D02*
X1683619D01*
X1685320Y795271D01*
X1686469D01*
G01X1694469Y795291D02*
X1697151D01*
X1697954Y794488D01*
Y793500D01*
X1698876Y792578D01*
X1700388D01*
X1701380Y793570D01*
X1706633D01*
G01X1672583Y813648D02*
X1676933D01*
G01D02*
X1683619D01*
X1685320Y815349D01*
X1686469D01*
G01X1694469Y815369D02*
X1697151D01*
X1697954Y814566D01*
Y813578D01*
X1698876Y812656D01*
X1700388D01*
X1701380Y813648D01*
X1706633D01*
G01X1672583Y806955D02*
X1676933D01*
G01D02*
X1683619D01*
X1685320Y808656D01*
X1686469D01*
G01X1694469Y808676D02*
X1697151D01*
X1697954Y807873D01*
Y806885D01*
X1698876Y805963D01*
X1700388D01*
X1701380Y806955D01*
X1706633D01*
G01X1676933Y820341D02*
X1679269D01*
X1680258Y821330D01*
X1681458D01*
X1683131Y819657D01*
X1684227D01*
X1685244Y818640D01*
X1686469D01*
G01X1694469Y818639D02*
X1695736D01*
X1696740Y819643D01*
X1699313D01*
X1701067Y821397D01*
X1703341D01*
X1704397Y820341D01*
X1706633D01*
G01X1672583Y830381D02*
X1676933D01*
G01D02*
X1683619D01*
X1685320Y832082D01*
X1686469D01*
G01X1694469Y832102D02*
X1697151D01*
X1697954Y831299D01*
Y830311D01*
X1698876Y829389D01*
X1700388D01*
X1701380Y830381D01*
X1706633D01*
G01X1672583Y823688D02*
X1676933D01*
G01D02*
X1679022D01*
X1680090Y822620D01*
X1681993D01*
X1683666Y820947D01*
X1684148D01*
X1685240Y822039D01*
X1686469D01*
G01X1694469Y822058D02*
X1695724D01*
X1696849Y820933D01*
X1698778D01*
X1700532Y822687D01*
X1703649D01*
X1704650Y823688D01*
X1706633D01*
G01X1672583Y820341D02*
X1676933D01*
G01X1672583Y850459D02*
X1676933D01*
G01D02*
X1683619D01*
X1685320Y852160D01*
X1686469D01*
G01X1694469Y852180D02*
X1697151D01*
X1697954Y851377D01*
Y850389D01*
X1698876Y849467D01*
X1700388D01*
X1701380Y850459D01*
X1706633D01*
G01X1672583Y843766D02*
X1676933D01*
G01D02*
X1683619D01*
X1685320Y845467D01*
X1686469D01*
G01X1694469Y845487D02*
X1697151D01*
X1697954Y844684D01*
Y843696D01*
X1698876Y842774D01*
X1700388D01*
X1701380Y843766D01*
X1706633D01*
G01X1672583Y837074D02*
X1676933D01*
G01D02*
X1683619D01*
X1685320Y838775D01*
X1686469D01*
G01X1694469Y838795D02*
X1697151D01*
X1697954Y837992D01*
Y837004D01*
X1698876Y836082D01*
X1700388D01*
X1701380Y837074D01*
X1706633D01*
G01X1672583Y867192D02*
X1676933D01*
G01D02*
X1683619D01*
X1685320Y868893D01*
X1686469D01*
G01X1694469Y868913D02*
X1697151D01*
X1697954Y868110D01*
Y867122D01*
X1698876Y866200D01*
X1700388D01*
X1701380Y867192D01*
X1706633D01*
G01X1672583Y860499D02*
X1676933D01*
G01D02*
X1679022D01*
X1680090Y859431D01*
X1681993D01*
X1683666Y857758D01*
X1684148D01*
X1685240Y858850D01*
X1686469D01*
G01X1694469Y858869D02*
X1695724D01*
X1696849Y857744D01*
X1698778D01*
X1700532Y859498D01*
X1703649D01*
X1704650Y860499D01*
X1706633D01*
G01X1672583Y857152D02*
X1676933D01*
G01D02*
X1679269D01*
X1680258Y858141D01*
X1681458D01*
X1683131Y856468D01*
X1684227D01*
X1685244Y855451D01*
X1686469D01*
G01X1694469Y855450D02*
X1695736D01*
X1696740Y856454D01*
X1699313D01*
X1701067Y858208D01*
X1703341D01*
X1704397Y857152D01*
X1706633D01*
G01X1672583Y873885D02*
X1676933D01*
G01D02*
X1683619D01*
X1685320Y875586D01*
X1686469D01*
G01X1694469Y875606D02*
X1697151D01*
X1697954Y874803D01*
Y873815D01*
X1698876Y872893D01*
X1700388D01*
X1701380Y873885D01*
X1706633D01*
G01X1672583Y880577D02*
X1676933D01*
G01D02*
X1683619D01*
X1685320Y882278D01*
X1686469D01*
G01X1694469Y882298D02*
X1697151D01*
X1697954Y881495D01*
Y880507D01*
X1698876Y879585D01*
X1700388D01*
X1701380Y880577D01*
X1706633D01*
G01X1672583Y887270D02*
X1676933D01*
G01D02*
X1683619D01*
X1685320Y888971D01*
X1686469D01*
G01X1694469Y888991D02*
X1697151D01*
X1697954Y888188D01*
Y887200D01*
X1698876Y886278D01*
X1700388D01*
X1701380Y887270D01*
X1706633D01*
G01X1672583Y897310D02*
X1676933D01*
G01D02*
X1679022D01*
X1680090Y896242D01*
X1681993D01*
X1683666Y894569D01*
X1684148D01*
X1685240Y895661D01*
X1686469D01*
G01X1694469Y895680D02*
X1695724D01*
X1696849Y894555D01*
X1698778D01*
X1700532Y896309D01*
X1703649D01*
X1704650Y897310D01*
X1706633D01*
G01X1672583Y893963D02*
X1676933D01*
G01D02*
X1679269D01*
X1680258Y894952D01*
X1681458D01*
X1683131Y893279D01*
X1684227D01*
X1685244Y892262D01*
X1686469D01*
G01X1694469Y892261D02*
X1695736D01*
X1696740Y893265D01*
X1699313D01*
X1701067Y895019D01*
X1703341D01*
X1704397Y893963D01*
X1706633D01*
G01X1672583Y910696D02*
X1676933D01*
G01D02*
X1683619D01*
X1685320Y912397D01*
X1686469D01*
G01X1694469Y912417D02*
X1697151D01*
X1697954Y911614D01*
Y910626D01*
X1698876Y909704D01*
X1700388D01*
X1701380Y910696D01*
X1706633D01*
G01X1672583Y904003D02*
X1676933D01*
G01D02*
X1683619D01*
X1685320Y905704D01*
X1686469D01*
G01X1694469Y905724D02*
X1697151D01*
X1697954Y904921D01*
Y903933D01*
X1698876Y903011D01*
X1700388D01*
X1701380Y904003D01*
X1706633D01*
G01X1672583Y924081D02*
X1676933D01*
G01D02*
X1683619D01*
X1685320Y925782D01*
X1686469D01*
G01X1694469Y925802D02*
X1697151D01*
X1697954Y924999D01*
Y924011D01*
X1698876Y923089D01*
X1700388D01*
X1701380Y924081D01*
X1706633D01*
G01X1672583Y917389D02*
X1676933D01*
G01D02*
X1683619D01*
X1685320Y919090D01*
X1686469D01*
G01X1694469Y919110D02*
X1697151D01*
X1697954Y918307D01*
Y917319D01*
X1698876Y916397D01*
X1700388D01*
X1701380Y917389D01*
X1706633D01*
G01X1676933Y934121D02*
X1679022D01*
X1680090Y933053D01*
X1681993D01*
X1683666Y931380D01*
X1684148D01*
X1685240Y932472D01*
X1686469D01*
G01X1694469Y932491D02*
X1695724D01*
X1696849Y931366D01*
X1698778D01*
X1700532Y933120D01*
X1703649D01*
X1704650Y934121D01*
X1706633D01*
G01X1672583Y930774D02*
X1676933D01*
G01D02*
X1679269D01*
X1680258Y931763D01*
X1681458D01*
X1683131Y930090D01*
X1684227D01*
X1685244Y929073D01*
X1686469D01*
G01X1694469Y929072D02*
X1695736D01*
X1696740Y930076D01*
X1699313D01*
X1701067Y931830D01*
X1703341D01*
X1704397Y930774D01*
X1706633D01*
G01X1672583Y947507D02*
X1676933D01*
G01D02*
X1683619D01*
X1685320Y949208D01*
X1686469D01*
G01X1694469Y949228D02*
X1697151D01*
X1697954Y948425D01*
Y947437D01*
X1698876Y946515D01*
X1700388D01*
X1701380Y947507D01*
X1706633D01*
G01X1672583Y940814D02*
X1676933D01*
G01D02*
X1683619D01*
X1685320Y942515D01*
X1686469D01*
G01X1694469Y942535D02*
X1697151D01*
X1697954Y941732D01*
Y940744D01*
X1698876Y939822D01*
X1700388D01*
X1701380Y940814D01*
X1706633D01*
G01X1672583Y934121D02*
X1676933D01*
G01X1686041Y960892D02*
X1690491D01*
G01X1672583Y964239D02*
X1676933D01*
G01X1686041Y957546D02*
X1690491D01*
G01X1672583Y977625D02*
X1676933D01*
G01D02*
X1683373D01*
X1685088Y979340D01*
X1686469D01*
G01X1694469Y979327D02*
X1695548D01*
X1698953Y975922D01*
X1700542D01*
X1702245Y977625D01*
X1706633D01*
G01X1690491Y967585D02*
X1686141D01*
G01X1672583Y970932D02*
X1676933D01*
G01D02*
X1683373D01*
X1685088Y972647D01*
X1686469D01*
G01X1694469Y972634D02*
X1695548D01*
X1698953Y969229D01*
X1700542D01*
X1702245Y970932D01*
X1706633D01*
G01X1672583Y991011D02*
X1676933D01*
G01D02*
X1683373D01*
X1685088Y992726D01*
X1686469D01*
G01X1694469Y992713D02*
X1695548D01*
X1698953Y989308D01*
X1700542D01*
X1702245Y991011D01*
X1706633D01*
G01X1672583Y984318D02*
X1676933D01*
G01D02*
X1683373D01*
X1685088Y986033D01*
X1686469D01*
G01X1694469Y986020D02*
X1695548D01*
X1698953Y982615D01*
X1700542D01*
X1702245Y984318D01*
X1706633D01*
G01X1676933Y1021129D02*
X1672583D01*
G01X1676933Y1024475D02*
X1672583D01*
G01X1676933Y1031168D02*
X1683373D01*
X1685088Y1032883D01*
X1686469D01*
G01X1694469Y1032870D02*
X1695548D01*
X1698953Y1029465D01*
X1700542D01*
X1702245Y1031168D01*
X1706633D01*
G01X1672283Y1044554D02*
X1676933D01*
G01D02*
X1683373D01*
X1685088Y1046269D01*
X1686469D01*
G01X1694469Y1046256D02*
X1695548D01*
X1698953Y1042851D01*
X1700542D01*
X1702245Y1044554D01*
X1706633D01*
G01X1672283Y1037861D02*
X1676933D01*
G01D02*
X1683373D01*
X1685088Y1039576D01*
X1686469D01*
G01X1694469Y1039563D02*
X1695548D01*
X1698953Y1036158D01*
X1700542D01*
X1702245Y1037861D01*
X1706633D01*
G01X1672583Y1031168D02*
X1676933D01*
G01X1690491Y1054593D02*
X1686141D01*
G01X1676933Y1051247D02*
X1672583D01*
G01X1706633Y1071326D02*
X1701380D01*
X1700388Y1070334D01*
X1698876D01*
X1697954Y1071256D01*
Y1072244D01*
X1697151Y1073047D01*
X1694469D01*
G01X1686469Y1073027D02*
X1685320D01*
X1683619Y1071326D01*
X1676933D01*
G01X1672583Y1071325D02*
X1676932D01*
X1676933Y1071326D01*
G01X1672583Y1064633D02*
X1676933D01*
G01D02*
X1683619D01*
X1685320Y1066334D01*
X1686469D01*
G01X1694469Y1066354D02*
X1697151D01*
X1697954Y1065551D01*
Y1064563D01*
X1698876Y1063641D01*
X1700388D01*
X1701380Y1064633D01*
X1706633D01*
G01X1676933Y1081365D02*
X1679022D01*
X1680090Y1080297D01*
X1681993D01*
X1683666Y1078624D01*
X1684148D01*
X1685240Y1079716D01*
X1686469D01*
G01X1694469Y1079735D02*
X1695724D01*
X1696849Y1078610D01*
X1698778D01*
X1700532Y1080364D01*
X1703649D01*
X1704650Y1081365D01*
X1706633D01*
G01X1672583Y1078018D02*
X1676933D01*
G01D02*
X1679269D01*
X1680258Y1079007D01*
X1681458D01*
X1683131Y1077334D01*
X1684227D01*
X1685244Y1076317D01*
X1686469D01*
G01X1694469Y1076316D02*
X1695736D01*
X1696740Y1077320D01*
X1699313D01*
X1701067Y1079074D01*
X1703341D01*
X1704397Y1078018D01*
X1706633D01*
G01X1672583Y1094751D02*
X1676933D01*
G01D02*
X1683619D01*
X1685320Y1096452D01*
X1686469D01*
G01X1694469Y1096472D02*
X1697151D01*
X1697954Y1095669D01*
Y1094681D01*
X1698876Y1093759D01*
X1700388D01*
X1701380Y1094751D01*
X1706633D01*
G01X1672583Y1088058D02*
X1676933D01*
G01D02*
X1683619D01*
X1685320Y1089759D01*
X1686469D01*
G01X1694469Y1089779D02*
X1697151D01*
X1697954Y1088976D01*
Y1087988D01*
X1698876Y1087066D01*
X1700388D01*
X1701380Y1088058D01*
X1706633D01*
G01X1672583Y1081365D02*
X1676933D01*
G01X1706633Y1108137D02*
X1701380D01*
X1700388Y1107145D01*
X1698876D01*
X1697954Y1108067D01*
Y1109055D01*
X1697151Y1109858D01*
X1694469D01*
G01X1686469Y1109838D02*
X1685320D01*
X1683619Y1108137D01*
X1676933D01*
G01X1672583Y1108136D02*
X1672584Y1108137D01*
X1676933D01*
G01X1672583Y1101444D02*
X1676933D01*
G01D02*
X1683619D01*
X1685320Y1103145D01*
X1686469D01*
G01X1694469Y1103165D02*
X1697151D01*
X1697954Y1102362D01*
Y1101374D01*
X1698876Y1100452D01*
X1700388D01*
X1701380Y1101444D01*
X1706633D01*
G01X1672583Y1124869D02*
X1676933D01*
G01D02*
X1683619D01*
X1685320Y1126570D01*
X1686469D01*
G01X1694469Y1126590D02*
X1697151D01*
X1697954Y1125787D01*
Y1124799D01*
X1698876Y1123877D01*
X1700388D01*
X1701380Y1124869D01*
X1706633D01*
G01X1672583Y1118176D02*
X1676933D01*
G01D02*
X1679022D01*
X1680090Y1117108D01*
X1681993D01*
X1683666Y1115435D01*
X1684148D01*
X1685240Y1116527D01*
X1686469D01*
G01X1694469Y1116546D02*
X1695724D01*
X1696849Y1115421D01*
X1698778D01*
X1700532Y1117175D01*
X1703649D01*
X1704650Y1118176D01*
X1706633D01*
G01X1672583Y1114829D02*
X1676933D01*
G01D02*
X1679269D01*
X1680258Y1115818D01*
X1681458D01*
X1683131Y1114145D01*
X1684227D01*
X1685244Y1113128D01*
X1686469D01*
G01X1694469Y1113127D02*
X1695736D01*
X1696740Y1114131D01*
X1699313D01*
X1701067Y1115885D01*
X1703341D01*
X1704397Y1114829D01*
X1706633D01*
G01Y1144948D02*
X1701380D01*
X1700388Y1143956D01*
X1698876D01*
X1697954Y1144878D01*
Y1145866D01*
X1697151Y1146669D01*
X1694469D01*
G01X1686469Y1146649D02*
X1685320D01*
X1683619Y1144948D01*
X1676933D01*
G01X1672583Y1144947D02*
X1672584Y1144948D01*
X1676933D01*
G01X1672583Y1138255D02*
X1676933D01*
G01D02*
X1683619D01*
X1685320Y1139956D01*
X1686469D01*
G01X1694469Y1139976D02*
X1697151D01*
X1697954Y1139173D01*
Y1138185D01*
X1698876Y1137263D01*
X1700388D01*
X1701380Y1138255D01*
X1706633D01*
G01X1672583Y1131562D02*
X1676933D01*
G01D02*
X1683619D01*
X1685320Y1133263D01*
X1686469D01*
G01X1694469Y1133283D02*
X1697151D01*
X1697954Y1132480D01*
Y1131492D01*
X1698876Y1130570D01*
X1700388D01*
X1701380Y1131562D01*
X1706633D01*
G01X1672583Y1154987D02*
X1676933D01*
G01D02*
X1679022D01*
X1680090Y1153919D01*
X1681993D01*
X1683666Y1152246D01*
X1684148D01*
X1685240Y1153338D01*
X1686469D01*
G01X1694469Y1153357D02*
X1695724D01*
X1696849Y1152232D01*
X1698778D01*
X1700532Y1153986D01*
X1703649D01*
X1704650Y1154987D01*
X1706633D01*
G01Y1151641D02*
X1704396D01*
X1703341Y1152696D01*
X1701067D01*
X1699313Y1150942D01*
X1696740D01*
X1695737Y1149939D01*
X1694469D01*
G01X1686469Y1149940D02*
X1685243D01*
X1684227Y1150956D01*
X1683131D01*
X1681458Y1152629D01*
X1680258D01*
X1679270Y1151641D01*
X1676933D01*
G01X1672583Y1151640D02*
X1676932D01*
X1676933Y1151641D01*
G01X1672583Y1175066D02*
X1676933D01*
G01D02*
X1683619D01*
X1685320Y1176767D01*
X1686469D01*
G01X1694469Y1176787D02*
X1697151D01*
X1697954Y1175984D01*
Y1174996D01*
X1698876Y1174074D01*
X1700388D01*
X1701380Y1175066D01*
X1706633D01*
G01X1672583Y1168373D02*
X1676933D01*
G01D02*
X1683619D01*
X1685320Y1170074D01*
X1686469D01*
G01X1694469Y1170094D02*
X1697151D01*
X1697954Y1169291D01*
Y1168303D01*
X1698876Y1167381D01*
X1700388D01*
X1701380Y1168373D01*
X1706633D01*
G01X1672583Y1161680D02*
X1676933D01*
G01D02*
X1683619D01*
X1685320Y1163381D01*
X1686469D01*
G01X1694469Y1163401D02*
X1697151D01*
X1697954Y1162598D01*
Y1161610D01*
X1698876Y1160688D01*
X1700388D01*
X1701380Y1161680D01*
X1706633D01*
G01Y1181759D02*
X1701380D01*
X1700388Y1180767D01*
X1698876D01*
X1697954Y1181689D01*
Y1182677D01*
X1697151Y1183480D01*
X1694469D01*
G01X1686469Y1183460D02*
X1685320D01*
X1683619Y1181759D01*
X1676933D01*
G01X1672583Y1181758D02*
X1676932D01*
X1676933Y1181759D01*
G01X1672583Y1191798D02*
X1676933D01*
G01D02*
X1679022D01*
X1680090Y1190730D01*
X1681993D01*
X1683666Y1189057D01*
X1684148D01*
X1685240Y1190149D01*
X1686469D01*
G01X1694469Y1190168D02*
X1695724D01*
X1696849Y1189043D01*
X1698778D01*
X1700532Y1190797D01*
X1703649D01*
X1704650Y1191798D01*
X1706633D01*
G01Y1188452D02*
X1704396D01*
X1703341Y1189507D01*
X1701067D01*
X1699313Y1187753D01*
X1696740D01*
X1695737Y1186750D01*
X1694469D01*
G01X1686469Y1186751D02*
X1685243D01*
X1684227Y1187767D01*
X1683131D01*
X1681458Y1189440D01*
X1680258D01*
X1679270Y1188452D01*
X1676933D01*
G01X1672583Y1188451D02*
X1676932D01*
X1676933Y1188452D01*
G01X1672583Y1205184D02*
X1676933D01*
G01D02*
X1683619D01*
X1685320Y1206885D01*
X1686469D01*
G01X1694469Y1206905D02*
X1697151D01*
X1697954Y1206102D01*
Y1205114D01*
X1698876Y1204192D01*
X1700388D01*
X1701380Y1205184D01*
X1706633D01*
G01X1672583Y1198491D02*
X1676933D01*
G01D02*
X1683619D01*
X1685320Y1200192D01*
X1686469D01*
G01X1694469Y1200212D02*
X1697151D01*
X1697954Y1199409D01*
Y1198421D01*
X1698876Y1197499D01*
X1700388D01*
X1701380Y1198491D01*
X1706633D01*
G01Y1218570D02*
X1701380D01*
X1700388Y1217578D01*
X1698876D01*
X1697954Y1218500D01*
Y1219488D01*
X1697151Y1220291D01*
X1694469D01*
G01X1686469Y1220271D02*
X1685320D01*
X1683619Y1218570D01*
X1676933D01*
G01X1672583Y1218569D02*
X1676932D01*
X1676933Y1218570D01*
G01X1672583Y1211877D02*
X1676933D01*
G01D02*
X1683619D01*
X1685320Y1213578D01*
X1686469D01*
G01X1694469Y1213598D02*
X1697151D01*
X1697954Y1212795D01*
Y1211807D01*
X1698876Y1210885D01*
X1700388D01*
X1701380Y1211877D01*
X1706633D01*
G01X1676933Y1228609D02*
X1679022D01*
X1680090Y1227541D01*
X1681993D01*
X1683666Y1225868D01*
X1684148D01*
X1685240Y1226960D01*
X1686469D01*
G01X1694469Y1226979D02*
X1695724D01*
X1696849Y1225854D01*
X1698778D01*
X1700532Y1227608D01*
X1703649D01*
X1704650Y1228609D01*
X1706633D01*
G01Y1225263D02*
X1704396D01*
X1703341Y1226318D01*
X1701067D01*
X1699313Y1224564D01*
X1696740D01*
X1695737Y1223561D01*
X1694469D01*
G01X1686469Y1223562D02*
X1685243D01*
X1684227Y1224578D01*
X1683131D01*
X1681458Y1226251D01*
X1680258D01*
X1679270Y1225263D01*
X1676933D01*
G01X1672583Y1225262D02*
X1672584Y1225263D01*
X1676933D01*
G01X1672583Y1241995D02*
X1676933D01*
G01D02*
X1683619D01*
X1685320Y1243696D01*
X1686469D01*
G01X1694469Y1243716D02*
X1697151D01*
X1697954Y1242913D01*
Y1241925D01*
X1698876Y1241003D01*
X1700388D01*
X1701380Y1241995D01*
X1706633D01*
G01X1672583Y1235302D02*
X1676933D01*
G01D02*
X1683619D01*
X1685320Y1237003D01*
X1686469D01*
G01X1694469Y1237023D02*
X1697151D01*
X1697954Y1236220D01*
Y1235232D01*
X1698876Y1234310D01*
X1700388D01*
X1701380Y1235302D01*
X1706633D01*
G01X1672583Y1228609D02*
X1676933D01*
G01X1706633Y964239D02*
X1702283D01*
G01X1706633Y1021129D02*
X1702283D01*
G01X1706633Y1024475D02*
X1702283D01*
G01X1706633Y1051247D02*
X1702283D01*
G01X1749891Y780184D02*
X1749890Y780185D01*
X1743624D01*
X1741925Y778486D01*
X1740311D01*
G01X1731590Y778511D02*
X1730233D01*
X1729768Y778976D01*
Y780423D01*
X1729028Y781163D01*
X1727157D01*
X1726178Y780184D01*
X1720191D01*
G01D02*
X1715841D01*
G01X1749891Y773491D02*
X1749890Y773492D01*
X1743624D01*
X1741925Y771793D01*
X1740311D01*
G01X1731590Y771818D02*
X1730233D01*
X1729768Y772283D01*
Y773730D01*
X1729028Y774470D01*
X1727157D01*
X1726178Y773491D01*
X1720191D01*
G01D02*
X1715841D01*
G01Y786877D02*
X1720191D01*
G01D02*
X1722351D01*
X1723460Y787986D01*
X1726357D01*
X1727989Y789618D01*
X1730043D01*
X1731111Y788550D01*
X1731692D01*
G01X1740311Y788529D02*
X1741587D01*
X1742498Y789440D01*
X1743699D01*
X1745315Y787824D01*
X1746624D01*
X1747571Y786877D01*
X1749891D01*
G01Y796916D02*
X1749890Y796917D01*
X1743624D01*
X1741925Y795218D01*
X1740311D01*
G01X1731590Y795243D02*
X1730233D01*
X1729768Y795708D01*
Y797155D01*
X1729028Y797895D01*
X1727157D01*
X1726178Y796916D01*
X1720191D01*
G01D02*
X1715841D01*
G01Y790223D02*
X1720191D01*
G01D02*
X1722511D01*
X1723458Y789276D01*
X1725822D01*
X1727454Y790908D01*
X1730154D01*
X1731143Y791897D01*
X1731692D01*
G01X1740311Y791921D02*
X1741584D01*
X1742775Y790730D01*
X1744234D01*
X1745850Y789114D01*
X1746622D01*
X1747731Y790223D01*
X1749891D01*
G01Y816995D02*
X1749890Y816996D01*
X1743624D01*
X1741925Y815297D01*
X1740311D01*
G01X1731590Y815322D02*
X1730233D01*
X1729768Y815787D01*
Y817234D01*
X1729028Y817974D01*
X1727157D01*
X1726178Y816995D01*
X1720191D01*
G01D02*
X1715841D01*
G01X1749891Y810302D02*
X1749890Y810303D01*
X1743624D01*
X1741925Y808604D01*
X1740311D01*
G01X1731590Y808629D02*
X1730233D01*
X1729768Y809094D01*
Y810541D01*
X1729028Y811281D01*
X1727157D01*
X1726178Y810302D01*
X1720191D01*
G01D02*
X1715841D01*
G01X1749891Y803609D02*
X1749890Y803610D01*
X1743624D01*
X1741925Y801911D01*
X1740311D01*
G01X1731590Y801936D02*
X1730233D01*
X1729768Y802401D01*
Y803848D01*
X1729028Y804588D01*
X1727157D01*
X1726178Y803609D01*
X1720191D01*
G01D02*
X1715841D01*
G01X1749891Y833727D02*
X1749890Y833728D01*
X1743624D01*
X1741925Y832029D01*
X1740311D01*
G01X1731590Y832054D02*
X1730233D01*
X1729768Y832519D01*
Y833966D01*
X1729028Y834706D01*
X1727157D01*
X1726178Y833727D01*
X1720191D01*
G01D02*
X1715841D01*
G01Y823688D02*
X1720191D01*
G01D02*
X1722351D01*
X1723460Y824797D01*
X1726357D01*
X1727989Y826429D01*
X1730043D01*
X1731111Y825361D01*
X1731692D01*
G01X1740311Y825340D02*
X1741587D01*
X1742498Y826251D01*
X1743699D01*
X1745315Y824635D01*
X1746624D01*
X1747571Y823688D01*
X1749891D01*
G01X1715841Y827034D02*
X1720191D01*
G01D02*
X1722511D01*
X1723458Y826087D01*
X1725822D01*
X1727454Y827719D01*
X1730154D01*
X1731143Y828708D01*
X1731692D01*
G01X1740311Y828732D02*
X1741584D01*
X1742775Y827541D01*
X1744234D01*
X1745850Y825925D01*
X1746622D01*
X1747731Y827034D01*
X1749891D01*
G01Y847113D02*
X1749890Y847114D01*
X1743624D01*
X1741925Y845415D01*
X1740311D01*
G01X1731590Y845440D02*
X1730233D01*
X1729768Y845905D01*
Y847352D01*
X1729028Y848092D01*
X1727157D01*
X1726178Y847113D01*
X1720191D01*
G01D02*
X1715841D01*
G01X1749891Y840420D02*
X1749890Y840421D01*
X1743624D01*
X1741925Y838722D01*
X1740311D01*
G01X1731590Y838747D02*
X1730233D01*
X1729768Y839212D01*
Y840659D01*
X1729028Y841399D01*
X1727157D01*
X1726178Y840420D01*
X1720191D01*
G01D02*
X1715841D01*
G01X1749891Y853806D02*
X1749890Y853807D01*
X1743624D01*
X1741925Y852108D01*
X1740311D01*
G01X1731590Y852133D02*
X1730233D01*
X1729768Y852598D01*
Y854045D01*
X1729028Y854785D01*
X1727157D01*
X1726178Y853806D01*
X1720191D01*
G01D02*
X1715841D01*
G01Y860499D02*
X1720191D01*
G01D02*
X1722351D01*
X1723460Y861608D01*
X1726357D01*
X1727989Y863240D01*
X1730043D01*
X1731111Y862172D01*
X1731692D01*
G01X1740311Y862151D02*
X1741587D01*
X1742498Y863062D01*
X1743699D01*
X1745315Y861446D01*
X1746624D01*
X1747571Y860499D01*
X1749891D01*
G01X1715841Y863845D02*
X1720191D01*
G01D02*
X1722511D01*
X1723458Y862898D01*
X1725822D01*
X1727454Y864530D01*
X1730154D01*
X1731143Y865519D01*
X1731692D01*
G01X1740311Y865543D02*
X1741584D01*
X1742775Y864352D01*
X1744234D01*
X1745850Y862736D01*
X1746622D01*
X1747731Y863845D01*
X1749891D01*
G01Y883924D02*
X1749890Y883925D01*
X1743624D01*
X1741925Y882226D01*
X1740311D01*
G01X1731590Y882251D02*
X1730233D01*
X1729768Y882716D01*
Y884163D01*
X1729028Y884903D01*
X1727157D01*
X1726178Y883924D01*
X1720191D01*
G01D02*
X1715841D01*
G01X1749891Y877231D02*
X1749890Y877232D01*
X1743624D01*
X1741925Y875533D01*
X1740311D01*
G01X1731590Y875558D02*
X1730233D01*
X1729768Y876023D01*
Y877470D01*
X1729028Y878210D01*
X1727157D01*
X1726178Y877231D01*
X1720191D01*
G01D02*
X1715841D01*
G01X1749891Y870538D02*
X1749890Y870539D01*
X1743624D01*
X1741925Y868840D01*
X1740311D01*
G01X1731590Y868865D02*
X1730233D01*
X1729768Y869330D01*
Y870777D01*
X1729028Y871517D01*
X1727157D01*
X1726178Y870538D01*
X1720191D01*
G01D02*
X1715841D01*
G01X1749891Y890617D02*
X1749890Y890618D01*
X1743624D01*
X1741925Y888919D01*
X1740311D01*
G01X1731590Y888944D02*
X1730233D01*
X1729768Y889409D01*
Y890856D01*
X1729028Y891596D01*
X1727157D01*
X1726178Y890617D01*
X1720191D01*
G01D02*
X1715841D01*
G01Y897310D02*
X1720191D01*
G01D02*
X1722351D01*
X1723460Y898419D01*
X1726357D01*
X1727989Y900051D01*
X1730043D01*
X1731111Y898983D01*
X1731692D01*
G01X1740311Y898962D02*
X1741587D01*
X1742498Y899873D01*
X1743699D01*
X1745315Y898257D01*
X1746624D01*
X1747571Y897310D01*
X1749891D01*
G01X1715841Y900656D02*
X1720191D01*
G01D02*
X1722511D01*
X1723458Y899709D01*
X1725822D01*
X1727454Y901341D01*
X1730154D01*
X1731143Y902330D01*
X1731692D01*
G01X1740311Y902354D02*
X1741584D01*
X1742775Y901163D01*
X1744234D01*
X1745850Y899547D01*
X1746622D01*
X1747731Y900656D01*
X1749891D01*
G01Y914042D02*
X1749890Y914043D01*
X1743624D01*
X1741925Y912344D01*
X1740311D01*
G01X1731590Y912369D02*
X1730233D01*
X1729768Y912834D01*
Y914281D01*
X1729028Y915021D01*
X1727157D01*
X1726178Y914042D01*
X1720191D01*
G01D02*
X1715841D01*
G01X1749891Y907349D02*
X1749890Y907350D01*
X1743624D01*
X1741925Y905651D01*
X1740311D01*
G01X1731590Y905676D02*
X1730233D01*
X1729768Y906141D01*
Y907588D01*
X1729028Y908328D01*
X1727157D01*
X1726178Y907349D01*
X1720191D01*
G01D02*
X1715841D01*
G01X1749891Y927428D02*
X1749890Y927429D01*
X1743470D01*
X1741796Y925755D01*
X1741015D01*
G01X1731206D02*
X1730233D01*
X1729768Y926220D01*
Y927667D01*
X1729028Y928407D01*
X1727157D01*
X1726178Y927428D01*
X1720191D01*
G01D02*
X1715841D01*
G01X1749891Y920735D02*
X1749890Y920736D01*
X1743470D01*
X1741796Y919062D01*
X1741015D01*
G01X1731206D02*
X1730233D01*
X1729768Y919527D01*
Y920974D01*
X1729028Y921714D01*
X1727157D01*
X1726178Y920735D01*
X1720191D01*
G01D02*
X1715841D01*
G01X1749891Y944160D02*
X1749890Y944161D01*
X1743470D01*
X1741796Y942487D01*
X1741015D01*
G01X1731206D02*
X1730233D01*
X1729768Y942952D01*
Y944399D01*
X1729028Y945139D01*
X1727157D01*
X1726178Y944160D01*
X1720191D01*
G01D02*
X1715841D01*
G01Y934121D02*
X1720191D01*
G01D02*
X1722351D01*
X1723460Y935230D01*
X1726239D01*
X1727871Y936862D01*
X1730043D01*
X1731111Y935794D01*
X1731438D01*
G01X1741015D02*
X1741608D01*
X1742498Y936684D01*
X1743699D01*
X1745315Y935068D01*
X1746624D01*
X1747571Y934121D01*
X1749891D01*
G01X1715841Y937467D02*
X1720191D01*
G01D02*
X1722511D01*
X1723458Y936520D01*
X1725704D01*
X1727336Y938152D01*
X1730154D01*
X1731143Y939141D01*
X1731651D01*
G01X1741130D02*
X1741608D01*
X1742775Y937974D01*
X1744234D01*
X1745850Y936358D01*
X1746622D01*
X1747731Y937467D01*
X1749891D01*
G01X1720191Y960892D02*
X1715841D01*
G01X1749891Y950853D02*
X1749890Y950854D01*
X1743470D01*
X1741796Y949180D01*
X1741015D01*
G01X1731206D02*
X1730233D01*
X1729768Y949645D01*
Y951092D01*
X1729028Y951832D01*
X1727157D01*
X1726178Y950853D01*
X1720191D01*
G01D02*
X1715841D01*
G01Y957546D02*
X1720191D01*
G01X1715841Y980971D02*
X1720191D01*
G01D02*
X1724386D01*
X1726332Y979025D01*
X1727613D01*
X1731232Y982644D01*
X1731655D01*
G01X1740311Y982693D02*
X1741949D01*
X1743672Y980970D01*
X1749890D01*
X1749891Y980971D01*
G01X1715841Y974278D02*
X1720191D01*
G01D02*
X1724386D01*
X1726332Y972332D01*
X1727613D01*
X1731232Y975951D01*
X1731655D01*
G01X1740311Y976000D02*
X1741949D01*
X1743672Y974277D01*
X1749890D01*
X1749891Y974278D01*
G01X1720191Y967585D02*
X1715841D01*
G01Y994357D02*
X1720191D01*
G01D02*
X1725003D01*
X1726202Y993158D01*
X1728352D01*
X1731964Y996770D01*
X1743143D01*
X1745556Y994357D01*
X1749891D01*
G01X1715841Y987664D02*
X1720191D01*
G01D02*
X1724386D01*
X1726332Y985718D01*
X1727613D01*
X1731232Y989337D01*
X1731655D01*
G01X1740311Y989386D02*
X1741949D01*
X1743672Y987663D01*
X1749890D01*
X1749891Y987664D01*
G01X1715841Y1027822D02*
X1720191D01*
G01D02*
X1724386D01*
X1726332Y1025876D01*
X1727613D01*
X1731232Y1029495D01*
X1731655D01*
G01X1740311Y1029544D02*
X1741949D01*
X1743672Y1027821D01*
X1749890D01*
X1749891Y1027822D01*
G01X1715841Y1021129D02*
X1720191D01*
G01D02*
X1723686D01*
X1727199Y1017616D01*
X1728681D01*
X1730521Y1019456D01*
X1731619D01*
G01X1740311Y1019505D02*
X1742494D01*
X1744118Y1021129D01*
X1749891D01*
G01X1715841Y1041207D02*
X1720191D01*
G01D02*
X1723814D01*
X1725665Y1039356D01*
X1726784D01*
X1730308Y1042880D01*
X1731176D01*
G01X1740311Y1042929D02*
X1741949D01*
X1743672Y1041206D01*
X1749890D01*
X1749891Y1041207D01*
G01X1715841Y1034514D02*
X1715842Y1034515D01*
X1720191D01*
G01D02*
X1723696D01*
X1725557Y1032654D01*
X1726676D01*
X1730210Y1036188D01*
X1731271D01*
G01X1740311Y1036237D02*
X1741949D01*
X1743672Y1034514D01*
X1749890D01*
X1749891Y1034515D01*
G01Y1061286D02*
X1749890Y1061287D01*
X1743470D01*
X1741796Y1059613D01*
X1741015D01*
G01X1731206D02*
X1729480D01*
X1729015Y1060078D01*
Y1061525D01*
X1728275Y1062265D01*
X1727157D01*
X1726178Y1061286D01*
X1720191D01*
G01D02*
X1715841D01*
G01Y1047900D02*
X1720191D01*
G01D02*
X1724386D01*
X1726332Y1045954D01*
X1727613D01*
X1731232Y1049573D01*
X1731655D01*
G01X1740311Y1049622D02*
X1741949D01*
X1743672Y1047899D01*
X1749890D01*
X1749891Y1047900D01*
G01X1715841Y1054593D02*
X1720191D01*
G01X1749891Y1074672D02*
X1749890Y1074673D01*
X1743470D01*
X1741796Y1072999D01*
X1741015D01*
G01X1731206D02*
X1730233D01*
X1729768Y1073464D01*
Y1074911D01*
X1729028Y1075651D01*
X1727157D01*
X1726178Y1074672D01*
X1720191D01*
G01D02*
X1715841D01*
G01X1749891Y1067979D02*
X1749890Y1067980D01*
X1743470D01*
X1741796Y1066306D01*
X1741015D01*
G01X1731206D02*
X1730233D01*
X1729768Y1066771D01*
Y1068218D01*
X1729028Y1068958D01*
X1727157D01*
X1726178Y1067979D01*
X1720191D01*
G01D02*
X1715841D01*
G01X1749891Y1091404D02*
X1749890Y1091405D01*
X1743470D01*
X1741796Y1089731D01*
X1741015D01*
G01X1731206D02*
X1730233D01*
X1729768Y1090196D01*
Y1091643D01*
X1729028Y1092383D01*
X1727157D01*
X1726178Y1091404D01*
X1720191D01*
G01D02*
X1715841D01*
G01Y1081365D02*
X1720191D01*
G01D02*
X1722351D01*
X1723460Y1082474D01*
X1725724D01*
X1727356Y1084106D01*
X1730043D01*
X1731111Y1083038D01*
X1731438D01*
G01X1741015D02*
X1741608D01*
X1742498Y1083928D01*
X1743699D01*
X1745315Y1082312D01*
X1746624D01*
X1747571Y1081365D01*
X1749891D01*
G01X1715841Y1084711D02*
X1720191D01*
G01D02*
X1722511D01*
X1723458Y1083764D01*
X1725189D01*
X1726821Y1085396D01*
X1730154D01*
X1731143Y1086385D01*
X1731651D01*
G01X1741130D02*
X1741608D01*
X1742775Y1085218D01*
X1744234D01*
X1745850Y1083602D01*
X1746622D01*
X1747731Y1084711D01*
X1749891D01*
G01Y1098097D02*
X1749890Y1098098D01*
X1743470D01*
X1741796Y1096424D01*
X1741015D01*
G01X1731206D02*
X1730233D01*
X1729768Y1096889D01*
Y1098336D01*
X1729028Y1099076D01*
X1727157D01*
X1726178Y1098097D01*
X1720191D01*
G01D02*
X1715841D01*
G01X1749891Y1111483D02*
X1749890Y1111484D01*
X1743624D01*
X1741925Y1109785D01*
X1740311D01*
G01X1731165Y1109810D02*
X1730233D01*
X1729768Y1110275D01*
Y1111722D01*
X1729028Y1112462D01*
X1727157D01*
X1726178Y1111483D01*
X1720191D01*
G01D02*
X1715841D01*
G01X1749891Y1104790D02*
X1749890Y1104791D01*
X1743624D01*
X1741925Y1103092D01*
X1740311D01*
G01X1731590Y1103117D02*
X1730233D01*
X1729768Y1103582D01*
Y1105029D01*
X1729028Y1105769D01*
X1727157D01*
X1726178Y1104790D01*
X1720191D01*
G01D02*
X1715841D01*
G01X1749891Y1128215D02*
X1749890Y1128216D01*
X1743624D01*
X1741925Y1126517D01*
X1740311D01*
G01X1731590Y1126542D02*
X1730233D01*
X1729768Y1127007D01*
Y1128454D01*
X1729028Y1129194D01*
X1727157D01*
X1726178Y1128215D01*
X1720191D01*
G01D02*
X1715841D01*
G01Y1118176D02*
X1720191D01*
G01D02*
X1722351D01*
X1723460Y1119285D01*
X1726357D01*
X1727989Y1120917D01*
X1730043D01*
X1731111Y1119849D01*
X1731692D01*
G01X1740311Y1119828D02*
X1741587D01*
X1742498Y1120739D01*
X1743699D01*
X1745315Y1119123D01*
X1746624D01*
X1747571Y1118176D01*
X1749891D01*
G01X1715841Y1121522D02*
X1720191D01*
G01D02*
X1722511D01*
X1723458Y1120575D01*
X1725822D01*
X1727454Y1122207D01*
X1730154D01*
X1731143Y1123196D01*
X1731692D01*
G01X1740311Y1123220D02*
X1741584D01*
X1742775Y1122029D01*
X1744234D01*
X1745850Y1120413D01*
X1746622D01*
X1747731Y1121522D01*
X1749891D01*
G01Y1141601D02*
X1749890Y1141602D01*
X1743624D01*
X1741925Y1139903D01*
X1740311D01*
G01X1731590Y1139928D02*
X1730233D01*
X1729768Y1140393D01*
Y1141840D01*
X1729028Y1142580D01*
X1727157D01*
X1726178Y1141601D01*
X1720191D01*
G01D02*
X1715841D01*
G01X1749891Y1134908D02*
X1749890Y1134909D01*
X1743624D01*
X1741925Y1133210D01*
X1740311D01*
G01X1731590Y1133235D02*
X1730233D01*
X1729768Y1133700D01*
Y1135147D01*
X1729028Y1135887D01*
X1727157D01*
X1726178Y1134908D01*
X1720191D01*
G01D02*
X1715841D01*
G01X1749891Y1148294D02*
X1749890Y1148295D01*
X1743624D01*
X1741925Y1146596D01*
X1740311D01*
G01X1731590Y1146621D02*
X1730233D01*
X1729768Y1147086D01*
Y1148533D01*
X1729028Y1149273D01*
X1727157D01*
X1726178Y1148294D01*
X1720191D01*
G01D02*
X1715841D01*
G01Y1154987D02*
X1720191D01*
G01D02*
X1722351D01*
X1723460Y1156096D01*
X1726357D01*
X1727989Y1157728D01*
X1730043D01*
X1731111Y1156660D01*
X1731692D01*
G01X1740311Y1156639D02*
X1741587D01*
X1742498Y1157550D01*
X1743699D01*
X1745315Y1155934D01*
X1746624D01*
X1747571Y1154987D01*
X1749891D01*
G01X1715841Y1158333D02*
X1720191D01*
G01D02*
X1722511D01*
X1723458Y1157386D01*
X1725822D01*
X1727454Y1159018D01*
X1730154D01*
X1731143Y1160007D01*
X1731692D01*
G01X1740311Y1160031D02*
X1741584D01*
X1742775Y1158840D01*
X1744234D01*
X1745850Y1157224D01*
X1746622D01*
X1747731Y1158333D01*
X1749891D01*
G01Y1171719D02*
X1749890Y1171720D01*
X1743624D01*
X1741925Y1170021D01*
X1740311D01*
G01X1731590Y1170046D02*
X1730233D01*
X1729768Y1170511D01*
Y1171958D01*
X1729028Y1172698D01*
X1727157D01*
X1726178Y1171719D01*
X1720191D01*
G01D02*
X1715841D01*
G01X1749891Y1165026D02*
X1749890Y1165027D01*
X1743624D01*
X1741925Y1163328D01*
X1740311D01*
G01X1731590Y1163353D02*
X1730233D01*
X1729768Y1163818D01*
Y1165265D01*
X1729028Y1166005D01*
X1727157D01*
X1726178Y1165026D01*
X1720191D01*
G01D02*
X1715841D01*
G01X1749891Y1185105D02*
X1749890Y1185106D01*
X1743624D01*
X1741925Y1183407D01*
X1740311D01*
G01X1731328Y1183432D02*
X1729253D01*
X1728788Y1183897D01*
Y1185344D01*
X1728048Y1186084D01*
X1726177D01*
X1725198Y1185105D01*
X1720191D01*
G01D02*
X1715841D01*
G01X1749891Y1178412D02*
X1749890Y1178413D01*
X1743624D01*
X1741925Y1176714D01*
X1740311D01*
G01X1731590Y1176739D02*
X1730233D01*
X1729768Y1177204D01*
Y1178651D01*
X1729028Y1179391D01*
X1727157D01*
X1726178Y1178412D01*
X1720191D01*
G01D02*
X1715841D01*
G01Y1191798D02*
X1720191D01*
G01D02*
X1722351D01*
X1723460Y1192907D01*
X1726357D01*
X1727989Y1194539D01*
X1730043D01*
X1731111Y1193471D01*
X1731692D01*
G01X1740311Y1193450D02*
X1741587D01*
X1742498Y1194361D01*
X1743699D01*
X1745315Y1192745D01*
X1746624D01*
X1747571Y1191798D01*
X1749891D01*
G01Y1208530D02*
X1749890Y1208531D01*
X1743624D01*
X1741925Y1206832D01*
X1740311D01*
G01X1731590Y1206857D02*
X1730233D01*
X1729768Y1207322D01*
Y1208769D01*
X1729028Y1209509D01*
X1727157D01*
X1726178Y1208530D01*
X1720191D01*
G01D02*
X1715841D01*
G01X1749891Y1201837D02*
X1749890Y1201838D01*
X1743624D01*
X1741925Y1200139D01*
X1740311D01*
G01X1731590Y1200164D02*
X1730233D01*
X1729768Y1200629D01*
Y1202076D01*
X1729028Y1202816D01*
X1727157D01*
X1726178Y1201837D01*
X1720191D01*
G01D02*
X1715841D01*
G01Y1195144D02*
X1720191D01*
G01D02*
X1722511D01*
X1723458Y1194197D01*
X1725822D01*
X1727454Y1195829D01*
X1730154D01*
X1731143Y1196818D01*
X1731692D01*
G01X1740311Y1196842D02*
X1741584D01*
X1742775Y1195651D01*
X1744234D01*
X1745850Y1194035D01*
X1746622D01*
X1747731Y1195144D01*
X1749891D01*
G01Y1221916D02*
X1749890Y1221917D01*
X1743624D01*
X1741925Y1220218D01*
X1740311D01*
G01X1731590Y1220243D02*
X1730233D01*
X1729768Y1220708D01*
Y1222155D01*
X1729028Y1222895D01*
X1727157D01*
X1726178Y1221916D01*
X1720191D01*
G01D02*
X1715841D01*
G01X1749891Y1215223D02*
X1749890Y1215224D01*
X1743624D01*
X1741925Y1213525D01*
X1740311D01*
G01X1731590Y1213550D02*
X1730233D01*
X1729768Y1214015D01*
Y1215462D01*
X1729028Y1216202D01*
X1727157D01*
X1726178Y1215223D01*
X1720191D01*
G01D02*
X1715841D01*
G01X1749891Y1238648D02*
X1749890Y1238649D01*
X1743624D01*
X1741925Y1236950D01*
X1740311D01*
G01X1731590Y1236975D02*
X1730233D01*
X1729768Y1237440D01*
Y1238887D01*
X1729028Y1239627D01*
X1727157D01*
X1726178Y1238648D01*
X1720191D01*
G01D02*
X1715841D01*
G01Y1228609D02*
X1720191D01*
G01D02*
X1722351D01*
X1723460Y1229718D01*
X1726357D01*
X1727989Y1231350D01*
X1730043D01*
X1731111Y1230282D01*
X1731692D01*
G01X1740311Y1230261D02*
X1741587D01*
X1742498Y1231172D01*
X1743699D01*
X1745315Y1229556D01*
X1746624D01*
X1747571Y1228609D01*
X1749891D01*
G01X1715841Y1231955D02*
X1720191D01*
G01D02*
X1722511D01*
X1723458Y1231008D01*
X1725822D01*
X1727454Y1232640D01*
X1730154D01*
X1731143Y1233629D01*
X1731692D01*
G01X1740311Y1233653D02*
X1741584D01*
X1742775Y1232462D01*
X1744234D01*
X1745850Y1230846D01*
X1746622D01*
X1747731Y1231955D01*
X1749891D01*
G01Y1245341D02*
X1749890Y1245342D01*
X1743624D01*
X1741925Y1243643D01*
X1740311D01*
G01X1731590Y1243668D02*
X1730233D01*
X1729768Y1244133D01*
Y1245580D01*
X1729028Y1246320D01*
X1727157D01*
X1726178Y1245341D01*
X1720191D01*
G01D02*
X1715841D01*
G01X1731983Y770144D02*
X1736333D01*
G01D02*
X1743019D01*
X1744720Y771845D01*
X1745869D01*
G01X1753869Y771865D02*
X1756551D01*
X1757354Y771062D01*
Y770074D01*
X1758276Y769152D01*
X1759788D01*
X1760780Y770144D01*
X1766033D01*
G01X1731983Y776837D02*
X1736333D01*
G01D02*
X1743019D01*
X1744720Y778538D01*
X1745869D01*
G01X1753869Y778558D02*
X1756551D01*
X1757354Y777755D01*
Y776767D01*
X1758276Y775845D01*
X1759788D01*
X1760780Y776837D01*
X1766033D01*
G01X1731983Y786877D02*
X1736333D01*
G01D02*
X1738422D01*
X1739490Y785809D01*
X1741393D01*
X1743066Y784136D01*
X1743548D01*
X1744640Y785228D01*
X1745869D01*
G01X1753869Y785247D02*
X1755124D01*
X1756249Y784122D01*
X1758178D01*
X1759932Y785876D01*
X1763049D01*
X1764050Y786877D01*
X1766033D01*
G01X1731983Y783530D02*
X1736333D01*
G01D02*
X1738669D01*
X1739658Y784519D01*
X1740858D01*
X1742531Y782846D01*
X1743627D01*
X1744644Y781829D01*
X1745869D01*
G01X1753869Y781828D02*
X1755136D01*
X1756140Y782832D01*
X1758713D01*
X1760467Y784586D01*
X1762741D01*
X1763797Y783530D01*
X1766033D01*
G01X1731983Y800263D02*
X1736333D01*
G01D02*
X1743019D01*
X1744720Y801964D01*
X1745869D01*
G01X1753869Y801984D02*
X1756551D01*
X1757354Y801181D01*
Y800193D01*
X1758276Y799271D01*
X1759788D01*
X1760780Y800263D01*
X1766033D01*
G01X1731983Y793570D02*
X1736333D01*
G01D02*
X1743019D01*
X1744720Y795271D01*
X1745869D01*
G01X1753869Y795291D02*
X1756551D01*
X1757354Y794488D01*
Y793500D01*
X1758276Y792578D01*
X1759788D01*
X1760780Y793570D01*
X1766033D01*
G01X1731983Y813648D02*
X1736333D01*
G01D02*
X1743019D01*
X1744720Y815349D01*
X1745869D01*
G01X1753869Y815369D02*
X1756551D01*
X1757354Y814566D01*
Y813578D01*
X1758276Y812656D01*
X1759788D01*
X1760780Y813648D01*
X1766033D01*
G01X1731983Y806955D02*
X1736333D01*
G01D02*
X1743019D01*
X1744720Y808656D01*
X1745869D01*
G01X1753869Y808676D02*
X1756551D01*
X1757354Y807873D01*
Y806885D01*
X1758276Y805963D01*
X1759788D01*
X1760780Y806955D01*
X1766033D01*
G01X1731983Y830381D02*
X1736333D01*
G01D02*
X1743019D01*
X1744720Y832082D01*
X1745869D01*
G01X1753869Y832102D02*
X1756551D01*
X1757354Y831299D01*
Y830311D01*
X1758276Y829389D01*
X1759788D01*
X1760780Y830381D01*
X1766033D01*
G01X1731983Y823688D02*
X1736333D01*
G01D02*
X1738422D01*
X1739490Y822620D01*
X1741393D01*
X1743066Y820947D01*
X1743548D01*
X1744640Y822039D01*
X1745869D01*
G01X1753869Y822058D02*
X1755124D01*
X1756249Y820933D01*
X1758178D01*
X1759932Y822687D01*
X1763049D01*
X1764050Y823688D01*
X1766033D01*
G01X1731983Y820341D02*
X1736333D01*
G01D02*
X1738669D01*
X1739658Y821330D01*
X1740858D01*
X1742531Y819657D01*
X1743627D01*
X1744644Y818640D01*
X1745869D01*
G01X1753869Y818639D02*
X1755136D01*
X1756140Y819643D01*
X1758713D01*
X1760467Y821397D01*
X1762741D01*
X1763797Y820341D01*
X1766033D01*
G01X1731983Y850459D02*
X1736333D01*
G01D02*
X1743019D01*
X1744720Y852160D01*
X1745869D01*
G01X1753869Y852180D02*
X1756551D01*
X1757354Y851377D01*
Y850389D01*
X1758276Y849467D01*
X1759788D01*
X1760780Y850459D01*
X1766033D01*
G01X1731983Y843766D02*
X1736333D01*
G01D02*
X1743019D01*
X1744720Y845467D01*
X1745869D01*
G01X1753869Y845487D02*
X1756551D01*
X1757354Y844684D01*
Y843696D01*
X1758276Y842774D01*
X1759788D01*
X1760780Y843766D01*
X1766033D01*
G01X1731983Y837074D02*
X1736333D01*
G01D02*
X1743019D01*
X1744720Y838775D01*
X1745869D01*
G01X1753869Y838795D02*
X1756551D01*
X1757354Y837992D01*
Y837004D01*
X1758276Y836082D01*
X1759788D01*
X1760780Y837074D01*
X1766033D01*
G01X1731983Y867192D02*
X1736333D01*
G01D02*
X1743019D01*
X1744720Y868893D01*
X1745869D01*
G01X1753869Y868913D02*
X1756551D01*
X1757354Y868110D01*
Y867122D01*
X1758276Y866200D01*
X1759788D01*
X1760780Y867192D01*
X1766033D01*
G01X1731983Y860499D02*
X1736333D01*
G01D02*
X1738422D01*
X1739490Y859431D01*
X1741393D01*
X1743066Y857758D01*
X1743548D01*
X1744640Y858850D01*
X1745869D01*
G01X1753869Y858869D02*
X1755124D01*
X1756249Y857744D01*
X1758178D01*
X1759932Y859498D01*
X1763049D01*
X1764050Y860499D01*
X1766033D01*
G01X1731983Y857152D02*
X1736333D01*
G01D02*
X1738669D01*
X1739658Y858141D01*
X1740858D01*
X1742531Y856468D01*
X1743627D01*
X1744644Y855451D01*
X1745869D01*
G01X1753869Y855450D02*
X1755136D01*
X1756140Y856454D01*
X1758713D01*
X1760467Y858208D01*
X1762741D01*
X1763797Y857152D01*
X1766033D01*
G01X1731983Y873885D02*
X1736333D01*
G01D02*
X1743019D01*
X1744720Y875586D01*
X1745869D01*
G01X1753869Y875606D02*
X1756551D01*
X1757354Y874803D01*
Y873815D01*
X1758276Y872893D01*
X1759788D01*
X1760780Y873885D01*
X1766033D01*
G01X1731983Y880577D02*
X1736333D01*
G01D02*
X1743019D01*
X1744720Y882278D01*
X1745869D01*
G01X1753869Y882298D02*
X1756551D01*
X1757354Y881495D01*
Y880507D01*
X1758276Y879585D01*
X1759788D01*
X1760780Y880577D01*
X1766033D01*
G01X1731983Y887270D02*
X1736333D01*
G01D02*
X1743019D01*
X1744720Y888971D01*
X1745869D01*
G01X1753869Y888991D02*
X1756551D01*
X1757354Y888188D01*
Y887200D01*
X1758276Y886278D01*
X1759788D01*
X1760780Y887270D01*
X1766033D01*
G01X1731983Y897310D02*
X1736333D01*
G01D02*
X1738422D01*
X1739490Y896242D01*
X1741393D01*
X1743066Y894569D01*
X1743548D01*
X1744640Y895661D01*
X1745869D01*
G01X1753869Y895680D02*
X1755124D01*
X1756249Y894555D01*
X1758178D01*
X1759932Y896309D01*
X1763049D01*
X1764050Y897310D01*
X1766033D01*
G01X1731983Y893963D02*
X1736333D01*
G01D02*
X1738669D01*
X1739658Y894952D01*
X1740858D01*
X1742531Y893279D01*
X1743627D01*
X1744644Y892262D01*
X1745869D01*
G01X1753869Y892261D02*
X1755136D01*
X1756140Y893265D01*
X1758713D01*
X1760467Y895019D01*
X1762741D01*
X1763797Y893963D01*
X1766033D01*
G01X1731983Y910696D02*
X1736333D01*
G01D02*
X1743019D01*
X1744720Y912397D01*
X1745869D01*
G01X1753869Y912417D02*
X1756551D01*
X1757354Y911614D01*
Y910626D01*
X1758276Y909704D01*
X1759788D01*
X1760780Y910696D01*
X1766033D01*
G01X1731983Y904003D02*
X1736333D01*
G01D02*
X1743019D01*
X1744720Y905704D01*
X1745869D01*
G01X1753869Y905724D02*
X1756551D01*
X1757354Y904921D01*
Y903933D01*
X1758276Y903011D01*
X1759788D01*
X1760780Y904003D01*
X1766033D01*
G01X1731983Y924081D02*
X1736333D01*
G01D02*
X1742619D01*
X1744292Y925754D01*
X1745209D01*
G01X1755018D02*
X1756564D01*
X1757354Y924964D01*
Y923710D01*
X1758144Y922920D01*
X1759619D01*
X1760780Y924081D01*
X1766033D01*
G01X1731983Y917389D02*
X1736333D01*
G01D02*
X1743047D01*
X1744720Y919062D01*
X1745209D01*
G01X1755018D02*
X1756564D01*
X1757354Y918272D01*
Y917102D01*
X1758144Y916312D01*
X1759703D01*
X1760780Y917389D01*
X1766033D01*
G01X1731983Y930774D02*
X1736333D01*
G01D02*
X1738669D01*
X1739658Y931763D01*
X1740858D01*
X1742531Y930090D01*
X1743582D01*
X1744571Y929101D01*
X1744996D01*
G01X1754573D02*
X1755165D01*
X1756140Y930076D01*
X1758713D01*
X1760467Y931830D01*
X1762741D01*
X1763797Y930774D01*
X1766033D01*
G01X1731983Y947507D02*
X1736333D01*
G01D02*
X1742619D01*
X1744292Y949180D01*
X1745209D01*
G01X1755018D02*
X1756564D01*
X1757354Y948390D01*
Y947136D01*
X1758144Y946346D01*
X1759619D01*
X1760780Y947507D01*
X1766033D01*
G01X1731983Y940814D02*
X1736333D01*
G01D02*
X1743047D01*
X1744720Y942487D01*
X1745209D01*
G01X1755018D02*
X1756564D01*
X1757354Y941697D01*
Y940527D01*
X1758144Y939737D01*
X1759703D01*
X1760780Y940814D01*
X1766033D01*
G01X1731983Y934121D02*
X1736333D01*
G01D02*
X1738422D01*
X1739490Y933053D01*
X1741393D01*
X1743066Y931380D01*
X1743572D01*
X1744640Y932448D01*
X1745209D01*
G01X1754688D02*
X1755167D01*
X1756249Y931366D01*
X1758178D01*
X1759932Y933120D01*
X1763049D01*
X1764050Y934121D01*
X1766033D01*
G01X1736333Y964239D02*
X1731983D01*
G01Y977625D02*
X1736333D01*
G01D02*
X1742773D01*
X1744488Y979340D01*
X1745869D01*
G01X1753869Y979327D02*
X1754948D01*
X1758353Y975922D01*
X1759942D01*
X1761645Y977625D01*
X1766033D01*
G01X1731883Y970932D02*
X1736333D01*
G01D02*
X1742773D01*
X1744488Y972647D01*
X1745869D01*
G01X1753869Y972634D02*
X1754948D01*
X1758353Y969229D01*
X1759942D01*
X1761645Y970932D01*
X1766033D01*
G01X1731983Y991011D02*
X1736333D01*
G01D02*
X1742773D01*
X1744488Y992726D01*
X1745869D01*
G01X1753869Y992713D02*
X1754948D01*
X1758353Y989308D01*
X1759942D01*
X1761645Y991011D01*
X1766033D01*
G01X1731983Y984318D02*
X1736333D01*
G01D02*
X1742773D01*
X1744488Y986033D01*
X1745869D01*
G01X1753869Y986020D02*
X1754948D01*
X1758353Y982615D01*
X1759942D01*
X1761645Y984318D01*
X1766033D01*
G01X1736333Y1021129D02*
X1731983D01*
G01Y1024475D02*
X1736333D01*
G01X1731683Y1044554D02*
X1736333D01*
G01D02*
X1742773D01*
X1744488Y1046269D01*
X1745869D01*
G01X1753869Y1046256D02*
X1754948D01*
X1758353Y1042851D01*
X1759942D01*
X1761645Y1044554D01*
X1766033D01*
G01X1731683Y1037861D02*
X1736333D01*
G01D02*
X1742773D01*
X1744488Y1039576D01*
X1745869D01*
G01X1753869Y1039563D02*
X1754948D01*
X1758353Y1036158D01*
X1759942D01*
X1761645Y1037861D01*
X1766033D01*
G01X1731983Y1031168D02*
X1736333D01*
G01D02*
X1742773D01*
X1744488Y1032883D01*
X1745869D01*
G01X1753869Y1032870D02*
X1754948D01*
X1758353Y1029465D01*
X1759942D01*
X1761645Y1031168D01*
X1766033D01*
G01X1731983Y1051247D02*
X1736333D01*
G01X1731818Y1071326D02*
X1736333D01*
G01D02*
X1742619D01*
X1744292Y1072999D01*
X1745209D01*
G01X1755018D02*
X1756564D01*
X1757354Y1072209D01*
Y1070955D01*
X1758144Y1070165D01*
X1759619D01*
X1760780Y1071326D01*
X1766033D01*
G01X1731883Y1064633D02*
X1736333D01*
G01D02*
X1743047D01*
X1744720Y1066306D01*
X1745209D01*
G01X1755018D02*
X1756564D01*
X1757354Y1065516D01*
Y1064346D01*
X1758144Y1063556D01*
X1759703D01*
X1760780Y1064633D01*
X1766033D01*
G01X1731983Y1078018D02*
X1736333D01*
G01D02*
X1738669D01*
X1739658Y1079007D01*
X1740858D01*
X1742531Y1077334D01*
X1743582D01*
X1744571Y1076345D01*
X1744996D01*
G01X1754573D02*
X1755165D01*
X1756140Y1077320D01*
X1758713D01*
X1760467Y1079074D01*
X1762741D01*
X1763797Y1078018D01*
X1766033D01*
G01X1731983Y1094751D02*
X1736333D01*
G01D02*
X1742619D01*
X1744292Y1096424D01*
X1745209D01*
G01X1755018D02*
X1756564D01*
X1757354Y1095634D01*
Y1094380D01*
X1758144Y1093590D01*
X1759619D01*
X1760780Y1094751D01*
X1766033D01*
G01X1731983Y1088058D02*
X1736333D01*
G01D02*
X1743047D01*
X1744720Y1089731D01*
X1745209D01*
G01X1755018D02*
X1756564D01*
X1757354Y1088941D01*
Y1087771D01*
X1758144Y1086981D01*
X1759703D01*
X1760780Y1088058D01*
X1766033D01*
G01X1731983Y1081365D02*
X1736333D01*
G01D02*
X1738422D01*
X1739490Y1080297D01*
X1741393D01*
X1743066Y1078624D01*
X1743572D01*
X1744640Y1079692D01*
X1745209D01*
G01X1754688D02*
X1755167D01*
X1756249Y1078610D01*
X1758178D01*
X1759932Y1080364D01*
X1763049D01*
X1764050Y1081365D01*
X1766033D01*
G01X1731818Y1108137D02*
X1736333D01*
G01D02*
X1743019D01*
X1744720Y1109838D01*
X1745869D01*
G01X1753869Y1109858D02*
X1756551D01*
X1757354Y1109055D01*
Y1108067D01*
X1758276Y1107145D01*
X1759788D01*
X1760780Y1108137D01*
X1766033D01*
G01X1731983Y1101444D02*
X1736333D01*
G01D02*
X1743019D01*
X1744720Y1103145D01*
X1745869D01*
G01X1753869Y1103165D02*
X1756551D01*
X1757354Y1102362D01*
Y1101374D01*
X1758276Y1100452D01*
X1759788D01*
X1760780Y1101444D01*
X1766033D01*
G01X1731983Y1124869D02*
X1736333D01*
G01D02*
X1743019D01*
X1744720Y1126570D01*
X1745869D01*
G01X1753869Y1126590D02*
X1756551D01*
X1757354Y1125787D01*
Y1124799D01*
X1758276Y1123877D01*
X1759788D01*
X1760780Y1124869D01*
X1766033D01*
G01X1731983Y1118176D02*
X1736333D01*
G01D02*
X1738422D01*
X1739490Y1117108D01*
X1741393D01*
X1743066Y1115435D01*
X1743548D01*
X1744640Y1116527D01*
X1745869D01*
G01X1753869Y1116546D02*
X1755124D01*
X1756249Y1115421D01*
X1758178D01*
X1759932Y1117175D01*
X1763049D01*
X1764050Y1118176D01*
X1766033D01*
G01X1731983Y1114829D02*
X1736333D01*
G01D02*
X1738669D01*
X1739658Y1115818D01*
X1740858D01*
X1742531Y1114145D01*
X1743627D01*
X1744644Y1113128D01*
X1745869D01*
G01X1753869Y1113127D02*
X1755136D01*
X1756140Y1114131D01*
X1758713D01*
X1760467Y1115885D01*
X1762741D01*
X1763797Y1114829D01*
X1766033D01*
G01X1731983Y1144947D02*
X1731984Y1144948D01*
X1736333D01*
G01X1731983Y1138255D02*
X1736333D01*
G01D02*
X1743019D01*
X1744720Y1139956D01*
X1745869D01*
G01X1753869Y1139976D02*
X1756551D01*
X1757354Y1139173D01*
Y1138185D01*
X1758276Y1137263D01*
X1759788D01*
X1760780Y1138255D01*
X1766033D01*
G01X1731983Y1131562D02*
X1736333D01*
G01D02*
X1743019D01*
X1744720Y1133263D01*
X1745869D01*
G01X1753869Y1133283D02*
X1756551D01*
X1757354Y1132480D01*
Y1131492D01*
X1758276Y1130570D01*
X1759788D01*
X1760780Y1131562D01*
X1766033D01*
G01X1736333Y1144948D02*
X1743019D01*
X1744720Y1146649D01*
X1745869D01*
G01X1753869Y1146669D02*
X1756551D01*
X1757354Y1145866D01*
Y1144878D01*
X1758276Y1143956D01*
X1759788D01*
X1760780Y1144948D01*
X1766033D01*
G01X1731983Y1154987D02*
X1736333D01*
G01D02*
X1738422D01*
X1739490Y1153919D01*
X1741393D01*
X1743066Y1152246D01*
X1743548D01*
X1744640Y1153338D01*
X1745869D01*
G01X1753869Y1153357D02*
X1755124D01*
X1756249Y1152232D01*
X1758178D01*
X1759932Y1153986D01*
X1763049D01*
X1764050Y1154987D01*
X1766033D01*
G01X1731983Y1151640D02*
X1731984Y1151641D01*
X1736333D01*
G01D02*
X1738670D01*
X1739658Y1152629D01*
X1740858D01*
X1742531Y1150956D01*
X1743627D01*
X1744643Y1149940D01*
X1745869D01*
G01X1753869Y1149939D02*
X1755137D01*
X1756140Y1150942D01*
X1758713D01*
X1760467Y1152696D01*
X1762741D01*
X1763796Y1151641D01*
X1766033D01*
G01X1731983Y1175066D02*
X1736333D01*
G01D02*
X1743019D01*
X1744720Y1176767D01*
X1745869D01*
G01X1753869Y1176787D02*
X1756551D01*
X1757354Y1175984D01*
Y1174996D01*
X1758276Y1174074D01*
X1759788D01*
X1760780Y1175066D01*
X1766033D01*
G01X1731983Y1168373D02*
X1736333D01*
G01D02*
X1743019D01*
X1744720Y1170074D01*
X1745869D01*
G01X1753869Y1170094D02*
X1756551D01*
X1757354Y1169291D01*
Y1168303D01*
X1758276Y1167381D01*
X1759788D01*
X1760780Y1168373D01*
X1766033D01*
G01X1731983Y1161680D02*
X1736333D01*
G01D02*
X1743019D01*
X1744720Y1163381D01*
X1745869D01*
G01X1753869Y1163401D02*
X1756551D01*
X1757354Y1162598D01*
Y1161610D01*
X1758276Y1160688D01*
X1759788D01*
X1760780Y1161680D01*
X1766033D01*
G01X1731818Y1181759D02*
X1736333D01*
G01D02*
X1743019D01*
X1744720Y1183460D01*
X1745869D01*
G01X1753869Y1183480D02*
X1756551D01*
X1757354Y1182677D01*
Y1181689D01*
X1758276Y1180767D01*
X1759788D01*
X1760780Y1181759D01*
X1766033D01*
G01X1731983Y1191798D02*
X1736333D01*
G01D02*
X1738422D01*
X1739490Y1190730D01*
X1741393D01*
X1743066Y1189057D01*
X1743548D01*
X1744640Y1190149D01*
X1745869D01*
G01X1753869Y1190168D02*
X1755124D01*
X1756249Y1189043D01*
X1758178D01*
X1759932Y1190797D01*
X1763049D01*
X1764050Y1191798D01*
X1766033D01*
G01X1731818Y1188452D02*
X1736333D01*
G01D02*
X1738670D01*
X1739658Y1189440D01*
X1740858D01*
X1742531Y1187767D01*
X1743627D01*
X1744643Y1186751D01*
X1745869D01*
G01X1753869Y1186750D02*
X1755137D01*
X1756140Y1187753D01*
X1758713D01*
X1760467Y1189507D01*
X1762741D01*
X1763796Y1188452D01*
X1766033D01*
G01X1731983Y1205184D02*
X1736333D01*
G01D02*
X1743019D01*
X1744720Y1206885D01*
X1745869D01*
G01X1753869Y1206905D02*
X1756551D01*
X1757354Y1206102D01*
Y1205114D01*
X1758276Y1204192D01*
X1759788D01*
X1760780Y1205184D01*
X1766033D01*
G01X1731983Y1198491D02*
X1736333D01*
G01D02*
X1743019D01*
X1744720Y1200192D01*
X1745869D01*
G01X1753869Y1200212D02*
X1756551D01*
X1757354Y1199409D01*
Y1198421D01*
X1758276Y1197499D01*
X1759788D01*
X1760780Y1198491D01*
X1766033D01*
G01X1731983Y1218569D02*
X1731984Y1218570D01*
X1736333D01*
G01D02*
X1743019D01*
X1744720Y1220271D01*
X1745869D01*
G01X1753869Y1220291D02*
X1756551D01*
X1757354Y1219488D01*
Y1218500D01*
X1758276Y1217578D01*
X1759788D01*
X1760780Y1218570D01*
X1766033D01*
G01X1731983Y1211877D02*
X1736333D01*
G01D02*
X1743019D01*
X1744720Y1213578D01*
X1745869D01*
G01X1753869Y1213598D02*
X1756551D01*
X1757354Y1212795D01*
Y1211807D01*
X1758276Y1210885D01*
X1759788D01*
X1760780Y1211877D01*
X1766033D01*
G01X1731983Y1225262D02*
X1731984Y1225263D01*
X1736333D01*
G01D02*
X1738670D01*
X1739658Y1226251D01*
X1740858D01*
X1742531Y1224578D01*
X1743627D01*
X1744643Y1223562D01*
X1745869D01*
G01X1753869Y1223561D02*
X1755137D01*
X1756140Y1224564D01*
X1758713D01*
X1760467Y1226318D01*
X1762741D01*
X1763796Y1225263D01*
X1766033D01*
G01X1731983Y1241995D02*
X1736333D01*
G01D02*
X1743019D01*
X1744720Y1243696D01*
X1745869D01*
G01X1753869Y1243716D02*
X1756551D01*
X1757354Y1242913D01*
Y1241925D01*
X1758276Y1241003D01*
X1759788D01*
X1760780Y1241995D01*
X1766033D01*
G01X1731983Y1235302D02*
X1736333D01*
G01D02*
X1743019D01*
X1744720Y1237003D01*
X1745869D01*
G01X1753869Y1237023D02*
X1756551D01*
X1757354Y1236220D01*
Y1235232D01*
X1758276Y1234310D01*
X1759788D01*
X1760780Y1235302D01*
X1766033D01*
G01X1731983Y1228609D02*
X1736333D01*
G01D02*
X1738422D01*
X1739490Y1227541D01*
X1741393D01*
X1743066Y1225868D01*
X1743548D01*
X1744640Y1226960D01*
X1745869D01*
G01X1753869Y1226979D02*
X1755124D01*
X1756249Y1225854D01*
X1758178D01*
X1759932Y1227608D01*
X1763049D01*
X1764050Y1228609D01*
X1766033D01*
G01X1749891Y960892D02*
X1745541D01*
G01Y957546D02*
X1749891D01*
G01Y967585D02*
X1745541D01*
G01Y1054593D02*
X1749891D01*
G01X1766033Y964239D02*
X1761683D01*
G01X1766033Y1021129D02*
X1761683D01*
G01Y1024475D02*
X1766033D01*
G01X1761683Y1051247D02*
X1766033D01*
G01X1809291Y780184D02*
X1809290Y780185D01*
X1803024D01*
X1801325Y778486D01*
X1799711D01*
G01X1790990Y778511D02*
X1789633D01*
X1789168Y778976D01*
Y780423D01*
X1788428Y781163D01*
X1786557D01*
X1785578Y780184D01*
X1779591D01*
G01D02*
X1775241D01*
G01X1809291Y773491D02*
X1809290Y773492D01*
X1803024D01*
X1801325Y771793D01*
X1799711D01*
G01X1790990Y771818D02*
X1789633D01*
X1789168Y772283D01*
Y773730D01*
X1788428Y774470D01*
X1786557D01*
X1785578Y773491D01*
X1779591D01*
G01D02*
X1775241D01*
G01Y786877D02*
X1779591D01*
G01X1809291D02*
X1806971D01*
X1806024Y787824D01*
X1804715D01*
X1803099Y789440D01*
X1801898D01*
X1800987Y788529D01*
X1799711D01*
G01X1791092Y788550D02*
X1790511D01*
X1789443Y789618D01*
X1787389D01*
X1785757Y787986D01*
X1782860D01*
X1781751Y786877D01*
X1779591D01*
G01X1809291Y796916D02*
X1809290Y796917D01*
X1803024D01*
X1801325Y795218D01*
X1799711D01*
G01X1790990Y795243D02*
X1789633D01*
X1789168Y795708D01*
Y797155D01*
X1788428Y797895D01*
X1786557D01*
X1785578Y796916D01*
X1779591D01*
G01D02*
X1775241D01*
G01Y790223D02*
X1779591D01*
G01X1809291D02*
X1807131D01*
X1806022Y789114D01*
X1805250D01*
X1803634Y790730D01*
X1802175D01*
X1800984Y791921D01*
X1799711D01*
G01X1791092Y791897D02*
X1790543D01*
X1789554Y790908D01*
X1786854D01*
X1785222Y789276D01*
X1782858D01*
X1781911Y790223D01*
X1779591D01*
G01X1809291Y816995D02*
X1809290Y816996D01*
X1803024D01*
X1801325Y815297D01*
X1799711D01*
G01X1790990Y815322D02*
X1789633D01*
X1789168Y815787D01*
Y817234D01*
X1788428Y817974D01*
X1786557D01*
X1785578Y816995D01*
X1779591D01*
G01D02*
X1775241D01*
G01X1809291Y810302D02*
X1809290Y810303D01*
X1803024D01*
X1801325Y808604D01*
X1799711D01*
G01X1790990Y808629D02*
X1789633D01*
X1789168Y809094D01*
Y810541D01*
X1788428Y811281D01*
X1786557D01*
X1785578Y810302D01*
X1779591D01*
G01D02*
X1775241D01*
G01X1809291Y803609D02*
X1809290Y803610D01*
X1803024D01*
X1801325Y801911D01*
X1799711D01*
G01X1790990Y801936D02*
X1789633D01*
X1789168Y802401D01*
Y803848D01*
X1788428Y804588D01*
X1786557D01*
X1785578Y803609D01*
X1779591D01*
G01D02*
X1775241D01*
G01X1809291Y833727D02*
X1809290Y833728D01*
X1803024D01*
X1801325Y832029D01*
X1799711D01*
G01X1790990Y832054D02*
X1789633D01*
X1789168Y832519D01*
Y833966D01*
X1788428Y834706D01*
X1786557D01*
X1785578Y833727D01*
X1779591D01*
G01D02*
X1775241D01*
G01Y823688D02*
X1779591D01*
G01D02*
X1781751D01*
X1782860Y824797D01*
X1785757D01*
X1787389Y826429D01*
X1789443D01*
X1790511Y825361D01*
X1791092D01*
G01X1799711Y825340D02*
X1800987D01*
X1801898Y826251D01*
X1803099D01*
X1804715Y824635D01*
X1806024D01*
X1806971Y823688D01*
X1809291D01*
G01X1775241Y827034D02*
X1779591D01*
G01D02*
X1781911D01*
X1782858Y826087D01*
X1785222D01*
X1786854Y827719D01*
X1789554D01*
X1790543Y828708D01*
X1791092D01*
G01X1799711Y828732D02*
X1800984D01*
X1802175Y827541D01*
X1803634D01*
X1805250Y825925D01*
X1806022D01*
X1807131Y827034D01*
X1809291D01*
G01Y847113D02*
X1809290Y847114D01*
X1803024D01*
X1801325Y845415D01*
X1799711D01*
G01X1790990Y845440D02*
X1789633D01*
X1789168Y845905D01*
Y847352D01*
X1788428Y848092D01*
X1786557D01*
X1785578Y847113D01*
X1779591D01*
G01D02*
X1775241D01*
G01X1809291Y840420D02*
X1809290Y840421D01*
X1803024D01*
X1801325Y838722D01*
X1799711D01*
G01X1790990Y838747D02*
X1789633D01*
X1789168Y839212D01*
Y840659D01*
X1788428Y841399D01*
X1786557D01*
X1785578Y840420D01*
X1779591D01*
G01D02*
X1775241D01*
G01X1809291Y853806D02*
X1809290Y853807D01*
X1803024D01*
X1801325Y852108D01*
X1799711D01*
G01X1790990Y852133D02*
X1789633D01*
X1789168Y852598D01*
Y854045D01*
X1788428Y854785D01*
X1786557D01*
X1785578Y853806D01*
X1779591D01*
G01D02*
X1775241D01*
G01Y860499D02*
X1779591D01*
G01X1809291D02*
X1806971D01*
X1806024Y861446D01*
X1804715D01*
X1803099Y863062D01*
X1801898D01*
X1800987Y862151D01*
X1799711D01*
G01X1791092Y862172D02*
X1790511D01*
X1789443Y863240D01*
X1787389D01*
X1785757Y861608D01*
X1782860D01*
X1781751Y860499D01*
X1779591D01*
G01X1775241Y863845D02*
X1779591D01*
G01X1809291D02*
X1807131D01*
X1806022Y862736D01*
X1805250D01*
X1803634Y864352D01*
X1802175D01*
X1800984Y865543D01*
X1799711D01*
G01X1791092Y865519D02*
X1790543D01*
X1789554Y864530D01*
X1786854D01*
X1785222Y862898D01*
X1782858D01*
X1781911Y863845D01*
X1779591D01*
G01X1809291Y883924D02*
X1809290Y883925D01*
X1803024D01*
X1801325Y882226D01*
X1799711D01*
G01X1790990Y882251D02*
X1789633D01*
X1789168Y882716D01*
Y884163D01*
X1788428Y884903D01*
X1786557D01*
X1785578Y883924D01*
X1779591D01*
G01D02*
X1775241D01*
G01X1809291Y877231D02*
X1809290Y877232D01*
X1803024D01*
X1801325Y875533D01*
X1799711D01*
G01X1790990Y875558D02*
X1789633D01*
X1789168Y876023D01*
Y877470D01*
X1788428Y878210D01*
X1786557D01*
X1785578Y877231D01*
X1779591D01*
G01D02*
X1775241D01*
G01X1809291Y870538D02*
X1809290Y870539D01*
X1803024D01*
X1801325Y868840D01*
X1799711D01*
G01X1790990Y868865D02*
X1789633D01*
X1789168Y869330D01*
Y870777D01*
X1788428Y871517D01*
X1786557D01*
X1785578Y870538D01*
X1779591D01*
G01D02*
X1775241D01*
G01X1809291Y890617D02*
X1809290Y890618D01*
X1803024D01*
X1801325Y888919D01*
X1799711D01*
G01X1790990Y888944D02*
X1789633D01*
X1789168Y889409D01*
Y890856D01*
X1788428Y891596D01*
X1786557D01*
X1785578Y890617D01*
X1779591D01*
G01D02*
X1775241D01*
G01Y897310D02*
X1779591D01*
G01X1809291D02*
X1806971D01*
X1806024Y898257D01*
X1804715D01*
X1803099Y899873D01*
X1801898D01*
X1800987Y898962D01*
X1799711D01*
G01X1791092Y898983D02*
X1790511D01*
X1789443Y900051D01*
X1787389D01*
X1785757Y898419D01*
X1782860D01*
X1781751Y897310D01*
X1779591D01*
G01X1775241Y900656D02*
X1779591D01*
G01X1809291D02*
X1807131D01*
X1806022Y899547D01*
X1805250D01*
X1803634Y901163D01*
X1802175D01*
X1800984Y902354D01*
X1799711D01*
G01X1791092Y902330D02*
X1790543D01*
X1789554Y901341D01*
X1786854D01*
X1785222Y899709D01*
X1782858D01*
X1781911Y900656D01*
X1779591D01*
G01X1809291Y914042D02*
X1809290Y914043D01*
X1803024D01*
X1801325Y912344D01*
X1799711D01*
G01X1790990Y912369D02*
X1789633D01*
X1789168Y912834D01*
Y914281D01*
X1788428Y915021D01*
X1786557D01*
X1785578Y914042D01*
X1779591D01*
G01D02*
X1775241D01*
G01X1809291Y907349D02*
X1809290Y907350D01*
X1803024D01*
X1801325Y905651D01*
X1799711D01*
G01X1790990Y905676D02*
X1789633D01*
X1789168Y906141D01*
Y907588D01*
X1788428Y908328D01*
X1786557D01*
X1785578Y907349D01*
X1779591D01*
G01D02*
X1775241D01*
G01X1809291Y927428D02*
X1809290Y927429D01*
X1803024D01*
X1801325Y925730D01*
X1799711D01*
G01X1790990Y925755D02*
X1789633D01*
X1789168Y926220D01*
Y927667D01*
X1788428Y928407D01*
X1786557D01*
X1785578Y927428D01*
X1779591D01*
G01D02*
X1775241D01*
G01X1809291Y920735D02*
X1809290Y920736D01*
X1803024D01*
X1801325Y919037D01*
X1799711D01*
G01X1790990Y919062D02*
X1789633D01*
X1789168Y919527D01*
Y920974D01*
X1788428Y921714D01*
X1786557D01*
X1785578Y920735D01*
X1779591D01*
G01D02*
X1775241D01*
G01X1809291Y944160D02*
X1809290Y944161D01*
X1803024D01*
X1801325Y942462D01*
X1799711D01*
G01X1790990Y942487D02*
X1789633D01*
X1789168Y942952D01*
Y944399D01*
X1788428Y945139D01*
X1786557D01*
X1785578Y944160D01*
X1779591D01*
G01D02*
X1775241D01*
G01Y934121D02*
X1779591D01*
G01X1809291D02*
X1806971D01*
X1806024Y935068D01*
X1804715D01*
X1803099Y936684D01*
X1801898D01*
X1800987Y935773D01*
X1799711D01*
G01X1791092Y935794D02*
X1790511D01*
X1789443Y936862D01*
X1787389D01*
X1785757Y935230D01*
X1782860D01*
X1781751Y934121D01*
X1779591D01*
G01X1775241Y937467D02*
X1779591D01*
G01X1809291D02*
X1807131D01*
X1806022Y936358D01*
X1805250D01*
X1803634Y937974D01*
X1802175D01*
X1800984Y939165D01*
X1799711D01*
G01X1791092Y939141D02*
X1790543D01*
X1789554Y938152D01*
X1786854D01*
X1785222Y936520D01*
X1782858D01*
X1781911Y937467D01*
X1779591D01*
G01Y960892D02*
X1775241D01*
G01X1809291Y950853D02*
X1809290Y950854D01*
X1803024D01*
X1801325Y949155D01*
X1799711D01*
G01X1790990Y949180D02*
X1789633D01*
X1789168Y949645D01*
Y951092D01*
X1788428Y951832D01*
X1786557D01*
X1785578Y950853D01*
X1779591D01*
G01D02*
X1775241D01*
G01Y957546D02*
X1779591D01*
G01X1775241Y980971D02*
X1779591D01*
G01D02*
X1783786D01*
X1785732Y979025D01*
X1787013D01*
X1790632Y982644D01*
X1791055D01*
G01X1799711Y982693D02*
X1801349D01*
X1803072Y980970D01*
X1809290D01*
X1809291Y980971D01*
G01X1775241Y974278D02*
X1779591D01*
G01D02*
X1783786D01*
X1785732Y972332D01*
X1787013D01*
X1790632Y975951D01*
X1791055D01*
G01X1799711Y976000D02*
X1801349D01*
X1803072Y974277D01*
X1809290D01*
X1809291Y974278D01*
G01X1779591Y967585D02*
X1775241D01*
G01Y994357D02*
X1779591D01*
G01D02*
X1784403D01*
X1785602Y993158D01*
X1787752D01*
X1791364Y996770D01*
X1802543D01*
X1804956Y994357D01*
X1809291D01*
G01X1775241Y987664D02*
X1779591D01*
G01D02*
X1783786D01*
X1785732Y985718D01*
X1787013D01*
X1790632Y989337D01*
X1791055D01*
G01X1799711Y989386D02*
X1801349D01*
X1803072Y987663D01*
X1809290D01*
X1809291Y987664D01*
G01X1775241Y1027822D02*
X1779591D01*
G01D02*
X1783786D01*
X1785732Y1025876D01*
X1787013D01*
X1790632Y1029495D01*
X1791055D01*
G01X1799711Y1029544D02*
X1801349D01*
X1803072Y1027821D01*
X1809290D01*
X1809291Y1027822D01*
G01X1775241Y1021129D02*
X1779591D01*
G01D02*
X1783086D01*
X1786599Y1017616D01*
X1788081D01*
X1789921Y1019456D01*
X1791019D01*
G01X1799711Y1019505D02*
X1801894D01*
X1803518Y1021129D01*
X1809291D01*
G01X1779591Y1047900D02*
X1783240D01*
X1785186Y1045954D01*
X1786453D01*
X1790072Y1049573D01*
X1790684D01*
G01X1799711Y1049622D02*
X1801349D01*
X1803072Y1047899D01*
X1809290D01*
X1809291Y1047900D01*
G01X1775241Y1041207D02*
X1779591D01*
G01D02*
X1783786D01*
X1785732Y1039261D01*
X1787013D01*
X1790632Y1042880D01*
X1791055D01*
G01X1799711Y1042929D02*
X1801349D01*
X1803072Y1041206D01*
X1809290D01*
X1809291Y1041207D01*
G01X1775241Y1034515D02*
X1779591D01*
G01D02*
X1783786D01*
X1785732Y1032569D01*
X1787013D01*
X1790632Y1036188D01*
X1791055D01*
G01X1799711Y1036237D02*
X1801349D01*
X1803072Y1034514D01*
X1809290D01*
X1809291Y1034515D01*
G01Y1061286D02*
X1809290Y1061287D01*
X1805847D01*
X1805509Y1061625D01*
X1804158D01*
X1801983Y1059450D01*
X1799711D01*
G01X1790907Y1059613D02*
X1790438D01*
X1789288Y1060763D01*
Y1061464D01*
X1788588Y1062164D01*
X1786288D01*
X1785788Y1062664D01*
X1783058D01*
X1781680Y1061286D01*
X1779591D01*
G01D02*
X1775241D01*
G01Y1047900D02*
X1779591D01*
G01Y1054593D02*
X1775241D01*
G01X1809291Y1074672D02*
X1809290Y1074673D01*
X1803024D01*
X1801325Y1072974D01*
X1799711D01*
G01X1790990Y1072999D02*
X1789633D01*
X1789168Y1073464D01*
Y1074911D01*
X1788428Y1075651D01*
X1786557D01*
X1785578Y1074672D01*
X1779591D01*
G01D02*
X1775241D01*
G01X1809291Y1067979D02*
X1809290Y1067980D01*
X1803024D01*
X1801325Y1066281D01*
X1799711D01*
G01X1790990Y1066306D02*
X1789633D01*
X1789168Y1066771D01*
Y1068218D01*
X1788428Y1068958D01*
X1786557D01*
X1785578Y1067979D01*
X1779591D01*
G01D02*
X1775241D01*
G01X1809291Y1091404D02*
X1809290Y1091405D01*
X1803024D01*
X1801325Y1089706D01*
X1799711D01*
G01X1790990Y1089731D02*
X1789633D01*
X1789168Y1090196D01*
Y1091643D01*
X1788428Y1092383D01*
X1786557D01*
X1785578Y1091404D01*
X1779591D01*
G01D02*
X1775241D01*
G01Y1081365D02*
X1779591D01*
G01X1809291D02*
X1806971D01*
X1806024Y1082312D01*
X1804715D01*
X1803099Y1083928D01*
X1801898D01*
X1800987Y1083017D01*
X1799711D01*
G01X1791092Y1083038D02*
X1790511D01*
X1789443Y1084106D01*
X1787389D01*
X1785757Y1082474D01*
X1782860D01*
X1781751Y1081365D01*
X1779591D01*
G01X1775241Y1084711D02*
X1779591D01*
G01X1809291D02*
X1807131D01*
X1806022Y1083602D01*
X1805250D01*
X1803634Y1085218D01*
X1802175D01*
X1800984Y1086409D01*
X1799711D01*
G01X1791092Y1086385D02*
X1790543D01*
X1789554Y1085396D01*
X1786854D01*
X1785222Y1083764D01*
X1782858D01*
X1781911Y1084711D01*
X1779591D01*
G01X1809291Y1098097D02*
X1809290Y1098098D01*
X1803024D01*
X1801325Y1096399D01*
X1799711D01*
G01X1790990Y1096424D02*
X1789633D01*
X1789168Y1096889D01*
Y1098336D01*
X1788428Y1099076D01*
X1786557D01*
X1785578Y1098097D01*
X1779591D01*
G01D02*
X1775241D01*
G01X1809291Y1111483D02*
X1809290Y1111484D01*
X1803024D01*
X1801325Y1109785D01*
X1799711D01*
G01X1790990Y1109810D02*
X1789633D01*
X1789168Y1110275D01*
Y1111722D01*
X1788428Y1112462D01*
X1786557D01*
X1785578Y1111483D01*
X1779591D01*
G01D02*
X1775241D01*
G01X1809291Y1104790D02*
X1809290Y1104791D01*
X1803024D01*
X1801325Y1103092D01*
X1799711D01*
G01X1790990Y1103117D02*
X1789633D01*
X1789168Y1103582D01*
Y1105029D01*
X1788428Y1105769D01*
X1786557D01*
X1785578Y1104790D01*
X1779591D01*
G01D02*
X1775241D01*
G01X1809291Y1128215D02*
X1809290Y1128216D01*
X1803024D01*
X1801325Y1126517D01*
X1799711D01*
G01X1790990Y1126542D02*
X1789633D01*
X1789168Y1127007D01*
Y1128454D01*
X1788428Y1129194D01*
X1786557D01*
X1785578Y1128215D01*
X1779591D01*
G01D02*
X1775241D01*
G01Y1118176D02*
X1779591D01*
G01X1809291D02*
X1806971D01*
X1806024Y1119123D01*
X1804715D01*
X1803099Y1120739D01*
X1801898D01*
X1800987Y1119828D01*
X1799711D01*
G01X1791092Y1119849D02*
X1790511D01*
X1789443Y1120917D01*
X1787389D01*
X1785757Y1119285D01*
X1782860D01*
X1781751Y1118176D01*
X1779591D01*
G01X1775241Y1121522D02*
X1779591D01*
G01X1809291D02*
X1807131D01*
X1806022Y1120413D01*
X1805250D01*
X1803634Y1122029D01*
X1802175D01*
X1800984Y1123220D01*
X1799711D01*
G01X1791092Y1123196D02*
X1790543D01*
X1789554Y1122207D01*
X1786854D01*
X1785222Y1120575D01*
X1782858D01*
X1781911Y1121522D01*
X1779591D01*
G01X1809291Y1141601D02*
X1809290Y1141602D01*
X1803024D01*
X1801325Y1139903D01*
X1799711D01*
G01X1790990Y1139928D02*
X1789633D01*
X1789168Y1140393D01*
Y1141840D01*
X1788428Y1142580D01*
X1786557D01*
X1785578Y1141601D01*
X1779591D01*
G01D02*
X1775241D01*
G01X1809291Y1134908D02*
X1809290Y1134909D01*
X1803024D01*
X1801325Y1133210D01*
X1799711D01*
G01X1790990Y1133235D02*
X1789633D01*
X1789168Y1133700D01*
Y1135147D01*
X1788428Y1135887D01*
X1786557D01*
X1785578Y1134908D01*
X1779591D01*
G01D02*
X1775241D01*
G01X1809291Y1148294D02*
X1809290Y1148295D01*
X1803024D01*
X1801325Y1146596D01*
X1799711D01*
G01X1790990Y1146621D02*
X1789633D01*
X1789168Y1147086D01*
Y1148533D01*
X1788428Y1149273D01*
X1786557D01*
X1785578Y1148294D01*
X1779591D01*
G01D02*
X1775241D01*
G01Y1154987D02*
X1779591D01*
G01X1809291D02*
X1806971D01*
X1806024Y1155934D01*
X1804715D01*
X1803099Y1157550D01*
X1801898D01*
X1800987Y1156639D01*
X1799711D01*
G01X1791092Y1156660D02*
X1790511D01*
X1789443Y1157728D01*
X1787389D01*
X1785757Y1156096D01*
X1782860D01*
X1781751Y1154987D01*
X1779591D01*
G01X1775241Y1158333D02*
X1779591D01*
G01X1809291D02*
X1807131D01*
X1806022Y1157224D01*
X1805250D01*
X1803634Y1158840D01*
X1802175D01*
X1800984Y1160031D01*
X1799711D01*
G01X1791092Y1160007D02*
X1790543D01*
X1789554Y1159018D01*
X1786854D01*
X1785222Y1157386D01*
X1782858D01*
X1781911Y1158333D01*
X1779591D01*
G01X1809291Y1171719D02*
X1809290Y1171720D01*
X1803024D01*
X1801325Y1170021D01*
X1799711D01*
G01X1790990Y1170046D02*
X1789633D01*
X1789168Y1170511D01*
Y1171958D01*
X1788428Y1172698D01*
X1786557D01*
X1785578Y1171719D01*
X1779591D01*
G01D02*
X1775241D01*
G01X1809291Y1165026D02*
X1809290Y1165027D01*
X1803024D01*
X1801325Y1163328D01*
X1799711D01*
G01X1790990Y1163353D02*
X1789633D01*
X1789168Y1163818D01*
Y1165265D01*
X1788428Y1166005D01*
X1786557D01*
X1785578Y1165026D01*
X1779591D01*
G01D02*
X1775241D01*
G01X1809291Y1185105D02*
X1809290Y1185106D01*
X1803024D01*
X1801325Y1183407D01*
X1799711D01*
G01X1790990Y1183432D02*
X1789633D01*
X1789168Y1183897D01*
Y1185344D01*
X1788428Y1186084D01*
X1786557D01*
X1785578Y1185105D01*
X1779591D01*
G01D02*
X1775241D01*
G01X1809291Y1178412D02*
X1809290Y1178413D01*
X1803024D01*
X1801325Y1176714D01*
X1799711D01*
G01X1790990Y1176739D02*
X1789633D01*
X1789168Y1177204D01*
Y1178651D01*
X1788428Y1179391D01*
X1786557D01*
X1785578Y1178412D01*
X1779591D01*
G01D02*
X1775241D01*
G01Y1191798D02*
X1779591D01*
G01X1809291D02*
X1806971D01*
X1806024Y1192745D01*
X1804715D01*
X1803099Y1194361D01*
X1801898D01*
X1800987Y1193450D01*
X1799711D01*
G01X1791092Y1193471D02*
X1790511D01*
X1789443Y1194539D01*
X1787389D01*
X1785757Y1192907D01*
X1782860D01*
X1781751Y1191798D01*
X1779591D01*
G01X1809291Y1208530D02*
X1809290Y1208531D01*
X1803024D01*
X1801325Y1206832D01*
X1799711D01*
G01X1790990Y1206857D02*
X1789633D01*
X1789168Y1207322D01*
Y1208769D01*
X1788428Y1209509D01*
X1786557D01*
X1785578Y1208530D01*
X1779591D01*
G01D02*
X1775241D01*
G01X1809291Y1201837D02*
X1809290Y1201838D01*
X1803024D01*
X1801325Y1200139D01*
X1799711D01*
G01X1790990Y1200164D02*
X1789633D01*
X1789168Y1200629D01*
Y1202076D01*
X1788428Y1202816D01*
X1786557D01*
X1785578Y1201837D01*
X1779591D01*
G01D02*
X1775241D01*
G01Y1195144D02*
X1779591D01*
G01X1809291D02*
X1807131D01*
X1806022Y1194035D01*
X1805250D01*
X1803634Y1195651D01*
X1802175D01*
X1800984Y1196842D01*
X1799711D01*
G01X1791092Y1196818D02*
X1790543D01*
X1789554Y1195829D01*
X1786854D01*
X1785222Y1194197D01*
X1782858D01*
X1781911Y1195144D01*
X1779591D01*
G01X1809291Y1221916D02*
X1809290Y1221917D01*
X1803024D01*
X1801325Y1220218D01*
X1799711D01*
G01X1790990Y1220243D02*
X1789633D01*
X1789168Y1220708D01*
Y1222155D01*
X1788428Y1222895D01*
X1786557D01*
X1785578Y1221916D01*
X1779591D01*
G01D02*
X1775241D01*
G01X1809291Y1215223D02*
X1809290Y1215224D01*
X1803024D01*
X1801325Y1213525D01*
X1799711D01*
G01X1790990Y1213550D02*
X1789633D01*
X1789168Y1214015D01*
Y1215462D01*
X1788428Y1216202D01*
X1786557D01*
X1785578Y1215223D01*
X1779591D01*
G01D02*
X1775241D01*
G01X1809291Y1238648D02*
X1809290Y1238649D01*
X1803024D01*
X1801325Y1236950D01*
X1799711D01*
G01X1790990Y1236975D02*
X1789633D01*
X1789168Y1237440D01*
Y1238887D01*
X1788428Y1239627D01*
X1786557D01*
X1785578Y1238648D01*
X1779591D01*
G01D02*
X1775241D01*
G01Y1228609D02*
X1779591D01*
G01D02*
X1781751D01*
X1782860Y1229718D01*
X1785757D01*
X1787389Y1231350D01*
X1789443D01*
X1790511Y1230282D01*
X1791092D01*
G01X1799711Y1230261D02*
X1800987D01*
X1801898Y1231172D01*
X1803099D01*
X1804715Y1229556D01*
X1806024D01*
X1806971Y1228609D01*
X1809291D01*
G01X1775241Y1231955D02*
X1779591D01*
G01D02*
X1781911D01*
X1782858Y1231008D01*
X1785222D01*
X1786854Y1232640D01*
X1789554D01*
X1790543Y1233629D01*
X1791092D01*
G01X1799711Y1233653D02*
X1800984D01*
X1802175Y1232462D01*
X1803634D01*
X1805250Y1230846D01*
X1806022D01*
X1807131Y1231955D01*
X1809291D01*
G01Y1245341D02*
X1809290Y1245342D01*
X1803024D01*
X1801325Y1243643D01*
X1799711D01*
G01X1790990Y1243668D02*
X1789633D01*
X1789168Y1244133D01*
Y1245580D01*
X1788428Y1246320D01*
X1786557D01*
X1785578Y1245341D01*
X1779591D01*
G01D02*
X1775241D01*
G01X1791383Y770144D02*
X1795733D01*
G01D02*
X1802419D01*
X1804120Y771845D01*
X1805269D01*
G01X1813269Y771865D02*
X1815951D01*
X1816754Y771062D01*
Y770074D01*
X1817676Y769152D01*
X1819188D01*
X1820180Y770144D01*
X1825433D01*
G01X1791383Y776837D02*
X1795733D01*
G01D02*
X1802419D01*
X1804120Y778538D01*
X1805269D01*
G01X1813269Y778558D02*
X1815951D01*
X1816754Y777755D01*
Y776767D01*
X1817676Y775845D01*
X1819188D01*
X1820180Y776837D01*
X1825433D01*
G01X1791383Y786877D02*
X1795733D01*
G01X1825433D02*
X1823450D01*
X1822449Y785876D01*
X1819332D01*
X1817578Y784122D01*
X1815649D01*
X1814524Y785247D01*
X1813269D01*
G01X1805269Y785228D02*
X1804040D01*
X1802948Y784136D01*
X1802466D01*
X1800793Y785809D01*
X1798890D01*
X1797822Y786877D01*
X1795733D01*
G01X1791383Y783530D02*
X1795733D01*
G01X1825433D02*
X1823197D01*
X1822141Y784586D01*
X1819867D01*
X1818113Y782832D01*
X1815540D01*
X1814536Y781828D01*
X1813269D01*
G01X1805269Y781829D02*
X1804044D01*
X1803027Y782846D01*
X1801931D01*
X1800258Y784519D01*
X1799058D01*
X1798069Y783530D01*
X1795733D01*
G01X1791383Y800263D02*
X1795733D01*
G01D02*
X1802419D01*
X1804120Y801964D01*
X1805269D01*
G01X1813269Y801984D02*
X1815951D01*
X1816754Y801181D01*
Y800193D01*
X1817676Y799271D01*
X1819188D01*
X1820180Y800263D01*
X1825433D01*
G01X1791383Y793570D02*
X1795733D01*
G01D02*
X1802419D01*
X1804120Y795271D01*
X1805269D01*
G01X1813269Y795291D02*
X1815951D01*
X1816754Y794488D01*
Y793500D01*
X1817676Y792578D01*
X1819188D01*
X1820180Y793570D01*
X1825433D01*
G01X1791383Y813648D02*
X1795733D01*
G01D02*
X1802419D01*
X1804120Y815349D01*
X1805269D01*
G01X1813269Y815369D02*
X1815951D01*
X1816754Y814566D01*
Y813578D01*
X1817676Y812656D01*
X1819188D01*
X1820180Y813648D01*
X1825433D01*
G01X1791383Y806955D02*
X1795733D01*
G01D02*
X1802419D01*
X1804120Y808656D01*
X1805269D01*
G01X1813269Y808676D02*
X1815951D01*
X1816754Y807873D01*
Y806885D01*
X1817676Y805963D01*
X1819188D01*
X1820180Y806955D01*
X1825433D01*
G01X1795733Y820341D02*
X1798069D01*
X1799058Y821330D01*
X1800258D01*
X1801931Y819657D01*
X1803027D01*
X1804044Y818640D01*
X1805269D01*
G01X1813269Y818639D02*
X1814536D01*
X1815540Y819643D01*
X1818113D01*
X1819867Y821397D01*
X1822141D01*
X1823197Y820341D01*
X1825433D01*
G01X1791383Y830381D02*
X1795733D01*
G01D02*
X1802419D01*
X1804120Y832082D01*
X1805269D01*
G01X1813269Y832102D02*
X1815951D01*
X1816754Y831299D01*
Y830311D01*
X1817676Y829389D01*
X1819188D01*
X1820180Y830381D01*
X1825433D01*
G01X1791383Y823688D02*
X1795733D01*
G01D02*
X1797822D01*
X1798890Y822620D01*
X1800793D01*
X1802466Y820947D01*
X1802948D01*
X1804040Y822039D01*
X1805269D01*
G01X1813269Y822058D02*
X1814524D01*
X1815649Y820933D01*
X1817578D01*
X1819332Y822687D01*
X1822449D01*
X1823450Y823688D01*
X1825433D01*
G01X1791383Y820341D02*
X1795733D01*
G01X1791383Y850459D02*
X1795733D01*
G01D02*
X1802419D01*
X1804120Y852160D01*
X1805269D01*
G01X1813269Y852180D02*
X1815951D01*
X1816754Y851377D01*
Y850389D01*
X1817676Y849467D01*
X1819188D01*
X1820180Y850459D01*
X1825433D01*
G01X1791383Y843766D02*
X1795733D01*
G01D02*
X1802419D01*
X1804120Y845467D01*
X1805269D01*
G01X1813269Y845487D02*
X1815951D01*
X1816754Y844684D01*
Y843696D01*
X1817676Y842774D01*
X1819188D01*
X1820180Y843766D01*
X1825433D01*
G01X1791383Y837074D02*
X1795733D01*
G01D02*
X1802419D01*
X1804120Y838775D01*
X1805269D01*
G01X1813269Y838795D02*
X1815951D01*
X1816754Y837992D01*
Y837004D01*
X1817676Y836082D01*
X1819188D01*
X1820180Y837074D01*
X1825433D01*
G01X1791383Y867192D02*
X1795733D01*
G01D02*
X1802419D01*
X1804120Y868893D01*
X1805269D01*
G01X1813269Y868913D02*
X1815951D01*
X1816754Y868110D01*
Y867122D01*
X1817676Y866200D01*
X1819188D01*
X1820180Y867192D01*
X1825433D01*
G01X1791383Y860499D02*
X1795733D01*
G01X1825433D02*
X1823450D01*
X1822449Y859498D01*
X1819332D01*
X1817578Y857744D01*
X1815649D01*
X1814524Y858869D01*
X1813269D01*
G01X1805269Y858850D02*
X1804040D01*
X1802948Y857758D01*
X1802466D01*
X1800793Y859431D01*
X1798890D01*
X1797822Y860499D01*
X1795733D01*
G01X1791383Y857152D02*
X1795733D01*
G01X1825433D02*
X1823197D01*
X1822141Y858208D01*
X1819867D01*
X1818113Y856454D01*
X1815540D01*
X1814536Y855450D01*
X1813269D01*
G01X1805269Y855451D02*
X1804044D01*
X1803027Y856468D01*
X1801931D01*
X1800258Y858141D01*
X1799058D01*
X1798069Y857152D01*
X1795733D01*
G01X1791383Y873885D02*
X1795733D01*
G01D02*
X1802419D01*
X1804120Y875586D01*
X1805269D01*
G01X1813269Y875606D02*
X1815951D01*
X1816754Y874803D01*
Y873815D01*
X1817676Y872893D01*
X1819188D01*
X1820180Y873885D01*
X1825433D01*
G01X1791383Y880577D02*
X1795733D01*
G01D02*
X1802419D01*
X1804120Y882278D01*
X1805269D01*
G01X1813269Y882298D02*
X1815951D01*
X1816754Y881495D01*
Y880507D01*
X1817676Y879585D01*
X1819188D01*
X1820180Y880577D01*
X1825433D01*
G01X1791383Y887270D02*
X1795733D01*
G01D02*
X1802419D01*
X1804120Y888971D01*
X1805269D01*
G01X1813269Y888991D02*
X1815951D01*
X1816754Y888188D01*
Y887200D01*
X1817676Y886278D01*
X1819188D01*
X1820180Y887270D01*
X1825433D01*
G01X1791383Y897310D02*
X1795733D01*
G01X1825433D02*
X1823450D01*
X1822449Y896309D01*
X1819332D01*
X1817578Y894555D01*
X1815649D01*
X1814524Y895680D01*
X1813269D01*
G01X1805269Y895661D02*
X1804040D01*
X1802948Y894569D01*
X1802466D01*
X1800793Y896242D01*
X1798890D01*
X1797822Y897310D01*
X1795733D01*
G01X1791383Y893963D02*
X1795733D01*
G01X1825433D02*
X1823197D01*
X1822141Y895019D01*
X1819867D01*
X1818113Y893265D01*
X1815540D01*
X1814536Y892261D01*
X1813269D01*
G01X1805269Y892262D02*
X1804044D01*
X1803027Y893279D01*
X1801931D01*
X1800258Y894952D01*
X1799058D01*
X1798069Y893963D01*
X1795733D01*
G01X1791383Y910696D02*
X1795733D01*
G01D02*
X1802419D01*
X1804120Y912397D01*
X1805269D01*
G01X1813269Y912417D02*
X1815951D01*
X1816754Y911614D01*
Y910626D01*
X1817676Y909704D01*
X1819188D01*
X1820180Y910696D01*
X1825433D01*
G01X1791383Y904003D02*
X1795733D01*
G01D02*
X1802419D01*
X1804120Y905704D01*
X1805269D01*
G01X1813269Y905724D02*
X1815951D01*
X1816754Y904921D01*
Y903933D01*
X1817676Y903011D01*
X1819188D01*
X1820180Y904003D01*
X1825433D01*
G01X1791383Y924081D02*
X1795733D01*
G01D02*
X1802419D01*
X1804120Y925782D01*
X1805269D01*
G01X1813269Y925802D02*
X1815951D01*
X1816754Y924999D01*
Y924011D01*
X1817676Y923089D01*
X1819188D01*
X1820180Y924081D01*
X1825433D01*
G01X1791383Y917389D02*
X1795733D01*
G01D02*
X1802419D01*
X1804120Y919090D01*
X1805269D01*
G01X1813269Y919110D02*
X1815951D01*
X1816754Y918307D01*
Y917319D01*
X1817676Y916397D01*
X1819188D01*
X1820180Y917389D01*
X1825433D01*
G01Y934121D02*
X1823450D01*
X1822449Y933120D01*
X1819332D01*
X1817578Y931366D01*
X1815649D01*
X1814524Y932491D01*
X1813269D01*
G01X1805269Y932472D02*
X1804040D01*
X1802948Y931380D01*
X1802466D01*
X1800793Y933053D01*
X1798890D01*
X1797822Y934121D01*
X1795733D01*
G01X1791383Y930774D02*
X1795733D01*
G01X1825433D02*
X1823197D01*
X1822141Y931830D01*
X1819867D01*
X1818113Y930076D01*
X1815540D01*
X1814536Y929072D01*
X1813269D01*
G01X1805269Y929073D02*
X1804044D01*
X1803027Y930090D01*
X1801931D01*
X1800258Y931763D01*
X1799058D01*
X1798069Y930774D01*
X1795733D01*
G01X1791383Y947507D02*
X1795733D01*
G01D02*
X1802419D01*
X1804120Y949208D01*
X1805269D01*
G01X1813269Y949228D02*
X1815951D01*
X1816754Y948425D01*
Y947437D01*
X1817676Y946515D01*
X1819188D01*
X1820180Y947507D01*
X1825433D01*
G01X1791383Y940814D02*
X1795733D01*
G01D02*
X1802419D01*
X1804120Y942515D01*
X1805269D01*
G01X1813269Y942535D02*
X1815951D01*
X1816754Y941732D01*
Y940744D01*
X1817676Y939822D01*
X1819188D01*
X1820180Y940814D01*
X1825433D01*
G01X1791383Y934121D02*
X1795733D01*
G01X1791383Y964239D02*
X1795733D01*
G01X1791383Y977625D02*
X1795733D01*
G01D02*
X1802173D01*
X1803888Y979340D01*
X1805269D01*
G01X1813269Y979327D02*
X1814348D01*
X1817753Y975922D01*
X1819342D01*
X1821045Y977625D01*
X1825433D01*
G01X1791383Y970932D02*
X1795733D01*
G01D02*
X1802173D01*
X1803888Y972647D01*
X1805269D01*
G01X1813269Y972634D02*
X1814348D01*
X1817753Y969229D01*
X1819342D01*
X1821045Y970932D01*
X1825433D01*
G01X1791383Y991011D02*
X1795733D01*
G01D02*
X1802173D01*
X1803888Y992726D01*
X1805269D01*
G01X1813269Y992713D02*
X1814348D01*
X1817753Y989308D01*
X1819342D01*
X1821045Y991011D01*
X1825433D01*
G01X1791383Y984318D02*
X1795733D01*
G01D02*
X1802173D01*
X1803888Y986033D01*
X1805269D01*
G01X1813269Y986020D02*
X1814348D01*
X1817753Y982615D01*
X1819342D01*
X1821045Y984318D01*
X1825433D01*
G01X1795733Y1021129D02*
X1791383D01*
G01Y1024475D02*
X1795733D01*
G01X1791383Y1044554D02*
X1795733D01*
G01D02*
X1802173D01*
X1803888Y1046269D01*
X1805269D01*
G01X1813269Y1046256D02*
X1814348D01*
X1817753Y1042851D01*
X1819342D01*
X1821045Y1044554D01*
X1825433D01*
G01X1791383Y1037861D02*
X1795733D01*
G01D02*
X1802173D01*
X1803888Y1039576D01*
X1805269D01*
G01X1813269Y1039563D02*
X1814348D01*
X1817753Y1036158D01*
X1819342D01*
X1821045Y1037861D01*
X1825433D01*
G01X1791383Y1031168D02*
X1795733D01*
G01D02*
X1802173D01*
X1803888Y1032883D01*
X1805269D01*
G01X1813269Y1032870D02*
X1814348D01*
X1817753Y1029465D01*
X1819342D01*
X1821045Y1031168D01*
X1825433D01*
G01X1791083Y1051247D02*
X1795733D01*
G01X1791383Y1071325D02*
X1791384Y1071326D01*
X1795733D01*
G01D02*
X1802419D01*
X1804120Y1073027D01*
X1805269D01*
G01X1813269Y1073047D02*
X1815951D01*
X1816754Y1072244D01*
Y1071256D01*
X1817676Y1070334D01*
X1819188D01*
X1820180Y1071326D01*
X1825433D01*
G01X1791383Y1064633D02*
X1795733D01*
G01D02*
X1802419D01*
X1804120Y1066334D01*
X1805269D01*
G01X1813269Y1066354D02*
X1815951D01*
X1816754Y1065551D01*
Y1064563D01*
X1817676Y1063641D01*
X1819188D01*
X1820180Y1064633D01*
X1825433D01*
G01Y1081365D02*
X1823450D01*
X1822449Y1080364D01*
X1819332D01*
X1817578Y1078610D01*
X1815649D01*
X1814524Y1079735D01*
X1813269D01*
G01X1805269Y1079716D02*
X1804040D01*
X1802948Y1078624D01*
X1802466D01*
X1800793Y1080297D01*
X1798890D01*
X1797822Y1081365D01*
X1795733D01*
G01X1791383Y1078018D02*
X1795733D01*
G01X1825433D02*
X1823197D01*
X1822141Y1079074D01*
X1819867D01*
X1818113Y1077320D01*
X1815540D01*
X1814536Y1076316D01*
X1813269D01*
G01X1805269Y1076317D02*
X1804044D01*
X1803027Y1077334D01*
X1801931D01*
X1800258Y1079007D01*
X1799058D01*
X1798069Y1078018D01*
X1795733D01*
G01X1791383Y1094751D02*
X1795733D01*
G01D02*
X1802419D01*
X1804120Y1096452D01*
X1805269D01*
G01X1813269Y1096472D02*
X1815951D01*
X1816754Y1095669D01*
Y1094681D01*
X1817676Y1093759D01*
X1819188D01*
X1820180Y1094751D01*
X1825433D01*
G01X1791383Y1088058D02*
X1795733D01*
G01D02*
X1802419D01*
X1804120Y1089759D01*
X1805269D01*
G01X1813269Y1089779D02*
X1815951D01*
X1816754Y1088976D01*
Y1087988D01*
X1817676Y1087066D01*
X1819188D01*
X1820180Y1088058D01*
X1825433D01*
G01X1791383Y1081365D02*
X1795733D01*
G01X1791383Y1108136D02*
X1791384Y1108137D01*
X1795733D01*
G01D02*
X1802419D01*
X1804120Y1109838D01*
X1805269D01*
G01X1813269Y1109858D02*
X1815951D01*
X1816754Y1109055D01*
Y1108067D01*
X1817676Y1107145D01*
X1819188D01*
X1820180Y1108137D01*
X1825433D01*
G01X1791383Y1101444D02*
X1795733D01*
G01D02*
X1802419D01*
X1804120Y1103145D01*
X1805269D01*
G01X1813269Y1103165D02*
X1815951D01*
X1816754Y1102362D01*
Y1101374D01*
X1817676Y1100452D01*
X1819188D01*
X1820180Y1101444D01*
X1825433D01*
G01X1791383Y1124869D02*
X1795733D01*
G01D02*
X1802419D01*
X1804120Y1126570D01*
X1805269D01*
G01X1813269Y1126590D02*
X1815951D01*
X1816754Y1125787D01*
Y1124799D01*
X1817676Y1123877D01*
X1819188D01*
X1820180Y1124869D01*
X1825433D01*
G01X1791383Y1118176D02*
X1795733D01*
G01X1825433D02*
X1823450D01*
X1822449Y1117175D01*
X1819332D01*
X1817578Y1115421D01*
X1815649D01*
X1814524Y1116546D01*
X1813269D01*
G01X1805269Y1116527D02*
X1804040D01*
X1802948Y1115435D01*
X1802466D01*
X1800793Y1117108D01*
X1798890D01*
X1797822Y1118176D01*
X1795733D01*
G01X1791383Y1114829D02*
X1795733D01*
G01X1825433D02*
X1823197D01*
X1822141Y1115885D01*
X1819867D01*
X1818113Y1114131D01*
X1815540D01*
X1814536Y1113127D01*
X1813269D01*
G01X1805269Y1113128D02*
X1804044D01*
X1803027Y1114145D01*
X1801931D01*
X1800258Y1115818D01*
X1799058D01*
X1798069Y1114829D01*
X1795733D01*
G01X1791383Y1144947D02*
X1791384Y1144948D01*
X1795733D01*
G01X1791383Y1138255D02*
X1795733D01*
G01D02*
X1802419D01*
X1804120Y1139956D01*
X1805269D01*
G01X1813269Y1139976D02*
X1815951D01*
X1816754Y1139173D01*
Y1138185D01*
X1817676Y1137263D01*
X1819188D01*
X1820180Y1138255D01*
X1825433D01*
G01X1791383Y1131562D02*
X1795733D01*
G01D02*
X1802419D01*
X1804120Y1133263D01*
X1805269D01*
G01X1813269Y1133283D02*
X1815951D01*
X1816754Y1132480D01*
Y1131492D01*
X1817676Y1130570D01*
X1819188D01*
X1820180Y1131562D01*
X1825433D01*
G01X1795733Y1144948D02*
X1802419D01*
X1804120Y1146649D01*
X1805269D01*
G01X1813269Y1146669D02*
X1815951D01*
X1816754Y1145866D01*
Y1144878D01*
X1817676Y1143956D01*
X1819188D01*
X1820180Y1144948D01*
X1825433D01*
G01X1791383Y1154987D02*
X1795733D01*
G01X1825433D02*
X1823450D01*
X1822449Y1153986D01*
X1819332D01*
X1817578Y1152232D01*
X1815649D01*
X1814524Y1153357D01*
X1813269D01*
G01X1805269Y1153338D02*
X1804040D01*
X1802948Y1152246D01*
X1802466D01*
X1800793Y1153919D01*
X1798890D01*
X1797822Y1154987D01*
X1795733D01*
G01Y1151641D02*
X1798070D01*
X1799058Y1152629D01*
X1800258D01*
X1801931Y1150956D01*
X1803027D01*
X1804043Y1149940D01*
X1805269D01*
G01X1813269Y1149939D02*
X1814537D01*
X1815540Y1150942D01*
X1818113D01*
X1819867Y1152696D01*
X1822141D01*
X1823196Y1151641D01*
X1825433D01*
G01X1791383Y1151640D02*
X1791384Y1151641D01*
X1795733D01*
G01X1791383Y1175066D02*
X1795733D01*
G01D02*
X1802419D01*
X1804120Y1176767D01*
X1805269D01*
G01X1813269Y1176787D02*
X1815951D01*
X1816754Y1175984D01*
Y1174996D01*
X1817676Y1174074D01*
X1819188D01*
X1820180Y1175066D01*
X1825433D01*
G01X1791383Y1168373D02*
X1795733D01*
G01D02*
X1802419D01*
X1804120Y1170074D01*
X1805269D01*
G01X1813269Y1170094D02*
X1815951D01*
X1816754Y1169291D01*
Y1168303D01*
X1817676Y1167381D01*
X1819188D01*
X1820180Y1168373D01*
X1825433D01*
G01X1791383Y1161680D02*
X1795733D01*
G01D02*
X1802419D01*
X1804120Y1163381D01*
X1805269D01*
G01X1813269Y1163401D02*
X1815951D01*
X1816754Y1162598D01*
Y1161610D01*
X1817676Y1160688D01*
X1819188D01*
X1820180Y1161680D01*
X1825433D01*
G01X1791383Y1181758D02*
X1795732D01*
X1795733Y1181759D01*
G01D02*
X1802419D01*
X1804120Y1183460D01*
X1805269D01*
G01X1813269Y1183480D02*
X1815951D01*
X1816754Y1182677D01*
Y1181689D01*
X1817676Y1180767D01*
X1819188D01*
X1820180Y1181759D01*
X1825433D01*
G01X1791383Y1191798D02*
X1795733D01*
G01X1825433D02*
X1823450D01*
X1822449Y1190797D01*
X1819332D01*
X1817578Y1189043D01*
X1815649D01*
X1814524Y1190168D01*
X1813269D01*
G01X1805269Y1190149D02*
X1804040D01*
X1802948Y1189057D01*
X1802466D01*
X1800793Y1190730D01*
X1798890D01*
X1797822Y1191798D01*
X1795733D01*
G01Y1188452D02*
X1798070D01*
X1799058Y1189440D01*
X1800258D01*
X1801931Y1187767D01*
X1803027D01*
X1804043Y1186751D01*
X1805269D01*
G01X1813269Y1186750D02*
X1814537D01*
X1815540Y1187753D01*
X1818113D01*
X1819867Y1189507D01*
X1822141D01*
X1823196Y1188452D01*
X1825433D01*
G01X1791383Y1188451D02*
X1791384Y1188452D01*
X1795733D01*
G01X1791383Y1205184D02*
X1795733D01*
G01D02*
X1802419D01*
X1804120Y1206885D01*
X1805269D01*
G01X1813269Y1206905D02*
X1815951D01*
X1816754Y1206102D01*
Y1205114D01*
X1817676Y1204192D01*
X1819188D01*
X1820180Y1205184D01*
X1825433D01*
G01X1791383Y1198491D02*
X1795733D01*
G01D02*
X1802419D01*
X1804120Y1200192D01*
X1805269D01*
G01X1813269Y1200212D02*
X1815951D01*
X1816754Y1199409D01*
Y1198421D01*
X1817676Y1197499D01*
X1819188D01*
X1820180Y1198491D01*
X1825433D01*
G01X1791383Y1218570D02*
X1795733D01*
G01D02*
X1802419D01*
X1804120Y1220271D01*
X1805269D01*
G01X1813269Y1220291D02*
X1815951D01*
X1816754Y1219488D01*
Y1218500D01*
X1817676Y1217578D01*
X1819188D01*
X1820180Y1218570D01*
X1825433D01*
G01X1791383Y1211877D02*
X1795733D01*
G01D02*
X1802419D01*
X1804120Y1213578D01*
X1805269D01*
G01X1813269Y1213598D02*
X1815951D01*
X1816754Y1212795D01*
Y1211807D01*
X1817676Y1210885D01*
X1819188D01*
X1820180Y1211877D01*
X1825433D01*
G01X1795733Y1228609D02*
X1797822D01*
X1798890Y1227541D01*
X1800793D01*
X1802466Y1225868D01*
X1802948D01*
X1804040Y1226960D01*
X1805269D01*
G01X1813269Y1226979D02*
X1814524D01*
X1815649Y1225854D01*
X1817578D01*
X1819332Y1227608D01*
X1822449D01*
X1823450Y1228609D01*
X1825433D01*
G01X1791383Y1225263D02*
X1795733D01*
G01D02*
X1798070D01*
X1799058Y1226251D01*
X1800258D01*
X1801931Y1224578D01*
X1803027D01*
X1804043Y1223562D01*
X1805269D01*
G01X1813269Y1223561D02*
X1814537D01*
X1815540Y1224564D01*
X1818113D01*
X1819867Y1226318D01*
X1822141D01*
X1823196Y1225263D01*
X1825433D01*
G01X1791383Y1241995D02*
X1795733D01*
G01D02*
X1802419D01*
X1804120Y1243696D01*
X1805269D01*
G01X1813269Y1243716D02*
X1815951D01*
X1816754Y1242913D01*
Y1241925D01*
X1817676Y1241003D01*
X1819188D01*
X1820180Y1241995D01*
X1825433D01*
G01X1791383Y1235302D02*
X1795733D01*
G01D02*
X1802419D01*
X1804120Y1237003D01*
X1805269D01*
G01X1813269Y1237023D02*
X1815951D01*
X1816754Y1236220D01*
Y1235232D01*
X1817676Y1234310D01*
X1819188D01*
X1820180Y1235302D01*
X1825433D01*
G01X1791383Y1228609D02*
X1795733D01*
G01X1809291Y960892D02*
X1804941D01*
G01Y957546D02*
X1809291D01*
G01X1804941Y967585D02*
X1809291D01*
G01X1804941Y1054593D02*
X1809291D01*
G01X1821083Y964239D02*
X1825433D01*
G01Y1021129D02*
X1821083D01*
G01Y1024475D02*
X1825433D01*
G01X1821083Y1051247D02*
X1825433D01*
G01X1946178Y1362781D02*
Y1657359D01*
X1947182Y1658363D01*
X1955234D01*
X1956178Y1657419D01*
Y1362781D01*
G54D339*
G01X2047419Y583162D02*
X2051284D01*
X2051724Y582722D01*
Y-8598D01*
X2051284Y-9038D01*
X2047419D01*
G01X2057419Y583162D02*
X2053554D01*
X2053114Y582722D01*
Y-8598D01*
X2053554Y-9038D01*
X2057419D01*
G54D285*
X1283688Y129742D03*
G54D177*
X441990Y1627592D03*
G54D66*
X91786Y1533173D03*
X90211D03*
X88636D03*
X87061D03*
X85487D03*
X83912D03*
X82337D03*
X80762D03*
G54D39*
X61771Y1631013D03*
X59212D03*
X56653D03*
Y1654045D03*
X59212D03*
X61771D03*
X77126Y1631013D03*
X74567D03*
X72008D03*
X69449D03*
X66889D03*
X64330D03*
Y1654045D03*
X66889D03*
X69449D03*
X72008D03*
X74567D03*
X77126D03*
X79685Y1631013D03*
Y1654045D03*
G54D195*
X599552Y288661D03*
Y291220D03*
Y293779D03*
Y296338D03*
Y298897D03*
Y301457D03*
Y304016D03*
Y306575D03*
Y309134D03*
Y311693D03*
X621992Y298897D03*
Y296338D03*
Y293779D03*
Y291220D03*
Y288661D03*
Y311693D03*
Y309134D03*
Y306575D03*
Y304016D03*
Y301457D03*
G54D267*
X1100097Y1650635D03*
X1096357D03*
X1092617D03*
Y1661265D03*
X1096357D03*
X1100097D03*
G54D294*
X1511063Y299780D03*
X1515393Y297812D03*
Y301748D03*
G54D48*
X93400Y280203D03*
Y282762D03*
Y285321D03*
Y297703D03*
Y300262D03*
Y302821D03*
X100880Y282762D03*
Y280203D03*
Y285321D03*
Y297703D03*
Y302821D03*
Y300262D03*
X412386Y1547487D03*
Y1550046D03*
X419866D03*
Y1547487D03*
X412386Y1552605D03*
X419866D03*
X575124Y257291D03*
Y252173D03*
X567644D03*
Y254732D03*
Y257291D03*
X591355Y164717D03*
X583875D03*
Y167276D03*
X591355Y169835D03*
X583875D03*
X609419Y252407D03*
Y254966D03*
Y257525D03*
X616899D03*
Y254966D03*
Y252407D03*
X832084Y471682D03*
Y474241D03*
Y476800D03*
X839564D03*
Y474241D03*
Y471682D03*
X838530Y500523D03*
Y505641D03*
X846010D03*
Y503082D03*
Y500523D03*
X1092381Y73343D03*
Y78461D03*
X1099861D03*
Y75902D03*
Y73343D03*
X1298814Y52503D03*
Y55062D03*
Y57621D03*
X1306294Y52503D03*
Y57621D03*
X1427940Y1585323D03*
Y1587882D03*
Y1590441D03*
X1435420D03*
Y1585323D03*
X1798179Y405497D03*
Y408056D03*
Y410615D03*
X1798168Y418775D03*
Y421334D03*
Y423893D03*
X1812549Y371171D03*
Y366053D03*
X1805069D03*
Y368612D03*
Y371171D03*
X1813109Y390411D03*
Y385293D03*
X1805629D03*
Y387852D03*
Y390411D03*
X1805659Y410615D03*
Y408056D03*
Y405497D03*
X1805648Y423893D03*
Y421334D03*
Y418775D03*
X1830565Y182361D03*
Y177243D03*
X1823085D03*
Y179802D03*
Y182361D03*
G54D276*
X1247638Y269488D03*
X1405118Y112008D03*
X1766929Y1714960D03*
G54D168*
X417052Y234167D03*
X409178D03*
X417052Y239285D03*
Y236726D03*
X409178D03*
Y239285D03*
X531523Y129243D03*
Y131802D03*
Y134361D03*
Y147243D03*
Y149802D03*
Y152361D03*
X530978Y162167D03*
Y164726D03*
Y167285D03*
X539397Y134361D03*
Y131802D03*
Y129243D03*
Y152361D03*
Y149802D03*
Y147243D03*
X538852Y167285D03*
Y164726D03*
Y162167D03*
X579247Y133101D03*
Y130542D03*
Y127983D03*
X571373D03*
Y130542D03*
Y133101D03*
X577147Y147291D03*
Y144732D03*
Y142173D03*
X569273D03*
Y144732D03*
Y147291D03*
G54D258*
X994322Y382138D03*
Y384107D03*
Y386075D03*
Y388044D03*
Y390013D03*
Y391981D03*
Y393949D03*
Y395918D03*
Y397887D03*
Y399855D03*
Y401824D03*
X1018928Y395918D03*
Y393949D03*
Y391981D03*
Y390013D03*
Y388044D03*
Y386075D03*
Y384107D03*
Y382138D03*
Y401824D03*
Y399855D03*
Y397887D03*
G54D57*
X94311Y710347D03*
Y706411D03*
Y708379D03*
X87619Y706411D03*
Y710347D03*
X1701051Y710537D03*
Y714473D03*
X1707743D03*
Y710537D03*
Y712505D03*
G54D75*
X102982Y405071D03*
X109982D03*
X141545Y694807D03*
X141339Y702835D03*
X141363Y710840D03*
X141387Y717660D03*
X148545Y694807D03*
X148339Y702835D03*
X155187Y717660D03*
X155163Y710840D03*
X148363D03*
X148387Y717660D03*
X162187D03*
X162163Y710840D03*
X177043Y1409915D03*
X187866Y410549D03*
X180866D03*
X184043Y1409915D03*
X225347Y1420975D03*
X218347D03*
X225086Y1409915D03*
X218086D03*
X225347Y1427783D03*
X218347D03*
X255965Y70636D03*
X255669Y78930D03*
X244518Y667750D03*
X251518D03*
X262965Y70636D03*
X262669Y78930D03*
X286300Y210812D03*
X293300D03*
X411430Y1157520D03*
X418430D03*
X411430Y1165570D03*
X418430D03*
X430930Y1157520D03*
X423930D03*
X436430D03*
Y1165570D03*
X430930D03*
X423930D03*
X443430Y1157520D03*
X448930D03*
X443430Y1165570D03*
X448930D03*
X455930Y1157520D03*
X461430D03*
X468430D03*
X455930Y1165570D03*
X461430D03*
X468430D03*
X501082Y1381027D03*
X494082D03*
X501123Y1389027D03*
X494123D03*
X501123Y1397027D03*
X494123D03*
X507350Y97542D03*
X514350D03*
X685720Y83362D03*
X692720D03*
X697662Y1409940D03*
X690662D03*
X740860Y1401205D03*
X733860D03*
X739210Y1418365D03*
X732210D03*
X739200Y1410025D03*
X732200D03*
X855576Y234068D03*
X862576D03*
X1119440Y1566630D03*
X1111440D03*
X1115440Y1575430D03*
X1150354Y1446244D03*
X1157354D03*
X1195500Y182362D03*
X1188500D03*
X1195000Y198362D03*
X1188000D03*
X1200582Y1436732D03*
X1193582D03*
X1198552Y1453022D03*
X1191552D03*
X1198592Y1446212D03*
X1191592D03*
X1292008Y54121D03*
X1285008D03*
X1292008Y62321D03*
X1285008D03*
X1387720Y1157520D03*
X1394720D03*
X1387720Y1165570D03*
X1394720D03*
X1407220Y1157520D03*
X1400220D03*
X1412720D03*
X1407220Y1165570D03*
X1400220D03*
X1412720D03*
X1425220Y1157520D03*
X1419720D03*
Y1165570D03*
X1425220D03*
X1432220Y1157520D03*
X1437720D03*
X1444720D03*
X1437720Y1165570D03*
X1444720D03*
X1432220D03*
X1478658Y316356D03*
X1477223Y1381027D03*
X1470223D03*
X1477264Y1389027D03*
X1470264D03*
X1477264Y1397027D03*
X1470264D03*
X1485658Y316356D03*
X1602455Y620832D03*
X1609455D03*
X1651828Y1443536D03*
X1658828D03*
X1702057Y1435332D03*
X1695057D03*
X1700597Y1451935D03*
X1693597D03*
X1700317Y1443505D03*
X1693317D03*
X1718649Y1501870D03*
Y1509920D03*
X1729326Y71930D03*
X1736326D03*
X1729100Y80474D03*
X1736100D03*
X1725649Y1501870D03*
Y1509920D03*
X1755295Y716472D03*
X1755271Y708121D03*
X1755319Y724523D03*
X1747245Y1457671D03*
X1740245D03*
X1753145Y1482171D03*
Y1489371D03*
X1762477Y699940D03*
X1755477D03*
X1762295Y716472D03*
X1762271Y708121D03*
X1762319Y724523D03*
X1760145Y1482171D03*
Y1489371D03*
G54D84*
X109960Y1687921D03*
Y1685362D03*
Y1682803D03*
X102480D03*
Y1685362D03*
Y1687921D03*
X109960Y1696362D03*
Y1693803D03*
X102480D03*
Y1696362D03*
X109960Y1698921D03*
X102480D03*
X462060Y1645841D03*
Y1643282D03*
Y1640723D03*
X454580D03*
Y1643282D03*
Y1645841D03*
X558240Y311616D03*
Y309057D03*
Y306498D03*
X550760D03*
Y309057D03*
Y311616D03*
X658960Y1722921D03*
Y1720362D03*
Y1717803D03*
X651480D03*
Y1720362D03*
Y1722921D03*
X674880Y1668303D03*
Y1670862D03*
Y1673421D03*
X682360D03*
Y1670862D03*
Y1668303D03*
X1408250Y1600723D03*
Y1603282D03*
Y1605841D03*
X1415730Y1600723D03*
Y1605841D03*
Y1603282D03*
G54D186*
X489429Y1404569D03*
X500453Y1417955D03*
X1465570Y1404569D03*
X1476594Y1417955D03*
G54D249*
X963586Y1600926D03*
Y1607042D03*
X995198Y1600942D03*
Y1607058D03*
X1026798Y1600942D03*
Y1607058D03*
X1058398Y1600942D03*
Y1607058D03*
G54D93*
X163642Y1387393D03*
X201785D03*
X317625Y1345539D03*
X349753Y1322741D03*
X381881Y1309315D03*
X414009D03*
X446137D03*
X478265D03*
X510393Y1322741D03*
X542521Y1345539D03*
X677261Y1387418D03*
X715404D03*
X1136953Y1423722D03*
X1175096D03*
X1293886Y1345775D03*
X1325894Y1322741D03*
X1358022Y1309315D03*
X1390150D03*
X1422278D03*
X1454406D03*
X1486534Y1322741D03*
X1518662Y1345539D03*
X1638427Y1421014D03*
X1676570D03*
G54D159*
X366075Y1378501D03*
Y1411375D03*
X1338716Y1378571D03*
Y1411445D03*
G54D58*
X94705Y712316D03*
X1708137Y716442D03*
G54D295*
X1526675Y136146D03*
X1534155D03*
X1530415Y145202D03*
G54D277*
X1265107Y54022D03*
Y62422D03*
X1272587Y54022D03*
Y62422D03*
G54D178*
X467150Y1422842D03*
X463410Y1431504D03*
X470890D03*
X854820Y430793D03*
X858560Y422131D03*
X851080D03*
X1067070Y365631D03*
X1059590D03*
X1063330Y374293D03*
X1443482Y1423962D03*
X1439742Y1432624D03*
X1447222D03*
G54D85*
X145624Y386885D03*
Y389385D03*
Y391885D03*
Y394385D03*
Y396885D03*
Y399385D03*
Y401885D03*
Y404385D03*
X166530Y396885D03*
Y394385D03*
Y391885D03*
Y389385D03*
Y386885D03*
Y404385D03*
Y401885D03*
Y399385D03*
G54D76*
X105967Y421490D03*
Y424049D03*
Y426608D03*
Y429167D03*
Y431727D03*
Y434286D03*
Y436845D03*
Y439404D03*
X128015Y429167D03*
Y426608D03*
Y424049D03*
Y421490D03*
Y439404D03*
Y436845D03*
Y434286D03*
Y431727D03*
G54D196*
X611000Y491201D03*
Y503799D03*
X627000Y491201D03*
X619000D03*
X627000Y503799D03*
X619000D03*
X635000Y491201D03*
Y503799D03*
G54D268*
X1109429Y364235D03*
Y369235D03*
Y374235D03*
Y379235D03*
X1129901Y364235D03*
Y379235D03*
Y374235D03*
Y369235D03*
G54D67*
X79187Y1533173D03*
G54D286*
X1289620Y135702D03*
G54D94*
X158318Y1384286D03*
X155718D03*
X158318Y1387393D03*
X155718D03*
X160201Y1399732D03*
X157731D03*
Y1394132D03*
X160201D03*
X160918Y1384286D03*
X163518D03*
Y1387393D03*
X160918D03*
X169318Y1384286D03*
X166118D03*
X172262Y1384302D03*
Y1387409D03*
X163718Y1390500D03*
X161118D03*
X162631Y1399732D03*
Y1394132D03*
X172231Y1390532D03*
X170922Y1399255D03*
X166262D03*
X173252Y1400005D03*
X168592D03*
X208312Y576125D03*
Y581085D03*
Y578605D03*
X208056Y591665D03*
X208806Y589335D03*
X208056Y587005D03*
X208806Y584675D03*
X208312Y615085D03*
Y610125D03*
Y612605D03*
X208806Y618675D03*
X208056Y621005D03*
X208806Y623335D03*
X208056Y625665D03*
X208312Y649085D03*
Y644125D03*
Y646605D03*
X208056Y655005D03*
X208806Y657335D03*
Y652675D03*
X208056Y659665D03*
X207856Y686443D03*
X203043Y686483D03*
X207824Y681560D03*
X203044Y684036D03*
X207834Y684006D03*
X203237Y681549D03*
X201661Y1384286D03*
X193861D03*
X196461D03*
X199061D03*
X201661Y1387393D03*
X193861D03*
X196461D03*
X199061D03*
X204261Y1384286D03*
X207461D03*
X201861Y1390500D03*
X199261D03*
X195874Y1399732D03*
X198344D03*
X200774D03*
X195874Y1394132D03*
X198344D03*
X200774D03*
X206735Y1400005D03*
X209065Y1399255D03*
X204405D03*
X213912Y576125D03*
X220668Y574131D03*
X223775D03*
X213912Y578605D03*
Y581085D03*
X217556Y590575D03*
X217561Y582131D03*
Y579531D03*
X223775Y587731D03*
X223759Y590675D03*
X220652D03*
X223775Y584531D03*
X220668Y576731D03*
Y579331D03*
X223775Y581931D03*
Y579331D03*
Y576731D03*
X220668Y581931D03*
Y608131D03*
X223775D03*
X213912Y612605D03*
Y615085D03*
Y610125D03*
X217561Y616131D03*
Y613531D03*
X217556Y624575D03*
X223759Y624675D03*
X220652D03*
X223775Y618531D03*
X220668Y610731D03*
Y613331D03*
X223775Y615931D03*
Y613331D03*
Y610731D03*
X220668Y615931D03*
X223775Y621731D03*
X213912Y646605D03*
Y649085D03*
Y644125D03*
X217561Y650131D03*
Y647531D03*
X223775Y655731D03*
Y652531D03*
X220668Y644731D03*
Y647331D03*
Y642131D03*
X223775Y649931D03*
Y647331D03*
Y644731D03*
Y642131D03*
X220668Y649931D03*
X217556Y658575D03*
X223759Y658675D03*
X220652D03*
X210405Y1384302D03*
Y1387409D03*
X210374Y1390532D03*
X211395Y1400005D03*
X312301Y1345539D03*
Y1342432D03*
X309701Y1345539D03*
Y1342432D03*
X316655Y1352295D03*
X314175D03*
X311695D03*
X320101Y1342432D03*
X317701Y1348646D03*
X315101D03*
X314901Y1345539D03*
X317501D03*
X314901Y1342432D03*
X317501D03*
X320245Y1357401D03*
X316655Y1357895D03*
X311695D03*
X314175D03*
X322575Y1358151D03*
X326145Y1348651D03*
X326245Y1345555D03*
Y1342448D03*
X323301Y1342432D03*
X324905Y1357401D03*
X327235Y1358151D03*
X344429Y1322741D03*
X347029D03*
X341829D03*
X347029Y1319634D03*
X344429D03*
X341829D03*
X349629Y1322741D03*
Y1319634D03*
X352229D03*
X355429D03*
X346303Y1335097D03*
X343823D03*
Y1329497D03*
X346303D03*
X347229Y1325848D03*
X348783Y1329497D03*
X349829Y1325848D03*
X348783Y1335097D03*
X352373Y1334603D03*
X354703Y1335353D03*
X358373Y1322757D03*
Y1319650D03*
X358273Y1325853D03*
X357033Y1334603D03*
X359363Y1335353D03*
X373957Y1306208D03*
X381757D03*
X379157D03*
X376557D03*
X384357D03*
X387557D03*
X375951Y1321671D03*
X380911Y1316071D03*
X378431D03*
Y1321671D03*
X380911D03*
X373957Y1309315D03*
X381957Y1312422D03*
X381757Y1309315D03*
X379357Y1312422D03*
X379157Y1309315D03*
X376557D03*
X375951Y1316071D03*
X384501Y1321177D03*
X386831Y1321927D03*
X390501Y1306224D03*
X390401Y1312427D03*
X390501Y1309331D03*
X389161Y1321177D03*
X391491Y1321927D03*
X416485Y1306208D03*
X419685D03*
X413885D03*
X406085D03*
X411285D03*
X408685D03*
X414085Y1312422D03*
X413885Y1309315D03*
X411485Y1312422D03*
X408685Y1309315D03*
X406085D03*
X411285D03*
X413039Y1316071D03*
X408079D03*
X410559D03*
X413039Y1321671D03*
X408079D03*
X410559D03*
X416629Y1321177D03*
X418959Y1321927D03*
X422629Y1306224D03*
X422529Y1312427D03*
X422629Y1309331D03*
X421289Y1321177D03*
X423619Y1321927D03*
X448613Y1306208D03*
X446013D03*
X443413D03*
X440813D03*
X438213D03*
X451813D03*
X443613Y1312422D03*
X443413Y1309315D03*
X440813D03*
X438213D03*
X446213Y1312422D03*
X446013Y1309315D03*
X440207Y1316071D03*
X445167D03*
X442687D03*
X440207Y1321671D03*
X445167D03*
X442687D03*
X448757Y1321177D03*
X451087Y1321927D03*
X454757Y1306224D03*
X454657Y1312427D03*
X454757Y1309331D03*
X453417Y1321177D03*
X455747Y1321927D03*
X480741Y1306208D03*
X478141D03*
X475541D03*
X472941D03*
X470341D03*
X483941D03*
X472941Y1309315D03*
X478141D03*
X470341D03*
X478341Y1312422D03*
X475741D03*
X475541Y1309315D03*
X472335Y1316071D03*
X477295D03*
X474815D03*
X472335Y1321671D03*
X477295D03*
X474815D03*
X480885Y1321177D03*
X485545D03*
X483215Y1321927D03*
X486885Y1306224D03*
X486785Y1312427D03*
X486885Y1309331D03*
X487875Y1321927D03*
X516069Y1319634D03*
X502469D03*
Y1322741D03*
X512869Y1319634D03*
X510269D03*
X507669D03*
X505069D03*
X507669Y1322741D03*
X505069D03*
X510269D03*
X504463Y1329497D03*
Y1335097D03*
X509423Y1329497D03*
X506943D03*
X509423Y1335097D03*
X506943D03*
X510469Y1325848D03*
X507869D03*
X513013Y1334603D03*
X517673D03*
X515343Y1335353D03*
X519013Y1319650D03*
Y1322757D03*
X518913Y1325853D03*
X520003Y1335353D03*
X534597Y1345539D03*
Y1342432D03*
X548197D03*
X539997Y1348646D03*
X542397Y1345539D03*
X542597Y1348646D03*
X537197Y1342432D03*
X539797D03*
X542397D03*
X544997D03*
X537197Y1345539D03*
X539797D03*
X539071Y1352295D03*
X536591D03*
X541551D03*
X545141Y1357401D03*
X549801D03*
X541551Y1357895D03*
X536591D03*
X539071D03*
X547471Y1358151D03*
X551141Y1345555D03*
X551041Y1348651D03*
X551141Y1342448D03*
X552131Y1358151D03*
X677137Y1384311D03*
X674537D03*
X671937D03*
X669337D03*
X677137Y1387418D03*
X674537D03*
X671937D03*
X669337D03*
X679737Y1384311D03*
X677337Y1390525D03*
X674737D03*
X676250Y1399757D03*
X673820D03*
X671350D03*
X676250Y1394157D03*
X673820D03*
X671350D03*
X679881Y1399280D03*
X682937Y1384311D03*
X685881Y1384327D03*
Y1387434D03*
X685850Y1390557D03*
X684541Y1399280D03*
X682211Y1400030D03*
X686871D03*
X707480Y1384311D03*
X710080D03*
X707480Y1387418D03*
X710080D03*
X712680Y1384311D03*
Y1387418D03*
X709493Y1399757D03*
Y1394157D03*
X712880Y1390525D03*
X711963Y1399757D03*
Y1394157D03*
X715280Y1384311D03*
X717880D03*
X715280Y1387418D03*
X721080Y1384311D03*
X724024Y1384327D03*
Y1387434D03*
X715480Y1390525D03*
X723993Y1390557D03*
X714393Y1399757D03*
Y1394157D03*
X718024Y1399280D03*
X722684D03*
X720354Y1400030D03*
X725014D03*
X918532Y492445D03*
X927154Y492103D03*
X924623Y492097D03*
X918078Y495177D03*
X921189Y492086D03*
X918212Y497677D03*
X918131Y503330D03*
X921060Y506086D03*
X923783Y506076D03*
X918212Y500777D03*
X909984Y496330D03*
X926173Y512391D03*
X932373Y495175D03*
X932089Y492691D03*
X929654Y492103D03*
X932218Y499314D03*
X932089Y505986D03*
X932289Y502986D03*
X926637Y506069D03*
X929281Y506086D03*
X1131629Y1420615D03*
X1129029D03*
X1134229D03*
X1131629Y1423722D03*
X1129029D03*
X1134229D03*
X1131042Y1436061D03*
X1135942D03*
X1133512D03*
X1131042Y1430461D03*
X1135942D03*
X1133512D03*
X1134429Y1426829D03*
X1142629Y1420615D03*
X1145573Y1420631D03*
X1139429Y1420615D03*
X1136829D03*
X1145573Y1423738D03*
X1136829Y1423722D03*
X1145542Y1426861D03*
X1137029Y1426829D03*
X1146563Y1436334D03*
X1141903D03*
X1144233Y1435584D03*
X1139573D03*
X1167172Y1420615D03*
Y1423722D03*
X1183716Y1420631D03*
X1180772Y1420615D03*
X1174972D03*
X1177572D03*
X1172372D03*
X1169772D03*
X1183716Y1423738D03*
X1174972Y1423722D03*
X1172372D03*
X1169772D03*
X1174085Y1436061D03*
Y1430461D03*
X1171655Y1436061D03*
X1169185D03*
X1171655Y1430461D03*
X1169185D03*
X1183685Y1426861D03*
X1175172Y1426829D03*
X1172572D03*
X1184706Y1436334D03*
X1180046D03*
X1182376Y1435584D03*
X1177716D03*
X1197700Y1432672D03*
X1198010Y1441902D03*
X1198880Y1457162D03*
X1276745Y125850D03*
X1275807Y132922D03*
X1281600Y137962D03*
X1282568Y212722D03*
X1282654Y226309D03*
X1284930Y124922D03*
X1285793Y141562D03*
X1288258Y145501D03*
X1283781Y149115D03*
X1297605Y145824D03*
X1283781Y155788D03*
X1283397Y202085D03*
X1291205Y1345875D03*
X1286005Y1342768D03*
Y1345875D03*
X1296405Y1342768D03*
X1293805D03*
X1288605D03*
X1291205D03*
X1288605Y1345875D03*
X1293805D03*
X1291405Y1348982D03*
X1294005D03*
X1292916Y1352531D03*
X1290436D03*
X1287956D03*
X1292916Y1358131D03*
X1290436D03*
X1287956D03*
X1298836Y1358387D03*
X1296506Y1357637D03*
X1299605Y1342768D03*
X1302549Y1345891D03*
X1302520Y1348762D03*
X1302549Y1342784D03*
X1303496Y1358387D03*
X1301166Y1357637D03*
X1327920Y84418D03*
X1323958Y146227D03*
X1317970Y1322741D03*
Y1319634D03*
X1325770Y1322741D03*
X1323170D03*
X1331570Y1319634D03*
X1323170D03*
X1325770D03*
X1328370D03*
X1320570Y1322741D03*
Y1319634D03*
X1322444Y1329497D03*
X1324924D03*
X1319964D03*
X1322444Y1335097D03*
X1324924D03*
X1319964D03*
X1323370Y1325848D03*
X1325970D03*
X1328514Y1334603D03*
X1330844Y1335353D03*
X1333811Y235348D03*
X1334514Y1322757D03*
Y1319650D03*
X1334414Y1325853D03*
X1333174Y1334603D03*
X1335504Y1335353D03*
X1362793Y145262D03*
X1349704Y145385D03*
X1357888Y145893D03*
X1361111Y236448D03*
X1350098Y1306208D03*
X1352698D03*
X1355298D03*
X1360498D03*
X1363698D03*
X1357898D03*
X1352698Y1309315D03*
X1350098D03*
X1355498Y1312422D03*
X1358098D03*
X1355298Y1309315D03*
X1357898D03*
X1352092Y1316071D03*
Y1321671D03*
X1357052Y1316071D03*
X1354572D03*
X1357052Y1321671D03*
X1354572D03*
X1360593Y1321872D03*
X1363098Y1320951D03*
X1366868Y147341D03*
X1369593Y147462D03*
X1369916Y154132D03*
X1379969Y176330D03*
X1370586Y176366D03*
X1370405Y186938D03*
X1377597Y197604D03*
X1369479Y208384D03*
X1370636Y227292D03*
X1369410Y224504D03*
X1366642Y1306224D03*
X1366542Y1312427D03*
X1366642Y1309331D03*
X1365376Y1321938D03*
X1367635Y1320904D03*
X1386780Y197668D03*
X1395321D03*
X1382226Y1306208D03*
X1384826D03*
X1387426D03*
X1390026D03*
X1392626D03*
X1395826D03*
X1386700Y1321671D03*
X1389180D03*
X1382226Y1309315D03*
X1384826D03*
X1390226Y1312422D03*
X1387626D03*
X1390026Y1309315D03*
X1387426D03*
X1384220Y1316071D03*
Y1321671D03*
X1389180Y1316071D03*
X1386700D03*
X1392770Y1321177D03*
X1395100Y1321927D03*
X1404071Y197668D03*
X1412851D03*
X1398770Y1306224D03*
X1398670Y1312427D03*
X1398770Y1309331D03*
X1397430Y1321177D03*
X1399760Y1321927D03*
X1414354Y1306208D03*
X1416954D03*
X1419554D03*
X1422154D03*
X1424754D03*
X1427954D03*
X1418828Y1316071D03*
X1416348D03*
X1418828Y1321671D03*
X1416348D03*
X1421308Y1316071D03*
Y1321671D03*
X1414354Y1309315D03*
X1416954D03*
X1419554D03*
X1422354Y1312422D03*
X1419754D03*
X1422154Y1309315D03*
X1424898Y1321177D03*
X1427228Y1321927D03*
X1430898Y1306224D03*
X1430798Y1312427D03*
X1430898Y1309331D03*
X1429558Y1321177D03*
X1431888Y1321927D03*
X1446482Y1306208D03*
X1449082D03*
X1451682D03*
X1456882D03*
X1460082D03*
X1454282D03*
X1450956Y1321671D03*
X1448476D03*
X1453436Y1316071D03*
Y1321671D03*
X1446482Y1309315D03*
X1451882Y1312422D03*
X1449082Y1309315D03*
X1451682D03*
X1454482Y1312422D03*
X1454282Y1309315D03*
X1450956Y1316071D03*
X1448476D03*
X1457026Y1321177D03*
X1461686D03*
X1459356Y1321927D03*
X1463026Y1306224D03*
X1462926Y1312427D03*
X1463026Y1309331D03*
X1464016Y1321927D03*
X1486410Y1322741D03*
X1483810D03*
X1486410Y1319634D03*
X1483810D03*
X1481210Y1322741D03*
Y1319634D03*
X1492210D03*
X1489010D03*
X1478610Y1322741D03*
Y1319634D03*
X1484010Y1325848D03*
X1486610D03*
X1485564Y1335097D03*
X1483084D03*
X1485564Y1329497D03*
X1483084D03*
X1480604Y1335097D03*
Y1329497D03*
X1489154Y1334603D03*
X1493814D03*
X1491484Y1335353D03*
X1495154Y1322757D03*
Y1319650D03*
X1495054Y1325853D03*
X1496144Y1335353D03*
X1510738Y1345539D03*
Y1342432D03*
X1518538Y1345539D03*
Y1342432D03*
X1515938Y1345539D03*
Y1342432D03*
X1513338Y1345539D03*
Y1342432D03*
X1521138D03*
X1524338D03*
X1518738Y1348646D03*
X1516138D03*
X1515212Y1352295D03*
X1512732D03*
X1517692D03*
X1521282Y1357401D03*
X1525942D03*
X1515212Y1357895D03*
X1512732D03*
X1517692D03*
X1523612Y1358151D03*
X1527282Y1345555D03*
Y1342448D03*
X1527182Y1348651D03*
X1528272Y1358151D03*
X1636412Y638451D03*
X1636417Y630007D03*
X1640061Y639497D03*
X1636412Y641051D03*
X1630198Y638651D03*
Y636051D03*
Y641251D03*
X1633305Y638651D03*
Y641251D03*
X1630198Y632851D03*
X1630214Y629907D03*
X1633321D03*
X1640061Y644457D03*
Y641977D03*
X1630198Y643851D03*
X1633305Y646451D03*
Y643851D03*
X1630198Y646451D03*
X1636412Y672451D03*
X1636417Y664007D03*
X1640061Y673497D03*
X1630198Y672651D03*
Y670051D03*
X1633305Y672651D03*
X1630198Y666851D03*
X1630214Y663907D03*
X1633321D03*
X1640061Y678457D03*
Y675977D03*
X1636412Y675051D03*
X1630198Y677851D03*
Y675251D03*
X1633305Y680451D03*
Y675251D03*
Y677851D03*
X1630198Y680451D03*
X1636417Y698007D03*
X1636412Y706451D03*
X1630214Y697907D03*
X1633321D03*
X1630198Y704051D03*
Y706651D03*
X1633305D03*
X1630198Y700851D03*
X1640061Y707497D03*
Y712457D03*
Y709977D03*
X1636412Y709051D03*
X1633305Y711851D03*
Y709251D03*
X1630198D03*
Y711851D03*
X1633305Y714451D03*
X1630198D03*
X1633103Y1417907D03*
X1630503D03*
X1635703D03*
X1633103Y1421014D03*
X1630503D03*
X1635703D03*
X1638303Y1417907D03*
Y1421014D03*
X1635903Y1424121D03*
X1638503D03*
X1632516Y1427753D03*
Y1433353D03*
X1634986Y1427753D03*
Y1433353D03*
X1637416Y1427753D03*
Y1433353D03*
X1649149Y607022D03*
X1653929Y604546D03*
X1649139Y604576D03*
X1653736Y607033D03*
X1649117Y602139D03*
X1653930Y602099D03*
X1645661Y639497D03*
X1645917Y628917D03*
Y633577D03*
X1645167Y631247D03*
Y635907D03*
X1645661Y644457D03*
Y641977D03*
Y673497D03*
X1645917Y662917D03*
Y667577D03*
X1645167Y665247D03*
Y669907D03*
X1645661Y678457D03*
Y675977D03*
X1645167Y703907D03*
X1645917Y701577D03*
X1645167Y699247D03*
X1645917Y696917D03*
X1645661Y707497D03*
Y709977D03*
Y712457D03*
X1644103Y1417907D03*
X1647047Y1417923D03*
Y1421030D03*
X1640903Y1417907D03*
X1647016Y1424153D03*
X1641047Y1432876D03*
X1645707D03*
X1643377Y1433626D03*
X1648037D03*
X1668646Y1417907D03*
Y1421014D03*
X1671246Y1417907D03*
Y1421014D03*
X1670659Y1427753D03*
X1673129D03*
X1670659Y1433353D03*
X1673129D03*
X1685190Y1417923D03*
X1676446Y1417907D03*
X1679046D03*
X1682246D03*
X1676446Y1421014D03*
X1685190Y1421030D03*
X1673846Y1417907D03*
Y1421014D03*
X1676646Y1424121D03*
X1685159Y1424153D03*
X1675559Y1427753D03*
Y1433353D03*
X1674046Y1424121D03*
X1679190Y1432876D03*
X1683850D03*
X1681520Y1433626D03*
X1686180D03*
X1699457Y1439185D03*
Y1447805D03*
X1746970Y1451872D03*
X1750970Y1459172D03*
Y1456172D03*
X1760160Y1476032D03*
X1763730Y1483712D03*
Y1480712D03*
X1763830Y1490782D03*
Y1487782D03*
G54D49*
X81899Y633260D03*
X455434Y1400669D03*
X1431575D03*
G54D169*
X418813Y1401470D03*
Y1424108D03*
X434561Y1401470D03*
X432986D03*
X431411D03*
X429836D03*
X428261D03*
X426687D03*
X425112D03*
X423537D03*
X421962D03*
X420387D03*
Y1424108D03*
X421962D03*
X423537D03*
X425112D03*
X426687D03*
X428261D03*
X429836D03*
X431411D03*
X432986D03*
X434561D03*
X436135Y1401470D03*
Y1424108D03*
X1394954Y1401470D03*
Y1424108D03*
X1410702Y1401470D03*
X1409127D03*
X1407552D03*
X1405977D03*
X1404402D03*
X1402828D03*
X1401253D03*
X1399678D03*
X1398103D03*
X1396528D03*
Y1424108D03*
X1398103D03*
X1399678D03*
X1401253D03*
X1402828D03*
X1404402D03*
X1405977D03*
X1407552D03*
X1409127D03*
X1410702D03*
X1412276Y1401470D03*
Y1424108D03*
G54D187*
X489626Y1417955D03*
X1465767D03*
G54D259*
X1006625Y391981D03*
G54D269*
X1135748Y1528937D03*
X1133780Y1545551D03*
X1139685Y1528937D03*
X1143622D03*
X1147559D03*
X1151497D03*
X1137717Y1545551D03*
X1141654D03*
X1145591D03*
X1149528D03*
X1155433Y1528937D03*
X1159371D03*
X1163308D03*
X1167245D03*
X1153465Y1545551D03*
X1157402D03*
X1161339D03*
X1165276D03*
X1171182Y1528937D03*
X1169213Y1545551D03*
X1173150D03*
G54D197*
X615480Y520299D03*
X629480Y512425D03*
X619220D03*
X622960Y520299D03*
X633220D03*
X636960Y512425D03*
X759289Y143438D03*
X763029Y151312D03*
X766769Y143438D03*
X805480Y425425D03*
X809220Y433299D03*
X812960Y425425D03*
X1194713Y118101D03*
X1198453Y110227D03*
X1190973D03*
X1656896Y187187D03*
X1660636Y179313D03*
X1664376Y187187D03*
G54D77*
X112578Y517044D03*
X115704Y635278D03*
X1662285Y543813D03*
X1702700Y498681D03*
G54D95*
X157638Y1390937D03*
X195781D03*
X311621Y1349083D03*
X343749Y1326285D03*
X375877Y1312859D03*
X408005D03*
X440133D03*
X472261D03*
X504389Y1326285D03*
X536517Y1349083D03*
X671257Y1390962D03*
X709400D03*
X1130949Y1427266D03*
X1169092D03*
X1287882Y1349319D03*
X1319890Y1326285D03*
X1352018Y1312859D03*
X1384146D03*
X1416274D03*
X1448402D03*
X1480530Y1326285D03*
X1512658Y1349083D03*
X1632423Y1424558D03*
X1670566D03*
G54D179*
X478316Y152187D03*
Y147069D03*
X471316D03*
Y149628D03*
Y152187D03*
G54D296*
X1543444Y195866D03*
Y197834D03*
Y199803D03*
Y201771D03*
Y203740D03*
Y205708D03*
Y207677D03*
Y209645D03*
Y211614D03*
Y213582D03*
Y215551D03*
Y217519D03*
Y219488D03*
Y221456D03*
Y223425D03*
Y225393D03*
Y227362D03*
Y229330D03*
Y231299D03*
Y233267D03*
Y235236D03*
Y237204D03*
Y239173D03*
Y241141D03*
Y243110D03*
Y245078D03*
Y247047D03*
Y249015D03*
Y250984D03*
Y252952D03*
X1566004Y195866D03*
Y197834D03*
Y199803D03*
Y201771D03*
Y203740D03*
Y205708D03*
Y207677D03*
Y209645D03*
Y211614D03*
Y213582D03*
Y215551D03*
Y217519D03*
Y219488D03*
Y221456D03*
Y223425D03*
Y225393D03*
Y227362D03*
Y229330D03*
Y231299D03*
Y233267D03*
Y235236D03*
Y237204D03*
Y239173D03*
Y241141D03*
Y243110D03*
Y245078D03*
Y247047D03*
Y249015D03*
Y250984D03*
Y252952D03*
G54D59*
X88406Y708379D03*
X1701838Y712505D03*
G54D287*
X1287521Y133603D03*
G54D68*
X86274Y1538094D03*
G54D86*
X139961Y514305D03*
X484294Y1415339D03*
X1460804Y1415333D03*
X1653854Y644285D03*
X1689755Y541673D03*
G54D188*
X489429Y1406538D03*
Y1408112D03*
Y1409687D03*
Y1411262D03*
Y1412837D03*
Y1414412D03*
Y1415986D03*
X1465570Y1406538D03*
Y1408112D03*
Y1409687D03*
Y1411262D03*
Y1412837D03*
Y1414412D03*
Y1415986D03*
G54D278*
X1276480Y118820D03*
X1269520Y125780D03*
G54D69*
X79187Y1543015D03*
G54D87*
X138469Y537803D03*
X1690028Y564500D03*
G54D279*
X1281262Y125396D03*
X1277160Y129498D03*
G54D189*
X494926Y1432143D03*
Y1455173D03*
X1471404Y1431721D03*
Y1454751D03*
G54D78*
X112413Y531500D03*
X405649Y1385910D03*
X1381790D03*
X1661402Y558097D03*
G54D96*
X155807Y1403338D03*
X157579D03*
X159351D03*
X171752D03*
X169981D03*
X168209D03*
X166437D03*
X164666D03*
X161122D03*
X162894D03*
X207183Y572606D03*
Y606606D03*
Y640606D03*
X208124Y1403338D03*
X206352D03*
X204580D03*
X202809D03*
X193950D03*
X195722D03*
X197494D03*
X199265D03*
X201037D03*
X216042Y572606D03*
X214270D03*
X212498D03*
X210727D03*
X208955D03*
X216042Y606606D03*
X214270D03*
X212498D03*
X210727D03*
X208955D03*
X216042Y640606D03*
X214270D03*
X212498D03*
X210727D03*
X208955D03*
X209895Y1403338D03*
X289206Y149291D03*
X287237D03*
X285269D03*
X283300D03*
Y160315D03*
X285269D03*
X287237D03*
X289206D03*
X322192Y1361484D03*
X320420D03*
X318649D03*
X309790D03*
X311562D03*
X313334D03*
X315105D03*
X316877D03*
X325735D03*
X323964D03*
X354320Y1338686D03*
X352548D03*
X350777D03*
X341918D03*
X343690D03*
X345462D03*
X347233D03*
X349005D03*
X357863D03*
X356092D03*
X386448Y1325260D03*
X384676D03*
X382905D03*
X374046D03*
X375818D03*
X377590D03*
X379361D03*
X381133D03*
X389991D03*
X388220D03*
X418576D03*
X416804D03*
X415033D03*
X406174D03*
X407946D03*
X409718D03*
X411489D03*
X413261D03*
X422119D03*
X420348D03*
X450704D03*
X448932D03*
X447161D03*
X438302D03*
X440074D03*
X441846D03*
X443617D03*
X445389D03*
X454247D03*
X452476D03*
X484604D03*
X482832D03*
X481060D03*
X479289D03*
X470430D03*
X472202D03*
X473974D03*
X475745D03*
X477517D03*
X486375D03*
X516732Y1338686D03*
X514960D03*
X513188D03*
X511417D03*
X502558D03*
X504330D03*
X506102D03*
X507873D03*
X509645D03*
X518503D03*
X548860Y1361484D03*
X547088D03*
X545316D03*
X543545D03*
X534686D03*
X536458D03*
X538230D03*
X540001D03*
X541773D03*
X550631D03*
X598203Y200466D03*
Y211490D03*
X604109Y200466D03*
X602140D03*
X600172D03*
Y211490D03*
X602140D03*
X604109D03*
X680056Y1403363D03*
X678285D03*
X669426D03*
X671198D03*
X672970D03*
X674741D03*
X676513D03*
X685371D03*
X683600D03*
X681828D03*
X707569D03*
X709341D03*
X711113D03*
X723514D03*
X721743D03*
X719971D03*
X718199D03*
X716428D03*
X712884D03*
X714656D03*
X826467Y131386D03*
X824498D03*
X822530D03*
X820561D03*
Y142410D03*
X822530D03*
X824498D03*
X826467D03*
X850432Y208879D03*
X848463D03*
X846495D03*
X844526D03*
Y219903D03*
X846495D03*
X848463D03*
X850432D03*
X1129118Y1439667D03*
X1130890D03*
X1132662D03*
X1134433D03*
X1145063D03*
X1143292D03*
X1141520D03*
X1139748D03*
X1137977D03*
X1136205D03*
X1167261D03*
X1183206D03*
X1181435D03*
X1179663D03*
X1177891D03*
X1176120D03*
X1169033D03*
X1170805D03*
X1172576D03*
X1174348D03*
X1171728Y1630732D03*
X1173697D03*
X1175665D03*
X1177634D03*
Y1619708D03*
X1175665D03*
X1173697D03*
X1171728D03*
X1296681Y1361720D03*
X1294910D03*
X1286051D03*
X1287823D03*
X1289595D03*
X1291366D03*
X1293138D03*
X1301996D03*
X1300225D03*
X1298453D03*
X1330461Y1338686D03*
X1328689D03*
X1326918D03*
X1318059D03*
X1319831D03*
X1321603D03*
X1323374D03*
X1325146D03*
X1334004D03*
X1332233D03*
X1362589Y1325260D03*
X1360817D03*
X1359046D03*
X1350187D03*
X1351959D03*
X1353731D03*
X1355502D03*
X1357274D03*
X1366132D03*
X1364361D03*
X1394717D03*
X1392945D03*
X1391174D03*
X1382315D03*
X1384087D03*
X1385859D03*
X1387630D03*
X1389402D03*
X1398260D03*
X1396489D03*
X1426845D03*
X1425073D03*
X1423302D03*
X1414443D03*
X1416215D03*
X1417987D03*
X1419758D03*
X1421530D03*
X1430388D03*
X1428617D03*
X1460745D03*
X1458973D03*
X1457201D03*
X1455430D03*
X1446571D03*
X1448343D03*
X1450115D03*
X1451886D03*
X1453658D03*
X1462516D03*
X1492873Y1338686D03*
X1491101D03*
X1489329D03*
X1487558D03*
X1478699D03*
X1480471D03*
X1482243D03*
X1484014D03*
X1485786D03*
X1494644D03*
X1525001Y1361484D03*
X1523229D03*
X1521457D03*
X1519686D03*
X1510827D03*
X1512599D03*
X1514371D03*
X1516142D03*
X1517914D03*
X1526772D03*
X1637931Y647976D03*
X1639703D03*
X1637931Y681976D03*
X1639703D03*
X1637931Y715976D03*
X1639703D03*
X1639451Y1436959D03*
X1630592D03*
X1632364D03*
X1634136D03*
X1635907D03*
X1637679D03*
X1641475Y647976D03*
X1643246D03*
X1645018D03*
X1646790D03*
X1641475Y681976D03*
X1643246D03*
X1645018D03*
X1646790D03*
X1641475Y715976D03*
X1643246D03*
X1645018D03*
X1646790D03*
X1646537Y1436959D03*
X1644766D03*
X1642994D03*
X1641222D03*
X1668735D03*
X1670507D03*
X1672279D03*
X1684680D03*
X1682909D03*
X1681137D03*
X1679365D03*
X1677594D03*
X1674050D03*
X1675822D03*
X1735976Y364872D03*
X1734008D03*
X1732039D03*
Y375896D03*
X1734008D03*
X1735976D03*
X1737945Y364872D03*
Y375896D03*
G54D288*
G01X94705Y702376D02*
X97295Y699786D01*
G01D02*
X98895Y698186D01*
Y696262D01*
G01X1228518Y134262D02*
X1226093D01*
G01X1245486Y203000D02*
Y202562D01*
X1246486Y201562D01*
X1248018D01*
G01D02*
Y205362D01*
G01X1699110Y727452D02*
X1700010Y726552D01*
X1701885D01*
X1288347Y150750D03*
X1290927Y151438D03*
X1294866D03*
X1292896Y149804D03*
X1296835D03*
X1294866Y148170D03*
X1287401Y167116D03*
X1290669D03*
X1289035Y165146D03*
X1292303D03*
X1287401Y163177D03*
X1290669D03*
X1289035Y161207D03*
X1292303D03*
X1287401Y159238D03*
X1290669D03*
X1285767Y157268D03*
X1289035D03*
X1292303D03*
X1287401Y155299D03*
X1290669D03*
X1294866Y154706D03*
X1289035Y153329D03*
X1292896Y153072D03*
X1296835D03*
X1289035Y184841D03*
X1292303D03*
X1287401Y182871D03*
X1290669D03*
X1289035Y180902D03*
X1292303D03*
X1287401Y178932D03*
X1290669D03*
X1289035Y176963D03*
X1292303D03*
X1287401Y174993D03*
X1290669D03*
X1289035Y173024D03*
X1292303D03*
X1287401Y171055D03*
X1290669D03*
X1289035Y169085D03*
X1292303D03*
X1289035Y196657D03*
X1292303D03*
X1287401Y194688D03*
X1290669D03*
X1289035Y192718D03*
X1292303D03*
X1287401Y190749D03*
X1290669D03*
X1289035Y188780D03*
X1292303D03*
X1287401Y186810D03*
X1290669D03*
X1289035Y200596D03*
X1292303D03*
X1287401Y198627D03*
X1290669D03*
X1289035Y216352D03*
X1292303D03*
X1287401Y214382D03*
X1290669D03*
X1289035Y212413D03*
X1292303D03*
X1287401Y210443D03*
X1290669D03*
X1289035Y208474D03*
X1292303D03*
X1287401Y206505D03*
X1290669D03*
X1289035Y204535D03*
X1292303D03*
X1287401Y202566D03*
X1290669D03*
X1292896Y231694D03*
X1296835D03*
X1290927Y230060D03*
X1294866D03*
X1289035Y228169D03*
X1292896Y228426D03*
X1296835D03*
X1287401Y226199D03*
X1290669D03*
X1294866Y226792D03*
X1289035Y224230D03*
X1292303D03*
X1287401Y222260D03*
X1290669D03*
X1289035Y220291D03*
X1292303D03*
X1287401Y218321D03*
X1290669D03*
X1302744Y151438D03*
X1306683D03*
X1310621D03*
X1314560D03*
X1298805D03*
X1304713Y149804D03*
X1308652D03*
X1312591D03*
X1300774D03*
X1302744Y154706D03*
X1306683D03*
X1310621D03*
X1314560D03*
X1298805D03*
X1304713Y153072D03*
X1308652D03*
X1312591D03*
X1300774D03*
X1304713Y231694D03*
X1308652D03*
X1312591D03*
X1300774D03*
X1302744Y230060D03*
X1306683D03*
X1310621D03*
X1314560D03*
X1298805D03*
X1304713Y228426D03*
X1308652D03*
X1312591D03*
X1300774D03*
X1302744Y226792D03*
X1306683D03*
X1310621D03*
X1314560D03*
X1298805D03*
X1318499Y151438D03*
X1322438D03*
X1326377D03*
X1330316D03*
X1316530Y149804D03*
X1320469D03*
X1324408D03*
X1328346D03*
X1318499Y154706D03*
X1322438D03*
X1326377D03*
X1330316D03*
X1316530Y153072D03*
X1320469D03*
X1324408D03*
X1328346D03*
X1316530Y231694D03*
X1320469D03*
X1324408D03*
X1328346D03*
X1318499Y230060D03*
X1322438D03*
X1326377D03*
X1330316D03*
X1316530Y228426D03*
X1320469D03*
X1324408D03*
X1328346D03*
X1318499Y226792D03*
X1322438D03*
X1326377D03*
X1330316D03*
X1334255Y151438D03*
X1338194D03*
X1342133D03*
X1346071D03*
X1332285Y149804D03*
X1336224D03*
X1340163D03*
X1344102D03*
X1334255Y154706D03*
X1338194D03*
X1342133D03*
X1346071D03*
X1332285Y153072D03*
X1336224D03*
X1340163D03*
X1344102D03*
X1332285Y231694D03*
X1336224D03*
X1340163D03*
X1344102D03*
X1334255Y230060D03*
X1338194D03*
X1342133D03*
X1346071D03*
X1332285Y228426D03*
X1336224D03*
X1340163D03*
X1344102D03*
X1334255Y226792D03*
X1338194D03*
X1342133D03*
X1346071D03*
X1350010Y151438D03*
X1353949D03*
X1357888D03*
X1361827D03*
X1348041Y149804D03*
X1351980D03*
X1355919D03*
X1359858D03*
X1362085Y167116D03*
X1360451Y165146D03*
X1362085Y163177D03*
X1360451Y161207D03*
X1362085Y159238D03*
X1360451Y157268D03*
X1350010Y154706D03*
X1353949D03*
X1357888D03*
X1362085Y155299D03*
X1348041Y153072D03*
X1351980D03*
X1355919D03*
X1359858D03*
X1360451Y184841D03*
X1362085Y182871D03*
X1360451Y180902D03*
X1362085Y178932D03*
X1360451Y176963D03*
X1362085Y174993D03*
X1360451Y173024D03*
X1362085Y171055D03*
X1360451Y169085D03*
Y196657D03*
X1362085Y194688D03*
X1360451Y192718D03*
X1362085Y190749D03*
X1360451Y188780D03*
X1362085Y186810D03*
X1360451Y200596D03*
X1362085Y198627D03*
X1360451Y216352D03*
X1362085Y214382D03*
X1360451Y212413D03*
X1362085Y210443D03*
X1360451Y208474D03*
X1362085Y206505D03*
X1360451Y204535D03*
X1362085Y202566D03*
X1348041Y231694D03*
X1351980D03*
X1355919D03*
X1359858D03*
X1350010Y230060D03*
X1353949D03*
X1357888D03*
X1361827D03*
X1348041Y228426D03*
X1351980D03*
X1355919D03*
X1359858D03*
X1350010Y226792D03*
X1353949D03*
X1357888D03*
X1362085Y226199D03*
X1360451Y224230D03*
X1362085Y222260D03*
X1360451Y220291D03*
X1362085Y218321D03*
X1364407Y150750D03*
X1365353Y167116D03*
X1363719Y165146D03*
X1365353Y163177D03*
X1363719Y161207D03*
X1365353Y159238D03*
X1363719Y157268D03*
X1365353Y155299D03*
X1363719Y153329D03*
Y184841D03*
X1365353Y182871D03*
X1363719Y180902D03*
X1365353Y178932D03*
X1363719Y176963D03*
X1365353Y174993D03*
X1363719Y173024D03*
X1365353Y171055D03*
X1363719Y169085D03*
Y196657D03*
X1365353Y194688D03*
X1363719Y192718D03*
X1365353Y190749D03*
X1363719Y188780D03*
X1365353Y186810D03*
X1363719Y200596D03*
X1365353Y198627D03*
X1363719Y216352D03*
X1365353Y214382D03*
X1363719Y212413D03*
X1365353Y210443D03*
X1363719Y208474D03*
X1365353Y206505D03*
X1363719Y204535D03*
X1365353Y202566D03*
X1364407Y230748D03*
X1363719Y228169D03*
X1365353Y226199D03*
X1363719Y224230D03*
X1365353Y222260D03*
X1363719Y220291D03*
X1365353Y218321D03*
G54D198*
X640246Y197466D03*
Y221966D03*
X791526Y125647D03*
Y150147D03*
X882183Y213783D03*
Y238283D03*
G54D297*
X1554724Y192657D03*
Y256161D03*
G54D97*
X160197Y1396941D03*
X198340D03*
X314180Y1355087D03*
X346308Y1332289D03*
X378436Y1318863D03*
X410564D03*
X442692D03*
X474820D03*
X506948Y1332289D03*
X539076Y1355087D03*
X673816Y1396966D03*
X711959D03*
X1133508Y1433270D03*
X1171651D03*
X1290441Y1355323D03*
X1322449Y1332289D03*
X1354577Y1318863D03*
X1386705D03*
X1418833D03*
X1450961D03*
X1483089Y1332289D03*
X1515217Y1355087D03*
X1634982Y1430562D03*
X1673125D03*
G54D199*
X646505Y1665405D03*
X643945D03*
X641386D03*
Y1682983D03*
X643945D03*
X646505D03*
X649064Y1665405D03*
Y1682983D03*
X711558Y1651562D03*
X708999D03*
X706439D03*
X703880D03*
Y1669140D03*
X706439D03*
X708999D03*
X711558D03*
G54D88*
X144883Y1725289D03*
Y1727848D03*
Y1730408D03*
Y1732967D03*
X170829Y1707678D03*
Y1710237D03*
Y1712797D03*
Y1715356D03*
X162461Y1730408D03*
Y1727848D03*
Y1725289D03*
Y1732967D03*
X188407Y1712797D03*
Y1710237D03*
Y1707678D03*
Y1715356D03*
X1422534Y1562932D03*
Y1565491D03*
Y1568051D03*
Y1570610D03*
X1440112Y1568051D03*
Y1565491D03*
Y1562932D03*
Y1570610D03*
G54D298*
X1554724Y211909D03*
Y236909D03*
G54D289*
G01X33105Y302472D02*
Y300128D01*
X31184Y298207D01*
X28068D01*
G01X27699Y770144D02*
X32049D01*
G01X27699Y783530D02*
X32049D01*
G01X27699Y776837D02*
X32049D01*
G01X27699Y800263D02*
X32049D01*
G01X27699Y793570D02*
X32049D01*
G01X27699Y813648D02*
X32049D01*
G01X27699Y806955D02*
X32049D01*
G01X27699Y830381D02*
X32049D01*
G01X27699Y820341D02*
X32049D01*
G01X27699Y850459D02*
X32049D01*
G01X27699Y843766D02*
X32049D01*
G01X27699Y837074D02*
X32049D01*
G01X27699Y867192D02*
X32049D01*
G01X27699Y857152D02*
X32049D01*
G01X27699Y880577D02*
X32049D01*
G01X27699Y873885D02*
X32049D01*
G01X27699Y893963D02*
X32049D01*
G01X27699Y887270D02*
X32049D01*
G01X27699Y917389D02*
X32049D01*
G01X27699Y910696D02*
X32049D01*
G01X27699Y904003D02*
X32049D01*
G01X27699Y930774D02*
X32049D01*
G01X27699Y924081D02*
X32049D01*
G01X27699Y947507D02*
X32049D01*
G01X27699Y940814D02*
X32049D01*
G01X27699Y964239D02*
X32049D01*
G01X27699Y954200D02*
X32049D01*
G01X27699Y977625D02*
X32049D01*
G01X27699Y970932D02*
X32049D01*
G01Y991011D02*
X27699D01*
G01Y984318D02*
X32049D01*
G01X27699Y1031168D02*
X32049D01*
G01X27699Y1024475D02*
X32049D01*
G01X27699Y1017782D02*
X32049D01*
G01X27699Y1044554D02*
X32049D01*
G01X27699Y1037861D02*
X32049D01*
G01X27699Y1057940D02*
X32049D01*
G01X27699Y1051247D02*
X32049D01*
G01Y1078018D02*
X27699D01*
G01X32049Y1071326D02*
X27699D01*
G01Y1064633D02*
X32049D01*
G01X27699Y1094751D02*
X32049D01*
G01X27699Y1088058D02*
X32049D01*
G01X27699Y1108137D02*
X32049D01*
G01X27699Y1101444D02*
X32049D01*
G01X27699Y1124869D02*
X32049D01*
G01X27699Y1114829D02*
X32049D01*
G01X27699Y1144948D02*
X32049D01*
G01X27699Y1138255D02*
X32049D01*
G01X27699Y1131562D02*
X32049D01*
G01X27699Y1151641D02*
X32049D01*
G01X27699Y1175066D02*
X32049D01*
G01X27699Y1168373D02*
X32049D01*
G01X27699Y1161680D02*
X32049D01*
G01X27699Y1188452D02*
X32049D01*
G01X27699Y1181759D02*
X32049D01*
G01X27699Y1205184D02*
X32049D01*
G01X27699Y1198491D02*
X32049D01*
G01X27699Y1225263D02*
X32049D01*
G01X27699Y1218570D02*
X32049D01*
G01X27699Y1211877D02*
X32049D01*
G01X27699Y1241995D02*
X32049D01*
G01X27699Y1235302D02*
X32049D01*
G01X27699Y1248688D02*
X32049D01*
G01Y1258727D02*
X27699D01*
G01X33105Y304972D02*
Y302472D01*
G01X61611Y735407D02*
X46100Y719896D01*
Y680791D01*
X72110Y654781D01*
X75440Y646739D01*
X77615Y644564D01*
G01X43841Y766798D02*
X48191D01*
G01X32049Y770144D02*
X36399D01*
G01X43841Y780184D02*
X48191D01*
G01X43841Y773491D02*
X48191D01*
G01X32049Y783530D02*
X36399D01*
G01X32049Y776837D02*
X36399D01*
G01X43841Y803609D02*
X48191D01*
G01X43841Y796916D02*
X48191D01*
G01Y790223D02*
X43841D01*
G01X32049Y800263D02*
X36399D01*
G01X32049Y793570D02*
X36399D01*
G01X43841Y816995D02*
X48191D01*
G01X43841Y810302D02*
X48191D01*
G01X32049Y813648D02*
X36399D01*
G01X32049Y806955D02*
X36399D01*
G01X43841Y833727D02*
X48191D01*
G01X43841Y827034D02*
X48191D01*
G01X32049Y830381D02*
X36399D01*
G01X32049Y820341D02*
X36399D01*
G01X43841Y847113D02*
X48191D01*
G01X43841Y840420D02*
X48191D01*
G01X32049Y850459D02*
X36399D01*
G01X32049Y843766D02*
X36399D01*
G01X32049Y837074D02*
X36399D01*
G01X43841Y863845D02*
X48191D01*
G01X43841Y853806D02*
X48191D01*
G01X32049Y867192D02*
X36399D01*
G01X32049Y857152D02*
X36399D01*
G01X43841Y883924D02*
X48191D01*
G01X43841Y877231D02*
X48191D01*
G01X43841Y870538D02*
X48191D01*
G01X32049Y880577D02*
X36399D01*
G01X32049Y873885D02*
X36399D01*
G01X43841Y900656D02*
X48191D01*
G01X43841Y890617D02*
X48191D01*
G01X32049Y893963D02*
X36399D01*
G01X32049Y887270D02*
X36399D01*
G01X43841Y914042D02*
X48191D01*
G01X43841Y907349D02*
X48191D01*
G01X32049Y917389D02*
X36399D01*
G01X32049Y910696D02*
X36399D01*
G01X32049Y904003D02*
X36399D01*
G01X48191Y927428D02*
X43841D01*
G01Y920735D02*
X48191D01*
G01X32049Y930774D02*
X36399D01*
G01X32049Y924081D02*
X36399D01*
G01X43841Y944160D02*
X48191D01*
G01X43841Y937467D02*
X48191D01*
G01X32049Y947507D02*
X36399D01*
G01X32049Y940814D02*
X36399D01*
G01X43841Y960892D02*
X48191D01*
G01X43841Y950853D02*
X48191D01*
G01X32049Y964239D02*
X36399D01*
G01X32049Y954200D02*
X36399D01*
G01X43841Y980971D02*
X48191D01*
G01X43841Y974278D02*
X48191D01*
G01X43841Y967585D02*
X48191D01*
G01X32049Y977625D02*
X36399D01*
G01X32049Y970932D02*
X36399D01*
G01X43841Y987664D02*
X48191D01*
G01X36399Y991011D02*
X32049D01*
G01Y984318D02*
X36399D01*
G01X43841Y1027822D02*
X48191D01*
G01X43841Y1017782D02*
X48191D01*
G01X32049Y1031168D02*
X36399D01*
G01X32049Y1024475D02*
X36399D01*
G01X32049Y1017782D02*
X36399D01*
G01X43841Y1041207D02*
X48191D01*
G01X43841Y1034515D02*
X48191D01*
G01X32049Y1044554D02*
X36399D01*
G01X32049Y1037861D02*
X36399D01*
G01X43841Y1061286D02*
X48191D01*
G01X43841Y1054593D02*
X48191D01*
G01X43841Y1047900D02*
X48191D01*
G01X32049Y1057940D02*
X36399D01*
G01X32049Y1051247D02*
X36399D01*
G01X43841Y1074672D02*
X48191D01*
G01X43841Y1067979D02*
X48191D01*
G01X36399Y1078018D02*
X32049D01*
G01X36399Y1071326D02*
X32049D01*
G01Y1064633D02*
X36399D01*
G01X43841Y1091404D02*
X48191D01*
G01X43841Y1084711D02*
X48191D01*
G01X32049Y1094751D02*
X36399D01*
G01X32049Y1088058D02*
X36399D01*
G01X43841Y1111483D02*
X48191D01*
G01X43841Y1104790D02*
X48191D01*
G01X43841Y1098097D02*
X48191D01*
G01X32049Y1108137D02*
X36399D01*
G01X32049Y1101444D02*
X36399D01*
G01X43841Y1128215D02*
X48191D01*
G01X43841Y1121522D02*
X48191D01*
G01X32049Y1124869D02*
X36399D01*
G01X32049Y1114829D02*
X36399D01*
G01X43841Y1141601D02*
X48191D01*
G01X43841Y1134908D02*
X48191D01*
G01X32049Y1144948D02*
X36399D01*
G01X32049Y1138255D02*
X36399D01*
G01X32049Y1131562D02*
X36399D01*
G01X43841Y1158333D02*
X48191D01*
G01X43841Y1148294D02*
X48191D01*
G01X32049Y1151641D02*
X36399D01*
G01X43841Y1171719D02*
X48191D01*
G01X43841Y1165026D02*
X48191D01*
G01X32049Y1175066D02*
X36399D01*
G01X32049Y1168373D02*
X36399D01*
G01X32049Y1161680D02*
X36399D01*
G01X43841Y1185105D02*
X48191D01*
G01X43841Y1178412D02*
X48191D01*
G01X32049Y1188452D02*
X36399D01*
G01X32049Y1181759D02*
X36399D01*
G01X43841Y1208530D02*
X48191D01*
G01X43841Y1201837D02*
X48191D01*
G01X43841Y1195144D02*
X48191D01*
G01X32049Y1205184D02*
X36399D01*
G01X32049Y1198491D02*
X36399D01*
G01X43841Y1221916D02*
X48191D01*
G01X43841Y1215223D02*
X48191D01*
G01X32049Y1225263D02*
X36399D01*
G01X32049Y1218570D02*
X36399D01*
G01X32049Y1211877D02*
X36399D01*
G01X43841Y1238648D02*
X48191D01*
G01X43841Y1231955D02*
X48191D01*
G01X32049Y1241995D02*
X36399D01*
G01X32049Y1235302D02*
X36399D01*
G01X48191Y1245341D02*
X43841D01*
G01X32049Y1248688D02*
X36399D01*
G01X44833Y1656759D02*
X47333D01*
G01X62731Y302926D02*
Y299754D01*
X61684Y298707D01*
X58668D01*
G01X59322Y363337D02*
Y360702D01*
G01X51114Y363337D02*
Y360862D01*
G01X57399Y770144D02*
X61749D01*
G01D02*
X66099D01*
G01X48191Y766798D02*
X52541D01*
G01X57399Y783530D02*
X61749D01*
G01D02*
X66099D01*
G01X57399Y776837D02*
X61749D01*
G01D02*
X66099D01*
G01X48191Y780184D02*
X52541D01*
G01X48191Y773491D02*
X52541D01*
G01X57399Y800263D02*
X61749D01*
G01D02*
X66099D01*
G01X57399Y793570D02*
X61749D01*
G01D02*
X66099D01*
G01X48191Y803609D02*
X52541D01*
G01X48191Y796916D02*
X52541D01*
G01Y790223D02*
X48191D01*
G01X57399Y813648D02*
X61749D01*
G01D02*
X66099D01*
G01X57399Y806955D02*
X61749D01*
G01D02*
X66099D01*
G01X48191Y816995D02*
X52541D01*
G01X48191Y810302D02*
X52541D01*
G01X57399Y830381D02*
X61749D01*
G01D02*
X66099D01*
G01X57399Y820341D02*
X61749D01*
G01D02*
X66099D01*
G01X48191Y833727D02*
X52541D01*
G01X48191Y827034D02*
X52541D01*
G01X57399Y850459D02*
X61749D01*
G01D02*
X66099D01*
G01X57399Y843766D02*
X61749D01*
G01D02*
X66099D01*
G01X57399Y837074D02*
X61749D01*
G01D02*
X66099D01*
G01X48191Y847113D02*
X52541D01*
G01X48191Y840420D02*
X52541D01*
G01X57399Y867192D02*
X61749D01*
G01D02*
X66099D01*
G01X57399Y857152D02*
X61749D01*
G01D02*
X66099D01*
G01X48191Y863845D02*
X52541D01*
G01X48191Y853806D02*
X52541D01*
G01X57399Y880577D02*
X61749D01*
G01D02*
X66099D01*
G01Y873885D02*
X61749D01*
G01D02*
X57399D01*
G01X48191Y883924D02*
X52541D01*
G01X48191Y877231D02*
X52541D01*
G01X48191Y870538D02*
X52541D01*
G01X57399Y893963D02*
X61749D01*
G01D02*
X66099D01*
G01X57399Y887270D02*
X61749D01*
G01D02*
X66099D01*
G01X48191Y900656D02*
X52541D01*
G01X48191Y890617D02*
X52541D01*
G01X57399Y917389D02*
X61749D01*
G01D02*
X66099D01*
G01X57399Y910696D02*
X61749D01*
G01D02*
X66099D01*
G01X57399Y904003D02*
X61749D01*
G01D02*
X66099D01*
G01X48191Y914042D02*
X52541D01*
G01X48191Y907349D02*
X52541D01*
G01X57399Y930774D02*
X61749D01*
G01D02*
X66099D01*
G01X57399Y924081D02*
X61749D01*
G01D02*
X66099D01*
G01X52541Y927428D02*
X48191D01*
G01Y920735D02*
X52541D01*
G01X57399Y947507D02*
X61749D01*
G01D02*
X66099D01*
G01X57399Y940814D02*
X61749D01*
G01D02*
X66099D01*
G01X48191Y944160D02*
X52541D01*
G01X48191Y937467D02*
X52541D01*
G01X57399Y964239D02*
X61749D01*
G01D02*
X66099D01*
G01X57399Y954200D02*
X61749D01*
G01D02*
X66099D01*
G01X48191Y960892D02*
X52541D01*
G01X48191Y950853D02*
X52541D01*
G01X57399Y977625D02*
X61749D01*
G01D02*
X66099D01*
G01X57399Y970932D02*
X61749D01*
G01D02*
X66099D01*
G01X48191Y980971D02*
X52541D01*
G01X48191Y974278D02*
X52541D01*
G01X48191Y967585D02*
X52541D01*
G01X66099Y991011D02*
X61749D01*
G01D02*
X57399D01*
G01Y984318D02*
X61749D01*
G01D02*
X66099D01*
G01X48191Y987664D02*
X52541D01*
G01X57399Y1031168D02*
X61749D01*
G01D02*
X66099D01*
G01X57399Y1024475D02*
X61749D01*
G01D02*
X66099D01*
G01Y1017782D02*
X61749D01*
G01D02*
X57399D01*
G01X48191Y1027822D02*
X52541D01*
G01X48191Y1017782D02*
X52541D01*
G01X57399Y1044554D02*
X61749D01*
G01D02*
X66099D01*
G01X57399Y1037861D02*
X61749D01*
G01D02*
X66099D01*
G01X48191Y1041207D02*
X52541D01*
G01X48191Y1034515D02*
X52541D01*
G01X57399Y1057940D02*
X61749D01*
G01D02*
X66099D01*
G01X57399Y1051247D02*
X61749D01*
G01D02*
X66099D01*
G01X48191Y1061286D02*
X52541D01*
G01X48191Y1054593D02*
X52541D01*
G01X48191Y1047900D02*
X52541D01*
G01X57399Y1078018D02*
X61749D01*
G01D02*
X66099D01*
G01X57399Y1071326D02*
X61749D01*
G01D02*
X66099D01*
G01X57399Y1064633D02*
X61749D01*
G01D02*
X66099D01*
G01X48191Y1074672D02*
X52541D01*
G01X48191Y1067979D02*
X52541D01*
G01X57399Y1094751D02*
X61749D01*
G01D02*
X66099D01*
G01X57399Y1088058D02*
X61749D01*
G01D02*
X66099D01*
G01X48191Y1091404D02*
X52541D01*
G01X48191Y1084711D02*
X52541D01*
G01X57399Y1108137D02*
X61749D01*
G01D02*
X66099D01*
G01X57399Y1101444D02*
X61749D01*
G01D02*
X66099D01*
G01X48191Y1111483D02*
X52541D01*
G01X48191Y1104790D02*
X52541D01*
G01X48191Y1098097D02*
X52541D01*
G01X57399Y1124869D02*
X61749D01*
G01D02*
X66099D01*
G01X57399Y1114829D02*
X61749D01*
G01D02*
X66099D01*
G01X48191Y1128215D02*
X52541D01*
G01X48191Y1121522D02*
X52541D01*
G01X66099Y1144948D02*
X61749D01*
G01D02*
X57399D01*
G01Y1138255D02*
X61749D01*
G01D02*
X66099D01*
G01X57399Y1131562D02*
X61749D01*
G01D02*
X66099D01*
G01X48191Y1141601D02*
X52541D01*
G01X48191Y1134908D02*
X52541D01*
G01X57399Y1151641D02*
X61749D01*
G01D02*
X66099D01*
G01X48191Y1158333D02*
X52541D01*
G01X48191Y1148294D02*
X52541D01*
G01X57399Y1175066D02*
X61749D01*
G01D02*
X66099D01*
G01X57399Y1168373D02*
X61749D01*
G01D02*
X66099D01*
G01X57399Y1161680D02*
X61749D01*
G01D02*
X66099D01*
G01X48191Y1171719D02*
X52541D01*
G01X48191Y1165026D02*
X52541D01*
G01X57399Y1188452D02*
X61749D01*
G01D02*
X66099D01*
G01X57399Y1181759D02*
X61749D01*
G01D02*
X66099D01*
G01X48191Y1185105D02*
X52541D01*
G01X48191Y1178412D02*
X52541D01*
G01X57399Y1205184D02*
X61749D01*
G01D02*
X66099D01*
G01X57399Y1198491D02*
X61749D01*
G01D02*
X66099D01*
G01X48191Y1208530D02*
X52541D01*
G01X48191Y1201837D02*
X52541D01*
G01X48191Y1195144D02*
X52541D01*
G01X57399Y1225263D02*
X61749D01*
G01D02*
X66099D01*
G01X57399Y1218570D02*
X61749D01*
G01D02*
X66099D01*
G01X57399Y1211877D02*
X61749D01*
G01D02*
X66099D01*
G01X48191Y1221916D02*
X52541D01*
G01X48191Y1215223D02*
X52541D01*
G01X57399Y1241995D02*
X61749D01*
G01D02*
X66099D01*
G01X57399Y1235302D02*
X61749D01*
G01D02*
X66099D01*
G01X48191Y1238648D02*
X52541D01*
G01X48191Y1231955D02*
X52541D01*
G01X57399Y1248688D02*
X61749D01*
G01D02*
X66099D01*
G01X52541Y1245341D02*
X48191D01*
G01X61749Y1258727D02*
X57399D01*
G01X59272Y1322328D02*
X55177D01*
G01X59272Y1326068D02*
X55277D01*
G01X56799Y1520094D02*
X59199D01*
G01X56799Y1536094D02*
X59199D01*
G01X56799Y1540094D02*
X59199D01*
G01X56799Y1560094D02*
X59199D01*
G01X59833Y1606759D02*
Y1604359D01*
G01X54333Y1615759D02*
Y1613359D01*
G01X50333Y1615759D02*
Y1613359D01*
G01X47333Y1656759D02*
X52201D01*
X53701Y1655259D01*
Y1654045D01*
G01X57833Y1669409D02*
Y1671809D01*
G01X79565Y278798D02*
X77165D01*
G01X79565Y295798D02*
X77165D01*
G01X79565Y286262D02*
X77165D01*
G01X62731Y305426D02*
Y302926D01*
G01X79565Y303262D02*
X77165D01*
G01X63429Y363337D02*
Y360702D01*
G01X67681Y363337D02*
Y360702D01*
G01X77615Y644564D02*
Y648574D01*
G01Y652564D02*
X77588Y652591D01*
Y656577D01*
G01X77615Y648574D02*
Y650546D01*
X77680Y650611D01*
Y652499D01*
X77615Y652564D01*
G01X82241Y766798D02*
X77891D01*
G01D02*
X73541D01*
G01X82241Y780184D02*
X77891D01*
G01D02*
X73541D01*
G01X82241Y773491D02*
X77891D01*
G01D02*
X73541D01*
G01X82241Y803609D02*
X77891D01*
G01D02*
X73541D01*
G01X82241Y796916D02*
X77891D01*
G01D02*
X73541D01*
G01X82241Y790223D02*
X77891D01*
G01D02*
X73541D01*
G01X82241Y816995D02*
X77891D01*
G01D02*
X73541D01*
G01X82241Y810302D02*
X77891D01*
G01D02*
X73541D01*
G01X82241Y833727D02*
X77891D01*
G01D02*
X73541D01*
G01X82241Y827034D02*
X77891D01*
G01D02*
X73541D01*
G01X82241Y847113D02*
X77891D01*
G01D02*
X73541D01*
G01X82241Y840420D02*
X77891D01*
G01D02*
X73541D01*
G01X82241Y863845D02*
X77891D01*
G01D02*
X73541D01*
G01X82241Y853806D02*
X77891D01*
G01D02*
X73541D01*
G01X82241Y883924D02*
X77891D01*
G01D02*
X73541D01*
G01X82241Y877231D02*
X77891D01*
G01D02*
X73541D01*
G01X82241Y870538D02*
X77891D01*
G01D02*
X73541D01*
G01Y900656D02*
X77891D01*
G01D02*
X82241D01*
G01X73541Y890617D02*
X77891D01*
G01D02*
X82241D01*
G01X73541Y914042D02*
X77891D01*
G01D02*
X82241D01*
G01X73541Y907349D02*
X77891D01*
G01D02*
X82241D01*
G01X73541Y927428D02*
X77891D01*
G01D02*
X82241D01*
G01X73541Y920735D02*
X77891D01*
G01D02*
X82241D01*
G01X73541Y944160D02*
X77891D01*
G01D02*
X82241D01*
G01X73541Y937467D02*
X77891D01*
G01D02*
X82241D01*
G01Y960892D02*
X77891D01*
G01D02*
X73541D01*
G01Y950853D02*
X77891D01*
G01D02*
X82241D01*
G01X73541Y980971D02*
X77891D01*
G01D02*
X82241D01*
G01X73541Y974278D02*
X77891D01*
G01D02*
X82241D01*
G01X73541Y967585D02*
X77891D01*
G01D02*
X82241D01*
G01X73541Y987664D02*
X77891D01*
G01D02*
X82241D01*
G01X73541Y1027822D02*
X77891D01*
G01D02*
X82241D01*
G01X73541Y1017782D02*
X77891D01*
G01D02*
X82241D01*
G01X73541Y1041207D02*
X77891D01*
G01D02*
X82241D01*
G01X73541Y1034515D02*
X77891D01*
G01D02*
X82241D01*
G01Y1061286D02*
X77891D01*
G01D02*
X73541D01*
G01X82241Y1054593D02*
X77891D01*
G01D02*
X73541D01*
G01Y1047900D02*
X77891D01*
G01D02*
X82241D01*
G01X73541Y1074672D02*
X77891D01*
G01D02*
X82241D01*
G01X73541Y1067979D02*
X77891D01*
G01D02*
X82241D01*
G01X73541Y1091404D02*
X77891D01*
G01D02*
X82241D01*
G01X73541Y1084711D02*
X77891D01*
G01D02*
X82241D01*
G01X73541Y1111483D02*
X77891D01*
G01D02*
X82241D01*
G01X73541Y1104790D02*
X77891D01*
G01D02*
X82241D01*
G01X73541Y1098097D02*
X77891D01*
G01D02*
X82241D01*
G01X73541Y1128215D02*
X77891D01*
G01D02*
X82241D01*
G01X73541Y1121522D02*
X77891D01*
G01D02*
X82241D01*
G01X73541Y1141601D02*
X77891D01*
G01D02*
X82241D01*
G01X73541Y1134908D02*
X77891D01*
G01D02*
X82241D01*
G01X73541Y1158333D02*
X77891D01*
G01D02*
X82241D01*
G01X73541Y1148294D02*
X77891D01*
G01D02*
X82241D01*
G01X73541Y1171719D02*
X77891D01*
G01D02*
X82241D01*
G01X73541Y1165026D02*
X77891D01*
G01D02*
X82241D01*
G01X73541Y1185105D02*
X77891D01*
G01D02*
X82241D01*
G01X73541Y1178412D02*
X77891D01*
G01D02*
X82241D01*
G01X73541Y1208530D02*
X77891D01*
G01D02*
X82241D01*
G01Y1201837D02*
X77891D01*
G01D02*
X73541D01*
G01Y1195144D02*
X77891D01*
G01D02*
X82241D01*
G01X73541Y1221916D02*
X77891D01*
G01D02*
X82241D01*
G01Y1215223D02*
X77891D01*
G01D02*
X73541D01*
G01Y1238648D02*
X77891D01*
G01D02*
X82241D01*
G01X73541Y1231955D02*
X77891D01*
G01D02*
X82241D01*
G01X73541Y1245341D02*
X77891D01*
G01D02*
X82241D01*
G01X75274Y1546519D02*
X72774D01*
G01X84949Y395865D02*
X87520D01*
G01X84949Y391391D02*
X87520D01*
G01X84949Y382219D02*
X87520D01*
G01X94811Y510173D02*
X95939Y511301D01*
Y512870D01*
G01X85565Y660564D02*
Y656564D01*
G01X82961Y657111D02*
X83508Y656564D01*
X85565D01*
G01X87565Y670441D02*
Y667734D01*
G01X82014Y699517D02*
X79451D01*
G01X87099Y770144D02*
X91449D01*
G01D02*
X95799D01*
G01X87099Y783530D02*
X91449D01*
G01X87099Y776837D02*
X91449D01*
G01D02*
X95799D01*
G01X91449Y783530D02*
X95799D01*
G01X87099Y800263D02*
X91449D01*
G01X87099Y793570D02*
X91449D01*
G01D02*
X95799D01*
G01X91449Y800263D02*
X95799D01*
G01X87099Y813648D02*
X91449D01*
G01X87099Y806955D02*
X91449D01*
G01D02*
X95799D01*
G01X91449Y813648D02*
X95799D01*
G01X87099Y830381D02*
X91449D01*
G01X87099Y820341D02*
X91449D01*
G01D02*
X95799D01*
G01X91449Y830381D02*
X95799D01*
G01X87099Y850459D02*
X91449D01*
G01X87099Y843766D02*
X91449D01*
G01X87099Y837074D02*
X91449D01*
G01D02*
X95799D01*
G01X91449Y843766D02*
X95799D01*
G01X91449Y850459D02*
X95799D01*
G01X87099Y867192D02*
X91449D01*
G01X87099Y857152D02*
X91449D01*
G01D02*
X95799D01*
G01X91449Y867192D02*
X95799D01*
G01X87099Y880577D02*
X91449D01*
G01X87099Y873885D02*
X91449D01*
G01D02*
X95799D01*
G01X91449Y880577D02*
X95799D01*
G01Y893963D02*
X91449D01*
G01X87099Y887270D02*
X91449D01*
G01D02*
X95799D01*
G01X91449Y893963D02*
X87099D01*
G01Y917389D02*
X91449D01*
G01X87099Y910696D02*
X91449D01*
G01X87099Y904003D02*
X91449D01*
G01D02*
X95799D01*
G01X91449Y910696D02*
X95799D01*
G01X91449Y917389D02*
X95799D01*
G01X87099Y930774D02*
X91449D01*
G01X87099Y924081D02*
X91449D01*
G01D02*
X95799D01*
G01X91449Y930774D02*
X95799D01*
G01X87099Y947507D02*
X91449D01*
G01X87099Y940814D02*
X91449D01*
G01D02*
X95799D01*
G01X91449Y947507D02*
X95799D01*
G01X87099Y964239D02*
X91449D01*
G01X87099Y954200D02*
X91449D01*
G01D02*
X95799D01*
G01X91449Y964239D02*
X95799D01*
G01X87099Y977625D02*
X91449D01*
G01X87099Y970932D02*
X91449D01*
G01D02*
X95799D01*
G01X91449Y977625D02*
X95799D01*
G01X87099Y991011D02*
X91449D01*
G01X87099Y984318D02*
X91449D01*
G01D02*
X95799D01*
G01X91449Y991011D02*
X95799D01*
G01X87099Y1031168D02*
X91449D01*
G01X87099Y1024475D02*
X91449D01*
G01X87099Y1017782D02*
X91449D01*
G01D02*
X95799D01*
G01X91449Y1024475D02*
X95799D01*
G01X91449Y1031168D02*
X95799D01*
G01X87099Y1044554D02*
X91449D01*
G01X87099Y1037861D02*
X91449D01*
G01D02*
X95799D01*
G01X91449Y1044554D02*
X95799D01*
G01X87099Y1057940D02*
X91449D01*
G01X87099Y1051247D02*
X91449D01*
G01D02*
X95799D01*
G01X91449Y1057940D02*
X95799D01*
G01X87099Y1078018D02*
X91449D01*
G01X87099Y1071326D02*
X91449D01*
G01X87099Y1064633D02*
X91449D01*
G01D02*
X95799D01*
G01X91449Y1071326D02*
X95799D01*
G01X91449Y1078018D02*
X95799D01*
G01X87099Y1094751D02*
X91449D01*
G01X87099Y1088058D02*
X91449D01*
G01D02*
X95799D01*
G01X91449Y1094751D02*
X95799D01*
G01X87099Y1108137D02*
X91449D01*
G01X87099Y1101444D02*
X91449D01*
G01D02*
X95799D01*
G01X91449Y1108137D02*
X95799D01*
G01X87099Y1124869D02*
X91449D01*
G01X87099Y1114829D02*
X91449D01*
G01D02*
X95799D01*
G01X91449Y1124869D02*
X95799D01*
G01X87099Y1144948D02*
X91449D01*
G01X87099Y1138255D02*
X91449D01*
G01X95799Y1131562D02*
X91449D01*
G01D02*
X87099D01*
G01X91449Y1138255D02*
X95799D01*
G01X91449Y1144948D02*
X95799D01*
G01X87099Y1151641D02*
X91449D01*
G01D02*
X95799D01*
G01X87099Y1175066D02*
X91449D01*
G01X87099Y1168373D02*
X91449D01*
G01X87099Y1161680D02*
X91449D01*
G01D02*
X95799D01*
G01X91449Y1168373D02*
X95799D01*
G01X91449Y1175066D02*
X95799D01*
G01X87099Y1188452D02*
X91449D01*
G01X87099Y1181759D02*
X91449D01*
G01D02*
X95799D01*
G01X91449Y1188452D02*
X95799D01*
G01X87099Y1205184D02*
X91449D01*
G01X87099Y1198491D02*
X91449D01*
G01D02*
X95799D01*
G01X91449Y1205184D02*
X95799D01*
G01X87099Y1225263D02*
X91449D01*
G01X87099Y1218570D02*
X91449D01*
G01X87099Y1211877D02*
X91449D01*
G01D02*
X95799D01*
G01X91449Y1218570D02*
X95799D01*
G01X91449Y1225263D02*
X95799D01*
G01X87099Y1241995D02*
X91449D01*
G01X87099Y1235302D02*
X91449D01*
G01D02*
X95799D01*
G01X91449Y1241995D02*
X95799D01*
G01X87099Y1248688D02*
X91449D01*
G01D02*
X95799D01*
G01X91449Y1258727D02*
X87099D01*
G01X87500Y1567069D02*
Y1564669D01*
G01X91500Y1567069D02*
Y1564669D01*
G01X93113Y1581852D02*
X90713D01*
G01X93113Y1597867D02*
X90713D01*
G01X84063Y1589872D02*
X81008D01*
G01X93188Y1611821D02*
X90788D01*
G01X93188Y1605867D02*
X90788D01*
G01X93188Y1615821D02*
X90788D01*
G01X93188Y1601867D02*
X90788D01*
G01X93188Y1623821D02*
X90788D01*
G01X93098Y1630362D02*
X90698D01*
G01X93188Y1619821D02*
X90788D01*
G01X93098Y1642362D02*
X90698D01*
G01X88645Y1694362D02*
X86245D01*
G01X110937Y282995D02*
X110684Y282742D01*
X103350D01*
X103330Y282762D01*
X100880D01*
G01Y300262D02*
X110845D01*
X110937Y300354D01*
G01X104875Y509374D02*
Y513374D01*
G01X102152Y509374D02*
X104875D01*
G01Y505374D02*
Y501374D01*
G01X102334Y500628D02*
X103080Y501374D01*
X104875D01*
G01X102359Y497374D02*
X104875D01*
G01X101983Y518100D02*
X102158Y517925D01*
X104875D01*
G01X103241Y766798D02*
X107591D01*
G01D02*
X111941D01*
G01X103241Y780184D02*
X107591D01*
G01X111941Y773491D02*
X107591D01*
G01D02*
X103241D01*
G01X107591Y780184D02*
X111941D01*
G01X103241Y803609D02*
X107591D01*
G01X103241Y796916D02*
X107591D01*
G01X103241Y790223D02*
X107591D01*
G01D02*
X111941D01*
G01X107591Y796916D02*
X111941D01*
G01X107591Y803609D02*
X111941D01*
G01X103241Y816995D02*
X107591D01*
G01X103241Y810302D02*
X107591D01*
G01D02*
X111941D01*
G01X107591Y816995D02*
X111941D01*
G01X103241Y833727D02*
X107591D01*
G01X103241Y827034D02*
X107591D01*
G01D02*
X111941D01*
G01X107591Y833727D02*
X111941D01*
G01X103241Y847113D02*
X107591D01*
G01X103241Y840420D02*
X107591D01*
G01D02*
X111941D01*
G01X107591Y847113D02*
X111941D01*
G01X103241Y863845D02*
X107591D01*
G01X103241Y853806D02*
X107591D01*
G01D02*
X111941D01*
G01X107591Y863845D02*
X111941D01*
G01X103241Y883924D02*
X107591D01*
G01X103241Y877231D02*
X107591D01*
G01X103241Y870538D02*
X107591D01*
G01D02*
X111941D01*
G01X107591Y877231D02*
X111941D01*
G01X107591Y883924D02*
X111941D01*
G01X103241Y900656D02*
X107591D01*
G01X103241Y890617D02*
X107591D01*
G01D02*
X111941D01*
G01X107591Y900656D02*
X111941D01*
G01X103241Y914042D02*
X107591D01*
G01X103241Y907349D02*
X107591D01*
G01D02*
X111941D01*
G01X107591Y914042D02*
X111941D01*
G01X103241Y927428D02*
X107591D01*
G01X103241Y920735D02*
X107591D01*
G01D02*
X111941D01*
G01X107591Y927428D02*
X111941D01*
G01X103241Y944160D02*
X107591D01*
G01X103241Y937467D02*
X107591D01*
G01D02*
X111941D01*
G01X107591Y944160D02*
X111941D01*
G01X103241Y960892D02*
X107591D01*
G01X103241Y950853D02*
X107591D01*
G01D02*
X111941D01*
G01X107591Y960892D02*
X111941D01*
G01Y980971D02*
X107591D01*
G01X103241Y974278D02*
X107591D01*
G01X103241Y967585D02*
X107591D01*
G01D02*
X111941D01*
G01X107591Y974278D02*
X111941D01*
G01X107591Y980971D02*
X103241D01*
G01Y987664D02*
X107591D01*
G01D02*
X111941D01*
G01X103241Y1027822D02*
X107591D01*
G01X103241Y1017782D02*
X107591D01*
G01D02*
X111941D01*
G01X107591Y1027822D02*
X111941D01*
G01X103241Y1041207D02*
X107591D01*
G01X103241Y1034515D02*
X107591D01*
G01D02*
X111941D01*
G01X107591Y1041207D02*
X111941D01*
G01X103241Y1061286D02*
X107591D01*
G01X103241Y1054593D02*
X107591D01*
G01X103241Y1047900D02*
X107591D01*
G01D02*
X111941D01*
G01X107591Y1054593D02*
X111941D01*
G01X107591Y1061286D02*
X111941D01*
G01X103241Y1074672D02*
X107591D01*
G01X103241Y1067979D02*
X107591D01*
G01D02*
X111941D01*
G01X107591Y1074672D02*
X111941D01*
G01X103241Y1091404D02*
X107591D01*
G01X103241Y1084711D02*
X107591D01*
G01D02*
X111941D01*
G01X107591Y1091404D02*
X111941D01*
G01X103241Y1111483D02*
X107591D01*
G01X103241Y1104790D02*
X107591D01*
G01X103241Y1098097D02*
X107591D01*
G01D02*
X111941D01*
G01X107591Y1104790D02*
X111941D01*
G01X107591Y1111483D02*
X111941D01*
G01X103241Y1128215D02*
X107591D01*
G01X103241Y1121522D02*
X107591D01*
G01D02*
X111941D01*
G01X107591Y1128215D02*
X111941D01*
G01X103241Y1141601D02*
X107591D01*
G01X103241Y1134908D02*
X107591D01*
G01D02*
X111941D01*
G01X107591Y1141601D02*
X111941D01*
G01X103241Y1158333D02*
X107591D01*
G01X103241Y1148294D02*
X107591D01*
G01D02*
X111941D01*
G01X107591Y1158333D02*
X111941D01*
G01X103241Y1171719D02*
X107591D01*
G01X103241Y1165026D02*
X107591D01*
G01D02*
X111941D01*
G01X107591Y1171719D02*
X111941D01*
G01X103241Y1185105D02*
X107591D01*
G01X103241Y1178412D02*
X107591D01*
G01D02*
X111941D01*
G01X107591Y1185105D02*
X111941D01*
G01X103241Y1208530D02*
X107591D01*
G01X103241Y1201837D02*
X107591D01*
G01X103241Y1195144D02*
X107591D01*
G01D02*
X111941D01*
G01X107591Y1201837D02*
X111941D01*
G01X107591Y1208530D02*
X111941D01*
G01X103241Y1221916D02*
X107591D01*
G01X103241Y1215223D02*
X107591D01*
G01D02*
X111941D01*
G01X107591Y1221916D02*
X111941D01*
G01X103241Y1238648D02*
X107591D01*
G01X103241Y1231955D02*
X107591D01*
G01D02*
X111941D01*
G01X107591Y1238648D02*
X111941D01*
G01X103241Y1245341D02*
X107591D01*
G01D02*
X111941D01*
G01X110349Y1532694D02*
X110449Y1532594D01*
X112749D01*
G01X99274Y1529169D02*
X96774D01*
G01X110349Y1528594D02*
X112749D01*
G01Y1552594D02*
X110349D01*
G01X112749Y1556594D02*
X110349D01*
G01X101500Y1604400D02*
X104900Y1607800D01*
Y1608825D01*
G01X114645Y1696362D02*
X109960D01*
G01X114720Y1683437D02*
X114620D01*
X112695Y1685362D01*
X109960D01*
G01X110937Y285495D02*
Y282995D01*
G01X126994Y278875D02*
X129394D01*
G01X126975Y274800D02*
X129375D01*
G01X110937Y300354D02*
Y302854D01*
G01X126994Y306236D02*
X129394D01*
G01X117597Y488434D02*
Y491316D01*
G01X113597Y488434D02*
Y491316D01*
G01X128193Y662015D02*
X127693Y661515D01*
X125749D01*
G01X128275Y665515D02*
X125749D01*
G01X114021Y669409D02*
Y666932D01*
G01X118021Y669409D02*
Y666932D01*
G01X116799Y770144D02*
X121149D01*
G01D02*
X125499D01*
G01X116799Y783530D02*
X121149D01*
G01D02*
X125499D01*
G01X116799Y776837D02*
X121149D01*
G01D02*
X125499D01*
G01X116799Y800263D02*
X121149D01*
G01D02*
X125499D01*
G01X116799Y793570D02*
X121149D01*
G01D02*
X125499D01*
G01X116799Y813648D02*
X121149D01*
G01D02*
X125499D01*
G01X116799Y806955D02*
X121149D01*
G01D02*
X125499D01*
G01X116799Y830381D02*
X121149D01*
G01D02*
X125499D01*
G01X116799Y820341D02*
X121149D01*
G01D02*
X125499D01*
G01X116799Y850459D02*
X121149D01*
G01D02*
X125499D01*
G01X116799Y843766D02*
X121149D01*
G01D02*
X125499D01*
G01X116799Y837074D02*
X121149D01*
G01D02*
X125499D01*
G01X116799Y867192D02*
X121149D01*
G01D02*
X125499D01*
G01X116799Y857152D02*
X121149D01*
G01D02*
X125499D01*
G01X116799Y880577D02*
X121149D01*
G01D02*
X125499D01*
G01X116799Y873885D02*
X121149D01*
G01D02*
X125499D01*
G01X116799Y893963D02*
X121149D01*
G01D02*
X125499D01*
G01X116799Y887270D02*
X121149D01*
G01D02*
X125499D01*
G01X116799Y917389D02*
X121149D01*
G01D02*
X125499D01*
G01X116799Y910696D02*
X121149D01*
G01D02*
X125499D01*
G01X116799Y904003D02*
X121149D01*
G01D02*
X125499D01*
G01X116799Y930774D02*
X121149D01*
G01D02*
X125499D01*
G01X116799Y924081D02*
X121149D01*
G01D02*
X125499D01*
G01X116799Y947507D02*
X121149D01*
G01D02*
X125499D01*
G01X116799Y940814D02*
X121149D01*
G01D02*
X125499D01*
G01X116799Y964239D02*
X121149D01*
G01D02*
X125499D01*
G01X116799Y954200D02*
X121149D01*
G01D02*
X125499D01*
G01X116799Y977625D02*
X121149D01*
G01D02*
X125499D01*
G01X116799Y970932D02*
X121149D01*
G01D02*
X125499D01*
G01X116799Y991011D02*
X121149D01*
G01D02*
X125499D01*
G01X116799Y984318D02*
X121149D01*
G01D02*
X125499D01*
G01X116799Y1031168D02*
X121149D01*
G01D02*
X125499D01*
G01X116799Y1024475D02*
X121149D01*
G01D02*
X125499D01*
G01X116799Y1017782D02*
X121149D01*
G01D02*
X125499D01*
G01X116799Y1044554D02*
X121149D01*
G01D02*
X125499D01*
G01X116799Y1037861D02*
X121149D01*
G01D02*
X125499D01*
G01X116799Y1057940D02*
X121149D01*
G01D02*
X125499D01*
G01X116799Y1051247D02*
X121149D01*
G01D02*
X125499D01*
G01X116799Y1078018D02*
X121149D01*
G01D02*
X125499D01*
G01X116799Y1071326D02*
X121149D01*
G01D02*
X125499D01*
G01X116799Y1064633D02*
X121149D01*
G01D02*
X125499D01*
G01X116799Y1094751D02*
X121149D01*
G01D02*
X125499D01*
G01X116799Y1088058D02*
X121149D01*
G01D02*
X125499D01*
G01X116799Y1108137D02*
X121149D01*
G01D02*
X125499D01*
G01X116799Y1101444D02*
X121149D01*
G01D02*
X125499D01*
G01X116799Y1124869D02*
X121149D01*
G01D02*
X125499D01*
G01X116799Y1114829D02*
X121149D01*
G01D02*
X125499D01*
G01X116799Y1144948D02*
X121149D01*
G01D02*
X125499D01*
G01X116799Y1138255D02*
X121149D01*
G01D02*
X125499D01*
G01X116799Y1131562D02*
X121149D01*
G01D02*
X125499D01*
G01X116799Y1151641D02*
X121149D01*
G01D02*
X125499D01*
G01X116799Y1175066D02*
X121149D01*
G01D02*
X125499D01*
G01X116799Y1168373D02*
X121149D01*
G01D02*
X125499D01*
G01X116799Y1161680D02*
X121149D01*
G01D02*
X125499D01*
G01X116799Y1188452D02*
X121149D01*
G01D02*
X125499D01*
G01X116799Y1181759D02*
X121149D01*
G01D02*
X125499D01*
G01X116799Y1205184D02*
X121149D01*
G01D02*
X125499D01*
G01X116799Y1198491D02*
X121149D01*
G01D02*
X125499D01*
G01X116799Y1225263D02*
X121149D01*
G01D02*
X125499D01*
G01X116799Y1218570D02*
X121149D01*
G01D02*
X125499D01*
G01X116799Y1211877D02*
X121149D01*
G01D02*
X125499D01*
G01X116799Y1241995D02*
X121149D01*
G01D02*
X125499D01*
G01X116799Y1235302D02*
X121149D01*
G01D02*
X125499D01*
G01X116799Y1248688D02*
X121149D01*
G01D02*
X125499D01*
G01X121149Y1258727D02*
X116799D01*
G01X122633Y1589352D02*
X125033D01*
G01X127133Y1637862D02*
X129533D01*
G01X114645Y1698862D02*
Y1696362D01*
G01X117220Y1683437D02*
X114720D01*
G01X124795Y1696362D02*
X127195D01*
G01X125082Y1727092D02*
X127392D01*
X127482Y1727182D01*
G01X120910Y1723472D02*
X123394D01*
G01X127738Y659226D02*
X128313Y658651D01*
Y656603D01*
G01X130067Y650213D02*
X128313Y651967D01*
Y652603D01*
G01X127313Y647103D02*
Y649765D01*
G01X131756Y643603D02*
X134205D01*
G01X137291Y766798D02*
X141641D01*
G01X132941D02*
X137291D01*
G01Y773491D02*
X141641D01*
G01X132941D02*
X137291D01*
G01Y780184D02*
X141641D01*
G01X132941D02*
X137291D01*
G01Y803609D02*
X141641D01*
G01X132941D02*
X137291D01*
G01Y790223D02*
X141641D01*
G01X132941D02*
X137291D01*
G01Y796916D02*
X141641D01*
G01X132941D02*
X137291D01*
G01Y816995D02*
X141641D01*
G01X132941D02*
X137291D01*
G01Y810302D02*
X141641D01*
G01X132941D02*
X137291D01*
G01Y833727D02*
X141641D01*
G01X132941D02*
X137291D01*
G01Y827034D02*
X141641D01*
G01X132941D02*
X137291D01*
G01Y840420D02*
X141641D01*
G01X132941D02*
X137291D01*
G01Y847113D02*
X141641D01*
G01X132941D02*
X137291D01*
G01X132941Y863845D02*
X137291D01*
G01D02*
X141641D01*
G01X137291Y853806D02*
X141641D01*
G01X132941D02*
X137291D01*
G01X132941Y883924D02*
X137291D01*
G01D02*
X141641D01*
G01X132941Y870538D02*
X137291D01*
G01D02*
X141641D01*
G01X132941Y877231D02*
X137291D01*
G01D02*
X141641D01*
G01X132941Y900656D02*
X137291D01*
G01D02*
X141641D01*
G01X132941Y890617D02*
X137291D01*
G01D02*
X141641D01*
G01X132941Y907349D02*
X137291D01*
G01D02*
X141641D01*
G01X132941Y914042D02*
X137291D01*
G01D02*
X141641D01*
G01X132941Y920735D02*
X137291D01*
G01D02*
X141641D01*
G01X132941Y927428D02*
X137291D01*
G01D02*
X141641D01*
G01X132941Y937467D02*
X137291D01*
G01D02*
X141641D01*
G01X132941Y944160D02*
X137291D01*
G01D02*
X141641D01*
G01X132941Y960892D02*
X137291D01*
G01D02*
X141641D01*
G01X132941Y950853D02*
X137291D01*
G01D02*
X141641D01*
G01X132941Y980971D02*
X137291D01*
G01D02*
X141641D01*
G01X132941Y974278D02*
X137291D01*
G01D02*
X141641D01*
G01X132941Y967585D02*
X137291D01*
G01D02*
X141641D01*
G01X132941Y987664D02*
X137291D01*
G01D02*
X141641D01*
G01X132941Y1027822D02*
X137291D01*
G01D02*
X141641D01*
G01X132941Y1017782D02*
X137291D01*
G01D02*
X141641D01*
G01X132941Y1041207D02*
X137291D01*
G01D02*
X141641D01*
G01X132941Y1034515D02*
X137291D01*
G01D02*
X141641D01*
G01Y1061286D02*
X137291D01*
G01D02*
X132941D01*
G01X141641Y1054593D02*
X137291D01*
G01D02*
X132941D01*
G01Y1047900D02*
X137291D01*
G01D02*
X141641D01*
G01Y1074672D02*
X137291D01*
G01D02*
X132941D01*
G01X141641Y1067979D02*
X137291D01*
G01D02*
X132941D01*
G01X141641Y1091404D02*
X137291D01*
G01D02*
X132941D01*
G01X141641Y1084711D02*
X137291D01*
G01D02*
X132941D01*
G01X141641Y1111483D02*
X137291D01*
G01D02*
X132941D01*
G01X141641Y1104790D02*
X137291D01*
G01D02*
X132941D01*
G01X141641Y1098097D02*
X137291D01*
G01D02*
X132941D01*
G01X141641Y1128215D02*
X137291D01*
G01D02*
X132941D01*
G01X141641Y1121522D02*
X137291D01*
G01D02*
X132941D01*
G01X141641Y1141601D02*
X137291D01*
G01D02*
X132941D01*
G01X141641Y1134908D02*
X137291D01*
G01D02*
X132941D01*
G01X141641Y1158333D02*
X137291D01*
G01D02*
X132941D01*
G01X141641Y1148294D02*
X137291D01*
G01D02*
X132941D01*
G01X141641Y1171719D02*
X137291D01*
G01D02*
X132941D01*
G01X141641Y1165026D02*
X137291D01*
G01D02*
X132941D01*
G01X141641Y1185105D02*
X137291D01*
G01D02*
X132941D01*
G01X141641Y1178412D02*
X137291D01*
G01D02*
X132941D01*
G01X141641Y1208530D02*
X137291D01*
G01D02*
X132941D01*
G01X141641Y1201837D02*
X137291D01*
G01D02*
X132941D01*
G01X141641Y1195144D02*
X137291D01*
G01D02*
X132941D01*
G01Y1221916D02*
X137291D01*
G01D02*
X141641D01*
G01X132941Y1215223D02*
X137291D01*
G01D02*
X141641D01*
G01X132941Y1238648D02*
X137291D01*
G01D02*
X141641D01*
G01X132941Y1231955D02*
X137291D01*
G01D02*
X141641D01*
G01X132941Y1245341D02*
X137291D01*
G01D02*
X141641D01*
G01X140142Y1392545D02*
X142342D01*
X142542Y1392745D01*
G01Y1396275D02*
X140142D01*
G01X127413Y1604367D02*
X129813D01*
G01X128133Y1622321D02*
X130533D01*
G01X140745Y1708362D02*
X137420D01*
G01X141642Y1717592D02*
Y1720092D01*
G01D02*
Y1723789D01*
X143142Y1725289D01*
X144883D01*
G01X158376Y425383D02*
Y426625D01*
X159484Y427733D01*
X166690D01*
G01X149472Y502810D02*
X147072D01*
G01X149486Y498810D02*
X147072D01*
G01X149472Y506810D02*
X151598D01*
X152470Y505938D01*
G01X149518Y522810D02*
X147072D01*
G01X150800Y512021D02*
X158298D01*
X159798Y513521D01*
Y517781D01*
X158298Y519281D01*
X155883D01*
G01X150849Y770144D02*
X146499D01*
G01X155199D02*
X150849D01*
G01Y783530D02*
X146499D01*
G01X155199D02*
X150849D01*
G01Y776837D02*
X146499D01*
G01X155199D02*
X150849D01*
G01Y800263D02*
X146499D01*
G01X155199D02*
X150849D01*
G01Y793570D02*
X146499D01*
G01X155199D02*
X150849D01*
G01Y813648D02*
X146499D01*
G01X155199D02*
X150849D01*
G01Y806955D02*
X146499D01*
G01X155199D02*
X150849D01*
G01Y830381D02*
X146499D01*
G01X155199D02*
X150849D01*
G01Y820341D02*
X146499D01*
G01X155199D02*
X150849D01*
G01Y850459D02*
X146499D01*
G01X155199D02*
X150849D01*
G01Y843766D02*
X146499D01*
G01X155199D02*
X150849D01*
G01Y837074D02*
X146499D01*
G01X155199D02*
X150849D01*
G01X155199Y867192D02*
X150849D01*
G01D02*
X146499D01*
G01X150849Y857152D02*
X146499D01*
G01X155199D02*
X150849D01*
G01X155199Y880577D02*
X150849D01*
G01D02*
X146499D01*
G01X155199Y873885D02*
X150849D01*
G01D02*
X146499D01*
G01X155199Y893963D02*
X150849D01*
G01D02*
X146499D01*
G01X155199Y887270D02*
X150849D01*
G01D02*
X146499D01*
G01X155199Y917389D02*
X150849D01*
G01D02*
X146499D01*
G01X155199Y910696D02*
X150849D01*
G01D02*
X146499D01*
G01X155199Y904003D02*
X150849D01*
G01D02*
X146499D01*
G01X155199Y930774D02*
X150849D01*
G01D02*
X146499D01*
G01X155199Y924081D02*
X150849D01*
G01D02*
X146499D01*
G01X155199Y947507D02*
X150849D01*
G01D02*
X146499D01*
G01X155199Y940814D02*
X150849D01*
G01D02*
X146499D01*
G01X155199Y964239D02*
X150849D01*
G01D02*
X146499D01*
G01X155199Y954200D02*
X150849D01*
G01D02*
X146499D01*
G01X155199Y977625D02*
X150849D01*
G01D02*
X146499D01*
G01X155199Y970932D02*
X150849D01*
G01D02*
X146499D01*
G01X155199Y991011D02*
X150849D01*
G01D02*
X146499D01*
G01X155199Y984318D02*
X150849D01*
G01D02*
X146499D01*
G01X155199Y1031168D02*
X150849D01*
G01D02*
X146499D01*
G01X155199Y1024475D02*
X150849D01*
G01D02*
X146499D01*
G01X155199Y1017782D02*
X150849D01*
G01D02*
X146499D01*
G01X155199Y1044554D02*
X150849D01*
G01D02*
X146499D01*
G01X155199Y1037861D02*
X150849D01*
G01D02*
X146499D01*
G01X155199Y1057940D02*
X150849D01*
G01D02*
X146499D01*
G01X155199Y1051247D02*
X150849D01*
G01D02*
X146499D01*
G01X155199Y1078018D02*
X150849D01*
G01D02*
X146499D01*
G01X155199Y1071326D02*
X150849D01*
G01D02*
X146499D01*
G01X155199Y1064633D02*
X150849D01*
G01D02*
X146499D01*
G01X155199Y1094751D02*
X150849D01*
G01D02*
X146499D01*
G01X155199Y1088058D02*
X150849D01*
G01D02*
X146499D01*
G01X155199Y1108137D02*
X150849D01*
G01D02*
X146499D01*
G01X155199Y1101444D02*
X150849D01*
G01D02*
X146499D01*
G01X155199Y1124869D02*
X150849D01*
G01D02*
X146499D01*
G01X155199Y1114829D02*
X150849D01*
G01D02*
X146499D01*
G01X155199Y1144948D02*
X150849D01*
G01D02*
X146499D01*
G01X155199Y1138255D02*
X150849D01*
G01D02*
X146499D01*
G01X155199Y1131562D02*
X150849D01*
G01D02*
X146499D01*
G01X155199Y1151641D02*
X150849D01*
G01D02*
X146499D01*
G01X155199Y1175066D02*
X150849D01*
G01D02*
X146499D01*
G01X155199Y1168373D02*
X150849D01*
G01D02*
X146499D01*
G01X155199Y1161680D02*
X150849D01*
G01D02*
X146499D01*
G01X155199Y1188452D02*
X150849D01*
G01D02*
X146499D01*
G01X155199Y1181759D02*
X150849D01*
G01D02*
X146499D01*
G01X155199Y1205184D02*
X150849D01*
G01D02*
X146499D01*
G01X155199Y1198491D02*
X150849D01*
G01D02*
X146499D01*
G01X155199Y1225263D02*
X150849D01*
G01D02*
X146499D01*
G01X155199Y1218570D02*
X150849D01*
G01D02*
X146499D01*
G01X155199Y1211877D02*
X150849D01*
G01D02*
X146499D01*
G01X155199Y1241995D02*
X150849D01*
G01D02*
X146499D01*
G01X155199Y1235302D02*
X150849D01*
G01D02*
X146499D01*
G01X155199Y1248688D02*
X150849D01*
G01D02*
X146499D01*
G01X150849Y1258727D02*
X146499D01*
G01X152806Y1411534D02*
Y1414175D01*
G01X148145Y1712362D02*
X145745D01*
G01X181821Y425383D02*
Y426383D01*
X180471Y427733D01*
X173475D01*
X172321Y426579D01*
Y425383D01*
G01D02*
X170429D01*
X168079Y427733D01*
X166690D01*
G01X171341Y766798D02*
X166991D01*
G01D02*
X162641D01*
G01X171341Y780184D02*
X166991D01*
G01D02*
X162641D01*
G01Y773491D02*
X166991D01*
G01D02*
X171341D01*
G01Y803609D02*
X166991D01*
G01D02*
X162641D01*
G01X171341Y796916D02*
X166991D01*
G01D02*
X162641D01*
G01X171341Y790223D02*
X166991D01*
G01D02*
X162641D01*
G01X171341Y816995D02*
X166991D01*
G01D02*
X162641D01*
G01X171341Y810302D02*
X166991D01*
G01D02*
X162641D01*
G01X171341Y833727D02*
X166991D01*
G01D02*
X162641D01*
G01X171341Y827034D02*
X166991D01*
G01D02*
X162641D01*
G01X171341Y847113D02*
X166991D01*
G01D02*
X162641D01*
G01X171341Y840420D02*
X166991D01*
G01D02*
X162641D01*
G01X166991Y863845D02*
X162641D01*
G01X171341D02*
X166991D01*
G01X171341Y853806D02*
X166991D01*
G01D02*
X162641D01*
G01X166991Y883924D02*
X162641D01*
G01X171341D02*
X166991D01*
G01Y877231D02*
X162641D01*
G01X171341D02*
X166991D01*
G01Y870538D02*
X162641D01*
G01X171341D02*
X166991D01*
G01Y900656D02*
X162641D01*
G01X171341D02*
X166991D01*
G01Y890617D02*
X162641D01*
G01X171341D02*
X166991D01*
G01Y914042D02*
X162641D01*
G01X171341D02*
X166991D01*
G01Y907349D02*
X162641D01*
G01X171341D02*
X166991D01*
G01Y927428D02*
X162641D01*
G01X171341D02*
X166991D01*
G01Y920735D02*
X162641D01*
G01X171341D02*
X166991D01*
G01Y944160D02*
X162641D01*
G01X171341D02*
X166991D01*
G01Y937467D02*
X162641D01*
G01X171341D02*
X166991D01*
G01Y960892D02*
X162641D01*
G01X171341D02*
X166991D01*
G01Y950853D02*
X162641D01*
G01X171341D02*
X166991D01*
G01Y980971D02*
X162641D01*
G01X171341D02*
X166991D01*
G01Y974278D02*
X162641D01*
G01X171341D02*
X166991D01*
G01Y967585D02*
X162641D01*
G01X171341D02*
X166991D01*
G01Y987664D02*
X162641D01*
G01X171341D02*
X166991D01*
G01Y1027822D02*
X162641D01*
G01X171341D02*
X166991D01*
G01Y1017782D02*
X162641D01*
G01X171341D02*
X166991D01*
G01Y1041207D02*
X162641D01*
G01X171341D02*
X166991D01*
G01Y1034515D02*
X162641D01*
G01X171341D02*
X166991D01*
G01Y1061286D02*
X162641D01*
G01X171341D02*
X166991D01*
G01Y1054593D02*
X162641D01*
G01X171341D02*
X166991D01*
G01Y1047900D02*
X162641D01*
G01X171341D02*
X166991D01*
G01Y1074672D02*
X162641D01*
G01X171341D02*
X166991D01*
G01Y1067979D02*
X162641D01*
G01X171341D02*
X166991D01*
G01Y1091404D02*
X162641D01*
G01X171341D02*
X166991D01*
G01Y1084711D02*
X162641D01*
G01X171341D02*
X166991D01*
G01Y1111483D02*
X162641D01*
G01X171341D02*
X166991D01*
G01Y1104790D02*
X162641D01*
G01X171341D02*
X166991D01*
G01Y1098097D02*
X162641D01*
G01X171341D02*
X166991D01*
G01Y1128215D02*
X162641D01*
G01X171341D02*
X166991D01*
G01Y1121522D02*
X162641D01*
G01X171341D02*
X166991D01*
G01Y1141601D02*
X162641D01*
G01X171341D02*
X166991D01*
G01Y1134908D02*
X162641D01*
G01X171341D02*
X166991D01*
G01Y1158333D02*
X162641D01*
G01X171341D02*
X166991D01*
G01Y1148294D02*
X162641D01*
G01X171341D02*
X166991D01*
G01Y1171719D02*
X162641D01*
G01X171341D02*
X166991D01*
G01Y1165026D02*
X162641D01*
G01X171341D02*
X166991D01*
G01Y1185105D02*
X162641D01*
G01X171341D02*
X166991D01*
G01Y1178412D02*
X162641D01*
G01X171341D02*
X166991D01*
G01Y1208530D02*
X162641D01*
G01X171341D02*
X166991D01*
G01Y1201837D02*
X162641D01*
G01X171341D02*
X166991D01*
G01Y1195144D02*
X162641D01*
G01X171341D02*
X166991D01*
G01Y1221916D02*
X171341D01*
G01X162641D02*
X166991D01*
G01Y1215223D02*
X162641D01*
G01X171341D02*
X166991D01*
G01Y1238648D02*
X162641D01*
G01X171341D02*
X166991D01*
G01Y1231955D02*
X162641D01*
G01X171341D02*
X166991D01*
G01Y1245341D02*
X162641D01*
G01X171341D02*
X166991D01*
G01X162693Y1411529D02*
Y1411673D01*
X162193Y1412173D01*
X160133D01*
G01X176199Y770144D02*
X180549D01*
G01D02*
X184899D01*
G01X176199Y783530D02*
X180549D01*
G01D02*
X184899D01*
G01X176199Y776837D02*
X180549D01*
G01D02*
X184899D01*
G01X176199Y800263D02*
X180549D01*
G01D02*
X184899D01*
G01X176199Y793570D02*
X180549D01*
G01D02*
X184899D01*
G01X176199Y813648D02*
X180549D01*
G01D02*
X184899D01*
G01X176199Y806955D02*
X180549D01*
G01D02*
X184899D01*
G01X191491Y827034D02*
X196691D01*
G01X176199Y830381D02*
X180549D01*
G01D02*
X184899D01*
G01X176199Y820341D02*
X180549D01*
G01D02*
X184899D01*
G01X176199Y850459D02*
X180549D01*
G01D02*
X184899D01*
G01X176199Y843766D02*
X180549D01*
G01D02*
X184899D01*
G01X176199Y837074D02*
X180549D01*
G01D02*
X184899D01*
G01X191491Y863845D02*
X196691D01*
G01X180549Y867192D02*
X184899D01*
G01X176199D02*
X180549D01*
G01X176199Y857152D02*
X180549D01*
G01D02*
X184899D01*
G01X180549Y880577D02*
X184899D01*
G01X176199D02*
X180549D01*
G01Y873885D02*
X184899D01*
G01X176199D02*
X180549D01*
G01Y893963D02*
X184899D01*
G01X176199D02*
X180549D01*
G01Y887270D02*
X184899D01*
G01X176199D02*
X180549D01*
G01Y917389D02*
X184899D01*
G01X176199D02*
X180549D01*
G01Y910696D02*
X184899D01*
G01X176199D02*
X180549D01*
G01Y904003D02*
X184899D01*
G01X176199D02*
X180549D01*
G01X191491Y927428D02*
X196691D01*
G01X180549Y930774D02*
X184899D01*
G01X176199D02*
X180549D01*
G01Y924081D02*
X184899D01*
G01X176199D02*
X180549D01*
G01Y947507D02*
X184899D01*
G01X176199D02*
X180549D01*
G01Y940814D02*
X184899D01*
G01X176199D02*
X180549D01*
G01Y964239D02*
X184899D01*
G01X176199D02*
X180549D01*
G01Y954200D02*
X184899D01*
G01X176199D02*
X180549D01*
G01Y977625D02*
X184899D01*
G01X176199D02*
X180549D01*
G01Y970932D02*
X184899D01*
G01X176199D02*
X180549D01*
G01Y991011D02*
X184899D01*
G01X176199D02*
X180549D01*
G01Y984318D02*
X184899D01*
G01X176199D02*
X180549D01*
G01Y1031168D02*
X184899D01*
G01X176199D02*
X180549D01*
G01Y1024475D02*
X184899D01*
G01X176199D02*
X180549D01*
G01Y1017782D02*
X184899D01*
G01X176199D02*
X180549D01*
G01Y1044554D02*
X184899D01*
G01X176199D02*
X180549D01*
G01Y1037861D02*
X184899D01*
G01X176199D02*
X180549D01*
G01Y1057940D02*
X184899D01*
G01X176199D02*
X180549D01*
G01Y1051247D02*
X184899D01*
G01X176199D02*
X180549D01*
G01Y1078018D02*
X184899D01*
G01X176199D02*
X180549D01*
G01Y1071326D02*
X184899D01*
G01X176199D02*
X180549D01*
G01Y1064633D02*
X184899D01*
G01X176199D02*
X180549D01*
G01X196691Y1084711D02*
X191491D01*
G01X180549Y1094751D02*
X184899D01*
G01X176199D02*
X180549D01*
G01Y1088058D02*
X184899D01*
G01X176199D02*
X180549D01*
G01Y1108137D02*
X184899D01*
G01X176199D02*
X180549D01*
G01Y1101444D02*
X184899D01*
G01X176199D02*
X180549D01*
G01Y1124869D02*
X184899D01*
G01X176199D02*
X180549D01*
G01Y1114829D02*
X184899D01*
G01X176199D02*
X180549D01*
G01Y1144948D02*
X184899D01*
G01X176199D02*
X180549D01*
G01Y1138255D02*
X184899D01*
G01X176199D02*
X180549D01*
G01Y1131562D02*
X176199D01*
G01X184899D02*
X180549D01*
G01X196691Y1158333D02*
X191491D01*
G01X180549Y1151641D02*
X184899D01*
G01X176199D02*
X180549D01*
G01Y1168373D02*
X184899D01*
G01X176199D02*
X180549D01*
G01Y1161680D02*
X184899D01*
G01X176199D02*
X180549D01*
G01Y1175066D02*
X176199D01*
G01X184899D02*
X180549D01*
G01Y1188452D02*
X184899D01*
G01X176199D02*
X180549D01*
G01Y1181759D02*
X184899D01*
G01X176199D02*
X180549D01*
G01Y1205184D02*
X184899D01*
G01X176199D02*
X180549D01*
G01Y1198491D02*
X184899D01*
G01X176199D02*
X180549D01*
G01Y1225263D02*
X184899D01*
G01X176199D02*
X180549D01*
G01Y1218570D02*
X184899D01*
G01X176199D02*
X180549D01*
G01Y1211877D02*
X184899D01*
G01X176199D02*
X180549D01*
G01X191491Y1231955D02*
X196691D01*
G01X180549Y1235302D02*
X184899D01*
G01X176199D02*
X180549D01*
G01Y1241995D02*
X176199D01*
G01X184899D02*
X180549D01*
G01Y1248688D02*
X176199D01*
G01X184899D02*
X180549D01*
G01Y1258727D02*
X176199D01*
G01X192767Y1413725D02*
Y1413352D01*
X190949Y1411534D01*
G01X185142Y1729092D02*
X187542D01*
G01X193293Y1719697D02*
Y1718132D01*
X190517Y1715356D01*
X188407D01*
G01X201549Y425755D02*
X199149D01*
G01X201549Y420255D02*
X199149D01*
G01X201549Y414755D02*
X199149D01*
G01X201549Y436755D02*
X199149D01*
G01X201549Y442255D02*
X199149D01*
G01X201549Y431255D02*
X199149D01*
G01X201549Y462755D02*
Y458755D01*
G01Y453255D02*
X199149D01*
G01X201549Y447755D02*
X199149D01*
G01X201549Y468255D02*
X199149D01*
G01X201549Y462755D02*
Y468255D01*
G01X196526Y570901D02*
Y567825D01*
G01X195888Y578546D02*
Y581071D01*
G01X197423Y601496D02*
X198271Y600648D01*
X199941D01*
G01X196526Y604901D02*
X194059D01*
G01X195888Y612546D02*
Y615071D01*
G01X196526Y638901D02*
X194059D01*
G01X197423Y635496D02*
X198271Y634648D01*
X199941D01*
G01X195888Y646546D02*
Y649071D01*
G01X205899Y770144D02*
X210249D01*
G01X192341Y766798D02*
X196691D01*
G01D02*
X201041D01*
G01X205899Y783530D02*
X210249D01*
G01X205899Y776837D02*
X210249D01*
G01X192341Y780184D02*
X196691D01*
G01D02*
X201041D01*
G01X192341Y773491D02*
X196691D01*
G01D02*
X201041D01*
G01X210249Y800263D02*
X205899D01*
G01X210249Y793570D02*
X205899D01*
G01X192341Y803609D02*
X196691D01*
G01D02*
X201041D01*
G01X192341Y796916D02*
X196691D01*
G01D02*
X201041D01*
G01Y790223D02*
X196691D01*
G01D02*
X192341D01*
G01X210249Y813648D02*
X205899D01*
G01X210249Y806955D02*
X205899D01*
G01X192341Y816995D02*
X196691D01*
G01D02*
X201041D01*
G01X192341Y810302D02*
X196691D01*
G01D02*
X201041D01*
G01X210249Y830381D02*
X205049D01*
G01X192341Y833727D02*
X196691D01*
G01D02*
X201041D01*
G01X196691Y827034D02*
X201041D01*
G01X210249Y820341D02*
X205049D01*
G01X205899Y850459D02*
X210249D01*
G01Y837074D02*
X205899D01*
G01X210249Y843766D02*
X205899D01*
G01X192341Y840420D02*
X196691D01*
G01D02*
X201041D01*
G01Y847113D02*
X196691D01*
G01D02*
X192341D01*
G01X210249Y867192D02*
X205049D01*
G01Y857152D02*
X210249D01*
G01X196691Y863845D02*
X201041D01*
G01Y853806D02*
X196691D01*
G01D02*
X192341D01*
G01X205899Y873885D02*
X210249D01*
G01X205899Y880577D02*
X210249D01*
G01X196691Y883924D02*
X201041D01*
G01X192341D02*
X196691D01*
G01Y877231D02*
X201041D01*
G01X192341D02*
X196691D01*
G01Y870538D02*
X201041D01*
G01X192341D02*
X196691D01*
G01X205899Y893963D02*
X210249D01*
G01X205899Y887270D02*
X210249D01*
G01X196691Y900656D02*
X201041D01*
G01X192341D02*
X196691D01*
G01Y890617D02*
X201041D01*
G01X192341D02*
X196691D01*
G01X205899Y917389D02*
X210249D01*
G01X205899Y910696D02*
X210249D01*
G01X205899Y904003D02*
X210249D01*
G01X196691Y914042D02*
X201041D01*
G01X192341D02*
X196691D01*
G01Y907349D02*
X201041D01*
G01X192341D02*
X196691D01*
G01X210249Y930774D02*
X205049D01*
G01Y924081D02*
X210249D01*
G01X196691Y927428D02*
X201041D01*
G01X196691Y920735D02*
X201041D01*
G01X192341D02*
X196691D01*
G01X205899Y940814D02*
X210249D01*
G01X205899Y947507D02*
X210249D01*
G01X192341Y937467D02*
X196691D01*
G01D02*
X201041D01*
G01X196691Y944160D02*
X201041D01*
G01X192341D02*
X196691D01*
G01X205899Y964239D02*
X210249D01*
G01X205899Y954200D02*
X210249D01*
G01X196691Y960892D02*
X201041D01*
G01X192341D02*
X196691D01*
G01Y950853D02*
X201041D01*
G01X192341D02*
X196691D01*
G01X205899Y970932D02*
X210249D01*
G01X205899Y977625D02*
X210249D01*
G01X192341Y974278D02*
X196691D01*
G01D02*
X201041D01*
G01X192341Y980971D02*
X196691D01*
G01D02*
X201041D01*
G01X192341Y967585D02*
X196691D01*
G01D02*
X201041D01*
G01X205899Y991011D02*
X210249D01*
G01X205899Y984318D02*
X210249D01*
G01X192341Y987664D02*
X196691D01*
G01D02*
X201041D01*
G01X205899Y1017782D02*
X210249D01*
G01X205899Y1024475D02*
X210249D01*
G01X196691Y1027822D02*
X201041D01*
G01X192341D02*
X196691D01*
G01Y1017782D02*
X201041D01*
G01X192341D02*
X196691D01*
G01X205899Y1044554D02*
X210249D01*
G01X205899Y1037861D02*
X210249D01*
G01X192341Y1041207D02*
X196691D01*
G01D02*
X201041D01*
G01X192341Y1034515D02*
X196691D01*
G01D02*
X201041D01*
G01X205899Y1057940D02*
X210249D01*
G01X192341Y1054593D02*
X196691D01*
G01D02*
X201041D01*
G01X196691Y1061286D02*
X201041D01*
G01X192341D02*
X196691D01*
G01X192341Y1047900D02*
X196691D01*
G01D02*
X201041D01*
G01X205049Y1078018D02*
X210249D01*
G01X205899Y1071326D02*
X210249D01*
G01X205899Y1064633D02*
X210249D01*
G01X196691Y1067979D02*
X201041D01*
G01X192341D02*
X196691D01*
G01Y1074672D02*
X192341D01*
G01X201041D02*
X196691D01*
G01X205899Y1094751D02*
X210249D01*
G01X205049Y1088058D02*
X210249D01*
G01X196691Y1091404D02*
X201041D01*
G01X192341D02*
X196691D01*
G01X201041Y1084711D02*
X196691D01*
G01X205899Y1101444D02*
X210249D01*
G01X205899Y1108137D02*
X210249D01*
G01X196691Y1111483D02*
X201041D01*
G01X192341D02*
X196691D01*
G01Y1104790D02*
X201041D01*
G01X192341D02*
X196691D01*
G01Y1098097D02*
X201041D01*
G01X192341D02*
X196691D01*
G01X205899Y1114829D02*
X210249D01*
G01X205899Y1124869D02*
X210249D01*
G01X196691Y1128215D02*
X201041D01*
G01X192341D02*
X196691D01*
G01Y1121522D02*
X201041D01*
G01X192341D02*
X196691D01*
G01X205899Y1144948D02*
X210249D01*
G01X205899Y1138255D02*
X210249D01*
G01X205899Y1131562D02*
X210249D01*
G01X196691Y1141601D02*
X201041D01*
G01X192341D02*
X196691D01*
G01Y1134908D02*
X201041D01*
G01X192341D02*
X196691D01*
G01X205049Y1151641D02*
X210249D01*
G01X201041Y1158333D02*
X196691D01*
G01Y1148294D02*
X201041D01*
G01X192341D02*
X196691D01*
G01X205899Y1168373D02*
X210249D01*
G01X205899Y1175066D02*
X210249D01*
G01X205049Y1161680D02*
X210249D01*
G01X196691Y1171719D02*
X201041D01*
G01X192341D02*
X196691D01*
G01Y1165026D02*
X201041D01*
G01X192341D02*
X196691D01*
G01X210249Y1188452D02*
X205899D01*
G01Y1181759D02*
X210249D01*
G01X196691Y1185105D02*
X201041D01*
G01X192341D02*
X196691D01*
G01Y1178412D02*
X201041D01*
G01X192341D02*
X196691D01*
G01X205899Y1205184D02*
X210249D01*
G01X205899Y1198491D02*
X210249D01*
G01X196691Y1208530D02*
X201041D01*
G01X192341D02*
X196691D01*
G01Y1201837D02*
X201041D01*
G01X192341D02*
X196691D01*
G01Y1195144D02*
X201041D01*
G01X192341D02*
X196691D01*
G01X205049Y1225263D02*
X210249D01*
G01X205899Y1211877D02*
X210249D01*
G01X205899Y1218570D02*
X210249D01*
G01X196691Y1221916D02*
X201041D01*
G01X192341D02*
X196691D01*
G01Y1215223D02*
X201041D01*
G01X192341D02*
X196691D01*
G01X205899Y1241995D02*
X210249D01*
G01X205049Y1235302D02*
X210249D01*
G01X196691Y1231955D02*
X201041D01*
G01X196691Y1238648D02*
X192341D01*
G01X201041D02*
X196691D01*
G01X205899Y1248688D02*
X210249D01*
G01X196691Y1245341D02*
X201041D01*
G01X192341D02*
X196691D01*
G01X210249Y1258727D02*
X205899D01*
G01X201071Y1412173D02*
X198276D01*
G01X208193Y1714017D02*
X210593D01*
G01X193293Y1722197D02*
Y1719697D01*
G01X202200Y1733022D02*
X204600D01*
G01X222907Y321831D02*
X225407D01*
G01X211979Y462235D02*
X209579D01*
G01X222041Y766798D02*
X226391D01*
G01X210249Y770144D02*
X214599D01*
G01X222041Y780184D02*
X226391D01*
G01X222041Y773491D02*
X226391D01*
G01X210249Y783530D02*
X214599D01*
G01X210249Y776837D02*
X214599D01*
G01X222041Y803609D02*
X226391D01*
G01X222041Y796916D02*
X226391D01*
G01X222041Y790223D02*
X226391D01*
G01X214599Y800263D02*
X210249D01*
G01X214599Y793570D02*
X210249D01*
G01X222041Y810302D02*
X226391D01*
G01X221191Y816995D02*
X226391D01*
G01X214599Y813648D02*
X210249D01*
G01X214599Y806955D02*
X210249D01*
G01X222041Y833727D02*
X226391D01*
G01Y827034D02*
X221191D01*
G01X215449Y830381D02*
X210249D01*
G01X215449Y820341D02*
X210249D01*
G01X222041Y847113D02*
X226391D01*
G01X222041Y840420D02*
X226391D01*
G01X210249Y850459D02*
X214599D01*
G01Y837074D02*
X210249D01*
G01X214599Y843766D02*
X210249D01*
G01X221191Y863845D02*
X226391D01*
G01X222041Y853806D02*
X226391D01*
G01X215449Y867192D02*
X210249D01*
G01Y857152D02*
X215449D01*
G01X226391Y877231D02*
X222041D01*
G01X221191Y870538D02*
X226391D01*
G01Y883924D02*
X222041D01*
G01X210249Y873885D02*
X214599D01*
G01X210249Y880577D02*
X214599D01*
G01X222041Y900656D02*
X226391D01*
G01X222041Y890617D02*
X226391D01*
G01X210249Y893963D02*
X214599D01*
G01X210249Y887270D02*
X214599D01*
G01X222041Y914042D02*
X226391D01*
G01X222041Y907349D02*
X226391D01*
G01X210249Y917389D02*
X214599D01*
G01X210249Y910696D02*
X214599D01*
G01X210249Y904003D02*
X214599D01*
G01X226391Y927428D02*
X221241D01*
G01X226391Y920735D02*
X222041D01*
G01X215449Y930774D02*
X210249D01*
G01Y924081D02*
X215449D01*
G01X222041Y944160D02*
X226391D01*
G01X221191Y937467D02*
X226391D01*
G01X210249Y940814D02*
X214599D01*
G01X210249Y947507D02*
X214599D01*
G01X222041Y960892D02*
X226391D01*
G01X222041Y950853D02*
X226391D01*
G01X210249Y964239D02*
X214599D01*
G01X210249Y954200D02*
X214599D01*
G01X222041Y980971D02*
X226391D01*
G01X222041Y974278D02*
X226391D01*
G01X222041Y967585D02*
X226391D01*
G01X210249Y970932D02*
X214599D01*
G01X210249Y977625D02*
X214599D01*
G01X226391Y987664D02*
X222041D01*
G01X210249Y991011D02*
X214599D01*
G01X210249Y984318D02*
X214599D01*
G01X226391Y1027822D02*
X222041D01*
G01X226391Y1017782D02*
X222041D01*
G01X210249D02*
X214599D01*
G01X210249Y1024475D02*
X214599D01*
G01X222041Y1041207D02*
X226391D01*
G01X222041Y1034515D02*
X226391D01*
G01X210249Y1044554D02*
X214599D01*
G01X210249Y1037861D02*
X214599D01*
G01X226391Y1054593D02*
X222041D01*
G01Y1061286D02*
X226391D01*
G01X222041Y1047900D02*
X226391D01*
G01X210249Y1057940D02*
X214599D01*
G01X222041Y1067979D02*
X226391D01*
G01X221191Y1074672D02*
X226391D01*
G01X210249Y1078018D02*
X215449D01*
G01X210249Y1071326D02*
X214599D01*
G01X210249Y1064633D02*
X214599D01*
G01X222041Y1091404D02*
X226391D01*
G01X221191Y1084711D02*
X226391D01*
G01X210249Y1094751D02*
X214599D01*
G01X210249Y1088058D02*
X215449D01*
G01X222041Y1111483D02*
X226391D01*
G01X222041Y1098097D02*
X226391D01*
G01X222041Y1104790D02*
X226391D01*
G01X210249Y1101444D02*
X214599D01*
G01X210249Y1108137D02*
X214599D01*
G01X222041Y1128215D02*
X226391D01*
G01X222041Y1121522D02*
X226391D01*
G01X210249Y1114829D02*
X214599D01*
G01X210249Y1124869D02*
X214599D01*
G01X222041Y1141601D02*
X226391D01*
G01X221191Y1134908D02*
X226391D01*
G01X210249Y1144948D02*
X214599D01*
G01X210249Y1138255D02*
X214599D01*
G01X210249Y1131562D02*
X214599D01*
G01X222041Y1158333D02*
X226391D01*
G01X221191Y1148294D02*
X226391D01*
G01X210249Y1151641D02*
X215449D01*
G01X222041Y1165026D02*
X226391D01*
G01X222041Y1171719D02*
X226391D01*
G01X210249Y1168373D02*
X214599D01*
G01X210249Y1175066D02*
X214599D01*
G01X210249Y1161680D02*
X215449D01*
G01X222041Y1185105D02*
X226391D01*
G01X222041Y1178412D02*
X226391D01*
G01X214599Y1188452D02*
X210249D01*
G01Y1181759D02*
X214599D01*
G01X222041Y1208530D02*
X226391D01*
G01X222041Y1201837D02*
X226391D01*
G01X222041Y1195144D02*
X226391D01*
G01X210249Y1205184D02*
X214599D01*
G01X210249Y1198491D02*
X214599D01*
G01X222041Y1221916D02*
X226391D01*
G01X222041Y1215223D02*
X226391D01*
G01X210249Y1225263D02*
X215449D01*
G01X210249Y1211877D02*
X214599D01*
G01X210249Y1218570D02*
X214599D01*
G01X221191Y1231955D02*
X226391D01*
G01X221191Y1238648D02*
X226391D01*
G01X210249Y1241995D02*
X214599D01*
G01X210249Y1235302D02*
X215449D01*
G01X222041Y1245341D02*
X226391D01*
G01X210249Y1248688D02*
X214599D01*
G01X212120Y1706687D02*
Y1703062D01*
G01X235697Y44370D02*
X235701Y44366D01*
Y39570D01*
G01X235599Y770144D02*
X239949D01*
G01D02*
X244299D01*
G01X226391Y766798D02*
X230741D01*
G01X235599Y783530D02*
X239949D01*
G01D02*
X244299D01*
G01X235599Y776837D02*
X239949D01*
G01D02*
X244299D01*
G01X226391Y780184D02*
X230741D01*
G01X226391Y773491D02*
X230741D01*
G01X235599Y800263D02*
X239949D01*
G01D02*
X244299D01*
G01X235599Y793570D02*
X239949D01*
G01D02*
X244299D01*
G01X226391Y803609D02*
X230741D01*
G01X226391Y796916D02*
X230741D01*
G01X226391Y790223D02*
X230741D01*
G01X239949Y813648D02*
X245149D01*
G01X234749D02*
X239949D01*
G01Y806955D02*
X244299D01*
G01X235599D02*
X239949D01*
G01X226391Y810302D02*
X230741D01*
G01X231006Y817554D02*
X230447Y816995D01*
X226391D01*
G01X239949Y830381D02*
X244299D01*
G01X235599D02*
X239949D01*
G01Y820341D02*
X245149D01*
G01X234749D02*
X239949D01*
G01X226391Y833727D02*
X230741D01*
G01X231591Y827034D02*
X226391D01*
G01X239949Y850459D02*
X244299D01*
G01X235599D02*
X239949D01*
G01Y837074D02*
X244299D01*
G01X235599D02*
X239949D01*
G01X235599Y843766D02*
X239949D01*
G01D02*
X244299D01*
G01X226391Y847113D02*
X230741D01*
G01X226391Y840420D02*
X230741D01*
G01X234749Y867492D02*
X235049Y867192D01*
X239949D01*
G01D02*
X245149D01*
G01X239949Y857152D02*
X245149D01*
G01X234749D02*
X239949D01*
G01X226391Y863845D02*
X231591D01*
G01X226391Y853806D02*
X230741D01*
G01X235599Y874185D02*
X235899Y873885D01*
X239949D01*
G01D02*
X244299D01*
G01X239949Y880577D02*
X244299D01*
G01X235599D02*
X239949D01*
G01X230741Y877231D02*
X226391D01*
G01X231059Y871084D02*
X230513Y870538D01*
X226391D01*
G01X230741Y883924D02*
X226391D01*
G01X239949Y893963D02*
X244299D01*
G01X235599D02*
X239949D01*
G01Y887270D02*
X244299D01*
G01X235599D02*
X239949D01*
G01X226391Y900656D02*
X230741D01*
G01X226391Y890617D02*
X230741D01*
G01X235599Y917389D02*
X239949D01*
G01D02*
X244299D01*
G01X239949Y910696D02*
X244299D01*
G01X235599D02*
X239949D01*
G01Y904003D02*
X244299D01*
G01X235599D02*
X239949D01*
G01X226391Y914042D02*
X230741D01*
G01X226391Y907349D02*
X230741D01*
G01X235599Y930774D02*
X239949D01*
G01D02*
X245149D01*
G01X235599Y924081D02*
X239949D01*
G01D02*
X244299D01*
G01X231541Y927428D02*
X226391D01*
G01X230741Y920735D02*
X226391D01*
G01X235599Y947507D02*
X239949D01*
G01D02*
X244299D01*
G01X234859Y940814D02*
X239949D01*
G01D02*
X245149D01*
G01X230741Y944660D02*
X230241Y944160D01*
X226391D01*
G01Y937467D02*
X231591D01*
G01X235599Y964239D02*
X239949D01*
G01D02*
X244299D01*
G01X239949Y954200D02*
X244299D01*
G01X235599D02*
X239949D01*
G01X226391Y960892D02*
X230741D01*
G01X226391Y950853D02*
X230741D01*
G01X235599Y977625D02*
X239949D01*
G01D02*
X244299D01*
G01X235599Y970932D02*
X239949D01*
G01D02*
X244299D01*
G01X226391Y980971D02*
X230741D01*
G01X226391Y974278D02*
X230741D01*
G01X226391Y967585D02*
X230741D01*
G01X235599Y991011D02*
X239949D01*
G01D02*
X244299D01*
G01X235599Y984318D02*
X239949D01*
G01D02*
X244299D01*
G01X230741Y987664D02*
X226391D01*
G01X235599Y1031168D02*
X239949D01*
G01D02*
X244299D01*
G01X235599Y1017782D02*
X239949D01*
G01D02*
X244299D01*
G01X235599Y1024475D02*
X239949D01*
G01D02*
X244299D01*
G01X230741Y1027822D02*
X226391D01*
G01X230741Y1017782D02*
X226391D01*
G01X235599Y1044554D02*
X239949D01*
G01D02*
X244299D01*
G01X235599Y1037861D02*
X239949D01*
G01D02*
X244299D01*
G01X226391Y1041207D02*
X230741D01*
G01X226391Y1034515D02*
X230741D01*
G01X235599Y1051247D02*
X239949D01*
G01D02*
X244299D01*
G01X239949Y1057940D02*
X244299D01*
G01X235599D02*
X239949D01*
G01X230741Y1054593D02*
X226391D01*
G01Y1061286D02*
X230741D01*
G01X226391Y1047900D02*
X230741D01*
G01X234749Y1078018D02*
X239949D01*
G01D02*
X245149D01*
G01X235599Y1071326D02*
X239949D01*
G01D02*
X244299D01*
G01X235599Y1064633D02*
X239949D01*
G01D02*
X244299D01*
G01X226391Y1067979D02*
X230741D01*
G01X226391Y1074672D02*
X231591D01*
G01X235599Y1094751D02*
X239949D01*
G01D02*
X244299D01*
G01X234749Y1088058D02*
X239949D01*
G01D02*
X245149D01*
G01X226391Y1091404D02*
X230741D01*
G01X226391Y1084711D02*
X230741D01*
G01X235599Y1108137D02*
X239949D01*
G01D02*
X244299D01*
G01X239949Y1101444D02*
X244299D01*
G01X235599D02*
X239949D01*
G01X226391Y1111483D02*
X230741D01*
G01X226391Y1098097D02*
X230741D01*
G01X226391Y1104790D02*
X230741D01*
G01X239949Y1124869D02*
X245149D01*
G01X234749D02*
X239949D01*
G01Y1114829D02*
X244299D01*
G01X235599D02*
X239949D01*
G01X226391Y1128215D02*
X230741D01*
G01X226391Y1121522D02*
X230741D01*
G01X235599Y1144948D02*
X239949D01*
G01D02*
X244299D01*
G01X239949Y1138255D02*
X244299D01*
G01X235599D02*
X239949D01*
G01Y1131562D02*
X245149D01*
G01X234749D02*
X239949D01*
G01X226391Y1141601D02*
X230741D01*
G01X226391Y1134908D02*
X231591D01*
G01X235599Y1151641D02*
X239949D01*
G01D02*
X244299D01*
G01X226391Y1158333D02*
X230741D01*
G01X226391Y1148294D02*
X231591D01*
G01X239949Y1175066D02*
X244299D01*
G01X235599D02*
X239949D01*
G01Y1168373D02*
X244299D01*
G01X235599D02*
X239949D01*
G01Y1161680D02*
X244299D01*
G01X235599D02*
X239949D01*
G01X226391Y1165026D02*
X230741D01*
G01X226391Y1171719D02*
X230741D01*
G01X239949Y1188452D02*
X244299D01*
G01X235599D02*
X239949D01*
G01Y1181759D02*
X244299D01*
G01X235599D02*
X239949D01*
G01X226391Y1185105D02*
X230741D01*
G01X226391Y1178412D02*
X230741D01*
G01X239949Y1205184D02*
X244299D01*
G01X235599D02*
X239949D01*
G01Y1198491D02*
X244299D01*
G01X235599D02*
X239949D01*
G01X226391Y1208530D02*
X230741D01*
G01X226391Y1201837D02*
X230741D01*
G01X226391Y1195144D02*
X230741D01*
G01X234749Y1225263D02*
X239949D01*
G01D02*
X245149D01*
G01X235599Y1218570D02*
X239949D01*
G01D02*
X244299D01*
G01X239949Y1211877D02*
X244299D01*
G01X235599D02*
X239949D01*
G01X226391Y1221916D02*
X230741D01*
G01X226391Y1215223D02*
X230741D01*
G01X235599Y1241995D02*
X239949D01*
G01D02*
X244299D01*
G01X235186Y1234977D02*
X235511Y1235302D01*
X239949D01*
G01D02*
X245149D01*
G01X226391Y1231955D02*
X231591D01*
G01X226391Y1238648D02*
X231591D01*
G01X235599Y1248688D02*
X239949D01*
G01D02*
X244299D01*
G01X226391Y1245341D02*
X230741D01*
G01X239949Y1258727D02*
X235599D01*
G01X254756Y156727D02*
X257256D01*
G01X251873Y451974D02*
X254393D01*
X256695Y454276D01*
Y458617D01*
G01Y461117D02*
Y458617D01*
G01X669778Y759929D02*
X662324Y752475D01*
X600388D01*
X594322Y758541D01*
X368778D01*
X366534Y760785D01*
X301837D01*
X300377Y759325D01*
X291676D01*
X289896Y757545D01*
X268967D01*
X263847Y752425D01*
X255977D01*
X253057Y755345D01*
G01X251741Y766798D02*
X256091D01*
G01D02*
X260441D01*
G01X251741Y780184D02*
X256091D01*
G01D02*
X260441D01*
G01X251741Y773491D02*
X256091D01*
G01D02*
X260441D01*
G01X251741Y803609D02*
X256091D01*
G01D02*
X260441D01*
G01X256091Y796916D02*
X260441D01*
G01X251741D02*
X256091D01*
G01X251741Y790223D02*
X256091D01*
G01D02*
X260441D01*
G01X250891Y816995D02*
X256091D01*
G01D02*
X261291D01*
G01X251741Y810302D02*
X256091D01*
G01D02*
X260441D01*
G01X251741Y833727D02*
X256091D01*
G01D02*
X260441D01*
G01X250891Y827034D02*
X256091D01*
G01D02*
X261291D01*
G01X251741Y847113D02*
X256091D01*
G01D02*
X260441D01*
G01X256091Y840420D02*
X260441D01*
G01X251741D02*
X256091D01*
G01X250891Y863845D02*
X256091D01*
G01D02*
X261291D01*
G01X250891Y853806D02*
X256091D01*
G01D02*
X261291D01*
G01X251741Y870538D02*
X256091D01*
G01D02*
X260441D01*
G01X256091Y883924D02*
X260441D01*
G01X251741D02*
X256091D01*
G01Y877231D02*
X260441D01*
G01X251741D02*
X256091D01*
G01Y900656D02*
X260441D01*
G01X250891D02*
X256091D01*
G01Y890617D02*
X260441D01*
G01X251741D02*
X256091D01*
G01X251741Y914042D02*
X256091D01*
G01D02*
X260441D01*
G01X251741Y907349D02*
X256091D01*
G01D02*
X260441D01*
G01X250891Y927428D02*
X256091D01*
G01D02*
X261291D01*
G01X251741Y920735D02*
X256091D01*
G01D02*
X260441D01*
G01X251741Y944160D02*
X256091D01*
G01D02*
X260441D01*
G01X250891Y937467D02*
X256091D01*
G01D02*
X261291D01*
G01X251741Y960892D02*
X256091D01*
G01D02*
X260441D01*
G01X256091Y950853D02*
X260441D01*
G01X251741D02*
X256091D01*
G01X251741Y980971D02*
X256091D01*
G01D02*
X260441D01*
G01X251741Y974278D02*
X256091D01*
G01D02*
X260441D01*
G01X251741Y967585D02*
X256091D01*
G01D02*
X260441D01*
G01X251741Y987664D02*
X256091D01*
G01D02*
X260441D01*
G01X251741Y1027822D02*
X256091D01*
G01D02*
X260441D01*
G01X251741Y1017782D02*
X256091D01*
G01D02*
X260441D01*
G01X251741Y1041207D02*
X256091D01*
G01D02*
X260441D01*
G01X251741Y1034515D02*
X256091D01*
G01D02*
X260441D01*
G01X251741Y1061286D02*
X256091D01*
G01D02*
X260441D01*
G01X256091Y1054593D02*
X260441D01*
G01X251741D02*
X256091D01*
G01X251741Y1047900D02*
X256091D01*
G01D02*
X260441D01*
G01X250891Y1074672D02*
X256091D01*
G01D02*
X261291D01*
G01X250891Y1067979D02*
X256091D01*
G01D02*
X261291D01*
G01X251741Y1091404D02*
X256091D01*
G01D02*
X260441D01*
G01X251741Y1084711D02*
X256091D01*
G01D02*
X260441D01*
G01X251741Y1104790D02*
X256091D01*
G01D02*
X260441D01*
G01X256091Y1111483D02*
X261291D01*
G01X250891D02*
X256091D01*
G01Y1098097D02*
X260441D01*
G01X251741D02*
X256091D01*
G01Y1128215D02*
X260441D01*
G01X251741D02*
X256091D01*
G01Y1121522D02*
X261291D01*
G01X250891D02*
X256091D01*
G01X251741Y1134908D02*
X256091D01*
G01D02*
X260441D01*
G01X256091Y1141601D02*
X260441D01*
G01X251741D02*
X256091D01*
G01X251741Y1158333D02*
X256091D01*
G01D02*
X260441D01*
G01X256091Y1148294D02*
X260441D01*
G01X251741D02*
X256091D01*
G01Y1171719D02*
X260441D01*
G01X251741D02*
X256091D01*
G01Y1165026D02*
X260441D01*
G01X251741D02*
X256091D01*
G01Y1185105D02*
X260441D01*
G01X251741D02*
X256091D01*
G01Y1178412D02*
X260441D01*
G01X251741D02*
X256091D01*
G01Y1208530D02*
X260441D01*
G01X251741D02*
X256091D01*
G01Y1201837D02*
X260441D01*
G01X251741D02*
X256091D01*
G01Y1195144D02*
X260441D01*
G01X250891D02*
X256091D01*
G01X250891Y1221916D02*
X256091D01*
G01D02*
X261291D01*
G01X251741Y1215223D02*
X256091D01*
G01D02*
X260441D01*
G01X250891Y1231955D02*
X256091D01*
G01D02*
X261291D01*
G01X251741Y1238648D02*
X256091D01*
G01D02*
X260441D01*
G01X251741Y1245341D02*
X256091D01*
G01D02*
X260441D01*
G01X266975Y142892D02*
Y140107D01*
G01X271821Y254656D02*
Y251962D01*
G01X267759Y254656D02*
Y251962D01*
G01X259224Y419532D02*
X260177Y418579D01*
X266461D01*
G01X269629Y443735D02*
X272029D01*
G01X266511Y431039D02*
X259869D01*
G01X274850Y442562D02*
X271893Y439605D01*
X269659D01*
G01X259845Y458617D02*
Y461117D01*
G01X286481Y254656D02*
Y251962D01*
G01X281077Y254656D02*
Y251962D01*
G01X276491Y254656D02*
Y251962D01*
G01X289274Y293313D02*
Y290662D01*
G01X284515Y293313D02*
Y290662D01*
G01X276500Y444862D02*
X278575Y446937D01*
Y447862D01*
G01X279500Y455362D02*
X278575Y454437D01*
Y451862D01*
G01X296478Y149203D02*
Y151703D01*
G01Y158703D02*
Y156203D01*
G01X304651Y254656D02*
Y251962D01*
G01X291759Y254656D02*
Y251962D01*
G01X302765Y293313D02*
Y290662D01*
G01X298184Y293313D02*
Y290662D01*
G01X293763Y293313D02*
Y290662D01*
G01X304047Y1368565D02*
X305094Y1369612D01*
X307019D01*
G01X308175Y146702D02*
Y150278D01*
X310235Y152338D01*
X312277D01*
G01X308175Y144202D02*
Y146702D01*
G01X317129Y254656D02*
Y251962D01*
G01X306736Y293313D02*
Y290662D01*
G01X316463Y293313D02*
Y290662D01*
G01X321276Y599298D02*
X324106D01*
G01X315221Y1369807D02*
Y1372445D01*
G01X323975Y161562D02*
X325601Y159936D01*
X328760D01*
Y157086D01*
G01X326900Y162287D02*
X324700D01*
X323975Y161562D01*
G01X329648Y254602D02*
Y252202D01*
G01X329002Y293313D02*
Y290662D01*
G01X324106Y599298D02*
X324347Y599057D01*
Y590158D01*
G01X339775Y141862D02*
X341500D01*
X342700Y140662D01*
Y139662D01*
G01X353145Y221862D02*
Y219362D01*
G01X342000Y255012D02*
Y252612D01*
G01X354672Y255093D02*
Y252693D01*
G01X341295Y292639D02*
Y290239D01*
G01X354145Y292991D02*
Y290591D01*
G01X348880Y703442D02*
X349772Y704334D01*
Y705779D01*
G01X357323Y130002D02*
X363465D01*
X363625Y130162D01*
G01D02*
Y127662D01*
G01X363525Y156202D02*
X363265Y155942D01*
X357324D01*
G01X363525Y158702D02*
Y156202D01*
G01X367306Y255211D02*
Y252811D01*
G01X366498Y292664D02*
Y290264D01*
G01X600460Y744912D02*
X596975Y748397D01*
X372469D01*
X370477Y746405D01*
X358902D01*
G01X370874Y1333458D02*
Y1335876D01*
G01X367490Y1332568D02*
X366911Y1333147D01*
Y1333846D01*
X366903Y1333854D01*
Y1335100D01*
G01X385585Y124322D02*
X383160D01*
G01X385500Y128491D02*
X383060D01*
G01X371551Y221362D02*
Y224862D01*
G01X379860Y254896D02*
Y252162D01*
G01X379112Y292786D02*
Y290386D01*
G01X378372Y1334095D02*
X380842D01*
G01X374391Y1648476D02*
X374500Y1648367D01*
Y1645997D01*
G01X374391Y1650876D02*
Y1648476D01*
G01X385123Y1643174D02*
Y1639732D01*
G01X378547Y1643180D02*
Y1639732D01*
G01X373320Y1688202D02*
X374509Y1687013D01*
Y1685734D01*
G01X376610Y1688252D02*
X376800D01*
X378509Y1686543D01*
Y1685734D01*
G01X388735Y119822D02*
X389706Y120793D01*
X400317D01*
G01X388735Y117322D02*
Y119822D01*
G01X408284Y161162D02*
X406134D01*
X405923Y160951D01*
X402220D01*
G01X392616Y254886D02*
Y252162D01*
G01X392083Y293354D02*
Y290954D01*
G01X399673Y1332653D02*
X399171Y1332151D01*
Y1330142D01*
G01X403130Y1335963D02*
X402973Y1335806D01*
Y1333428D01*
G01X400926Y1402207D02*
X398720D01*
X397819Y1403108D01*
G01X391249Y1401048D02*
X392284D01*
X393699Y1402463D01*
G01X392947Y1397827D02*
X393773Y1398653D01*
X395357D01*
G01X390934Y1404085D02*
X391694Y1404845D01*
X392931D01*
X393699Y1405613D01*
G01X397819Y1408908D02*
X394524Y1405613D01*
X393699D01*
G01X403324Y1411231D02*
X400919D01*
G01X392517Y1419015D02*
Y1417308D01*
X394750Y1415075D01*
Y1413619D01*
G01X390934Y1407605D02*
X392199D01*
X393699Y1406105D01*
Y1405613D01*
G01X403125Y1422578D02*
Y1425008D01*
G01X399346Y1541810D02*
X396768D01*
G01X399346Y1556810D02*
X396946D01*
G01X392550Y1618650D02*
X391830Y1619370D01*
X390192D01*
X387915Y1621647D01*
Y1622722D01*
G01X391563Y1642644D02*
Y1640244D01*
G01X407557Y1655310D02*
X406639Y1654392D01*
X403194D01*
X401824Y1655762D01*
Y1657204D01*
G01X419901Y117491D02*
X423500D01*
G01D02*
X420198Y120793D01*
X417443D01*
G01X408284Y163662D02*
Y161162D01*
G01X423145Y225362D02*
X423086Y225303D01*
X416415D01*
G01X423845Y236562D02*
X423681Y236726D01*
X417052D01*
G01X431873Y255205D02*
X417765D01*
G01D02*
Y252162D01*
G01X404985Y254815D02*
Y252162D01*
G01X404215Y293540D02*
Y291140D01*
G01X417218Y293674D02*
Y291274D01*
G01X412211Y1045639D02*
X412212D01*
G01X404811D02*
X404812D01*
G01X419612Y1039230D02*
Y1041339D01*
X419611Y1041340D01*
G01X415912Y1039230D02*
Y1041339D01*
X415911Y1041340D01*
G01X412212Y1039230D02*
Y1041339D01*
X412211Y1041340D01*
G01X414617Y1333473D02*
X413995Y1334095D01*
X412118D01*
G01X409980Y1393878D02*
X412465D01*
G01X407125Y1422578D02*
Y1424978D01*
G01X407625Y1549942D02*
Y1552572D01*
G01X412386Y1550046D02*
X407729D01*
X407625Y1549942D01*
G01X411125Y1607400D02*
X408600D01*
G01X411125Y1611300D02*
Y1607400D01*
G01X410700Y1655310D02*
X407557D01*
G01X409857Y1680267D02*
Y1682767D01*
G01X435340Y122196D02*
X433646D01*
X432039Y123803D01*
Y124015D01*
G01Y128515D02*
Y124015D01*
G01X435340Y122196D02*
X437840D01*
G01X423845Y232562D02*
Y236562D01*
G01X423145Y227862D02*
Y225362D01*
G01X423845Y232562D02*
X421200D01*
G01X429702Y293163D02*
Y290763D01*
G01X436743Y504233D02*
X434343D01*
G01X436743Y509733D02*
X434343D01*
G01X436743Y498733D02*
X434343D01*
G01X436743Y515233D02*
X434343D01*
G01X436743Y526233D02*
X434343D01*
G01X436743Y520733D02*
X434343D01*
G01X436743Y542733D02*
X434343D01*
G01X436743Y547769D02*
X434343D01*
G01X436743Y552769D02*
X434343D01*
G01X423312Y1039230D02*
Y1041340D01*
G01X434983Y1333457D02*
Y1335924D01*
G01X431578Y1332560D02*
X430730Y1331712D01*
Y1330042D01*
G01X432996Y1547810D02*
Y1551810D01*
G01D02*
X435396D01*
G01X426970Y1579466D02*
X424570D01*
G01X433383Y1600229D02*
Y1602629D01*
G01X421775Y1616600D02*
X424800D01*
G01X451418Y78782D02*
Y75985D01*
G01D02*
Y72664D01*
X454066Y70016D01*
X456128D01*
G01X437840Y122196D02*
X441384D01*
X442900Y120680D01*
Y117195D01*
G01X442265Y293339D02*
Y290939D01*
G01X451520Y473412D02*
Y475837D01*
G01X445253Y542519D02*
X442853D01*
G01X445253Y547519D02*
X442853D01*
G01X442628Y1334095D02*
X445153D01*
G01X446258Y1439206D02*
Y1441606D01*
G01X449778Y1439206D02*
Y1441606D01*
G01X450020Y1568012D02*
Y1570412D01*
G01X442020Y1568012D02*
X446020D01*
G01X452020Y1578012D02*
Y1580412D01*
G01X444458Y1602654D02*
Y1600154D01*
G01D02*
Y1595230D01*
X440019Y1590791D01*
Y1586989D01*
G01X459714Y120948D02*
X462620D01*
G01X468323Y260996D02*
Y254562D01*
G01X465236Y296973D02*
X467736D01*
G01X467211Y369308D02*
Y371902D01*
G01Y369308D02*
Y369208D01*
X463297D01*
X461298Y367209D01*
Y364503D01*
G01X455720Y402337D02*
Y404762D01*
G01X459098Y434003D02*
Y431054D01*
X462074Y428078D01*
X462921D01*
G01X465421D02*
X462921D01*
G01X464738Y1333085D02*
X463655Y1332002D01*
Y1330533D01*
G01X467644Y1333475D02*
Y1335981D01*
G01X465749Y1401238D02*
X467469D01*
X468272Y1400435D01*
G01X453176Y1409125D02*
X455576D01*
G01X453176Y1417125D02*
X455576D01*
G01X453176Y1420625D02*
X455576D01*
G01X453176Y1427632D02*
X455576D01*
G01X453176Y1424125D02*
X455576D01*
G01X453595Y1547437D02*
Y1551470D01*
G01X459520Y1549362D02*
Y1546962D01*
G01X464020Y1578012D02*
Y1580412D01*
G01X457220Y1586420D02*
Y1584020D01*
G01X456510Y1614472D02*
X453961Y1611923D01*
X453155D01*
G01X462060Y1643282D02*
X460930D01*
X459670Y1644542D01*
Y1647853D01*
X463474Y1651657D01*
X464930D01*
G01D02*
X468040D01*
G01X481246Y158864D02*
Y155074D01*
X478359Y152187D01*
X478316D01*
G01X481246Y161364D02*
Y158864D01*
G01X473500Y234787D02*
X470900D01*
G01X481500Y293787D02*
X478995D01*
G01X482720Y363287D02*
Y360862D01*
G01X474720Y366437D02*
Y368862D01*
X476585Y370727D01*
G01D02*
X479767Y373909D01*
Y375319D01*
G01X474756Y1334095D02*
X477162D01*
G01X477891Y1400385D02*
X474983D01*
G01X469488Y1610682D02*
Y1607362D01*
G01D02*
Y1603682D01*
G01X472210Y1622735D02*
X474750Y1625275D01*
Y1630688D01*
X474435Y1631003D01*
G01X469445Y1622735D02*
X472210D01*
G01X489230Y1643592D02*
X485580Y1647242D01*
X475505D01*
G01Y1663242D02*
X477905D01*
G01X475435Y1677462D02*
X477835D01*
G01X475435Y1681462D02*
Y1677462D01*
G01X488748Y72264D02*
Y66565D01*
G01D02*
X488858Y66455D01*
Y61205D01*
G01X489018Y55895D02*
Y61045D01*
X488858Y61205D01*
G01X503875Y86422D02*
X503170Y85717D01*
X499680D01*
G01X499580Y78442D02*
X499680Y78542D01*
Y85717D01*
G01X500925Y228362D02*
X500602Y228039D01*
X494000D01*
G01X500925Y228362D02*
Y231262D01*
G01X509496Y261964D02*
X499421D01*
X499096Y261639D01*
G01Y252462D02*
Y261639D01*
G01X501136Y296273D02*
X498636D01*
G01X489261Y305398D02*
X486861D01*
G01X490720Y366437D02*
Y368862D01*
G01D02*
Y372979D01*
X493167Y375426D01*
G01X499570Y427937D02*
X502070D01*
G01X495747Y433862D02*
Y430913D01*
X498723Y427937D01*
X499570D01*
G01X488169Y473271D02*
Y475696D01*
G01X487042Y541522D02*
X489962D01*
X491043Y542603D01*
Y547947D01*
G01Y550447D02*
Y547947D01*
G01X505575Y241862D02*
X508000D01*
G01X503040Y287928D02*
X503974Y288862D01*
X505425D01*
G01X505182Y315404D02*
X502239D01*
G01X514720Y363287D02*
Y360862D01*
G01X502720Y363287D02*
Y360862D01*
G01X506720Y366437D02*
Y368862D01*
G01X509267Y375319D02*
Y373409D01*
X506720Y370862D01*
Y368862D01*
G01X513720Y392787D02*
Y390362D01*
G01X505720Y395937D02*
Y398362D01*
G01D02*
Y403272D01*
X507267Y404819D01*
G01X517020Y484027D02*
X519520D01*
G01X501735Y615612D02*
X504135D01*
G01X509246Y1422494D02*
Y1420002D01*
G01X523720Y366437D02*
X523670Y366487D01*
Y368892D01*
G01X526267Y375819D02*
Y373909D01*
X523670Y371312D01*
Y368892D01*
G01X529720Y392787D02*
Y390362D01*
G01X521720Y395937D02*
Y398362D01*
G01D02*
Y403272D01*
X523267Y404819D01*
G01X535375Y446396D02*
X532650D01*
G01X521885Y455062D02*
Y457698D01*
X520924Y458659D01*
Y460733D01*
G01X521885Y452442D02*
Y455062D01*
G01X526825Y489112D02*
X524425D01*
G01X522805Y478492D02*
Y482155D01*
G01X519161Y505969D02*
X521561D01*
G01X519161Y500469D02*
X521561D01*
G01X526825Y495112D02*
X524425D01*
G01X519161Y516969D02*
X521561D01*
G01X519161Y522469D02*
X521561D01*
G01X519161Y511469D02*
X521561D01*
G01X519161Y527969D02*
X521561D01*
G01X519161Y539819D02*
X521561D01*
G01X519079Y850286D02*
Y848177D01*
X519078Y848176D01*
G01X539415Y99172D02*
X542460D01*
G01X539475Y112512D02*
Y118772D01*
G01X539397Y131802D02*
X552349D01*
X552395Y131756D01*
G01X547395Y149802D02*
Y147302D01*
G01X539397Y149802D02*
X547395D01*
G01X552720Y164787D02*
X552659Y164726D01*
X538852D01*
G01X539639Y269472D02*
Y271972D01*
G01X535720Y363287D02*
Y360862D01*
G01X552395Y131756D02*
Y134340D01*
G01X552720Y164787D02*
X552795Y164712D01*
Y161362D01*
G01X552720Y164787D02*
X555220D01*
G01X552795Y184862D02*
X555195D01*
G01X552795Y171862D02*
X555195D01*
G01X554489Y253202D02*
X552089D01*
G01X566614Y305247D02*
X562804Y309057D01*
X558240D01*
G01X566730Y300992D02*
X566614Y301108D01*
Y305247D01*
G01X571556Y378124D02*
X571481Y378199D01*
X567390D01*
X565378Y376187D01*
Y373573D01*
G01X559300Y411482D02*
Y414112D01*
G01X564942Y451710D02*
X563044D01*
X561470Y450136D01*
X558118D01*
G01X557829Y454479D02*
X564442D01*
X564942Y453979D01*
Y451710D01*
G01X565586Y491680D02*
X567733D01*
G01X566510Y1352217D02*
X567495Y1353202D01*
Y1355247D01*
G01X552000Y1449787D02*
X552220D01*
X552612Y1449395D01*
X555057D01*
G01D02*
X557328D01*
X557720Y1449787D01*
G01X579247Y130542D02*
X584521D01*
X585421Y129642D01*
X588245D01*
G01X573115Y157932D02*
Y145497D01*
X573880Y144732D01*
X577147D01*
G01X573115Y161232D02*
Y157932D01*
G01X570645Y167112D02*
X568245D01*
G01X581881Y198378D02*
X579481D01*
G01X581875Y190092D02*
X579170D01*
G01X581881Y206378D02*
X579481D01*
G01X581645Y221362D02*
X579245D01*
G01X581645Y225362D02*
Y221362D01*
G01X575359Y262632D02*
Y265132D01*
G01X575124Y257291D02*
Y262397D01*
X575359Y262632D01*
G01X584970Y296657D02*
X582510D01*
G01X584970Y304052D02*
X582510D01*
G01X584970Y311571D02*
X582510D01*
G01D02*
X581786Y310847D01*
X569664D01*
G01X574491Y376549D02*
X572916Y378124D01*
X571556D01*
G01X580645Y488212D02*
X583045D01*
G01X567733Y491680D02*
X568840Y492787D01*
Y498546D01*
G01Y501046D02*
Y498546D01*
G01X578925Y514362D02*
Y516846D01*
G01X571555Y1352487D02*
X570645Y1353397D01*
Y1355247D01*
G01X567495D02*
Y1358777D01*
G01X570645D02*
Y1361358D01*
G01X588245Y129642D02*
Y132142D01*
G01X592220Y173862D02*
X592970Y174612D01*
X595145D01*
G01D02*
Y171537D01*
X593443Y169835D01*
X591355D01*
G01X584795Y233362D02*
Y230862D01*
G01D02*
Y230762D01*
X588151Y227406D01*
X598416D01*
G01X591727Y288527D02*
X591861Y288661D01*
X599552D01*
G01X591727Y285862D02*
Y288527D01*
G01X594220Y433937D02*
X594385Y434102D01*
X599661D01*
G01X591720Y433937D02*
X594220D01*
G01X596800Y501957D02*
X598661Y500096D01*
Y497102D01*
G01X594090Y501957D02*
X596800D01*
G01X591425Y524862D02*
Y522337D01*
G01X614384Y121817D02*
Y119342D01*
G01X611381Y202878D02*
Y200378D01*
G01Y207378D02*
Y209878D01*
G01X621060Y271066D02*
X615156D01*
X614095Y272127D01*
Y275055D01*
G01X608895D02*
X614095D01*
G01X609040Y317282D02*
X607675Y318647D01*
Y320824D01*
G01X616645Y462862D02*
X614220D01*
G01X599645Y482362D02*
Y479862D01*
G01X613047Y741492D02*
Y741537D01*
X609672Y744912D01*
X600460D01*
G01X704000Y740862D02*
X700743Y737605D01*
X626598D01*
X619298Y744905D01*
X616471D01*
X613103Y741537D01*
X613092D01*
X613047Y741492D01*
G01X626699Y121817D02*
Y119182D01*
G01X630951Y121817D02*
Y119182D01*
G01X622592Y121817D02*
X626699D01*
G01X630795Y230362D02*
Y234362D01*
G01D02*
Y236862D01*
G01X627064Y253127D02*
X624139D01*
X622300Y254966D01*
X616899D01*
G01X629564Y253127D02*
X627064D01*
G01X615635Y320880D02*
Y317637D01*
G01X623365Y320900D02*
Y316742D01*
G01X631146Y320915D02*
Y317768D01*
G01X631645Y457862D02*
X629220D01*
G01X631645Y462862D02*
X629220D01*
G01X620899Y770144D02*
X625249D01*
G01D02*
X629599D01*
G01X620899Y783530D02*
X625249D01*
G01X620899Y776837D02*
X625249D01*
G01D02*
X629599D01*
G01X625249Y783530D02*
X629599D01*
G01Y800263D02*
X625249D01*
G01X620899Y793570D02*
X625249D01*
G01D02*
X629599D01*
G01X625249Y800263D02*
X620846D01*
G01X630593Y813648D02*
X625249D01*
G01X630792Y806955D02*
X625249D01*
G01D02*
X619632D01*
G01X625249Y813648D02*
X620076D01*
G01X629599Y830381D02*
X625249D01*
G01X629599Y820341D02*
X625249D01*
G01D02*
X620899D01*
G01X625249Y830381D02*
X620899D01*
G01X630754Y850459D02*
X625249D01*
G01X629599Y843766D02*
X625249D01*
G01X620899Y837074D02*
X625249D01*
G01D02*
X629599D01*
G01X625249Y843766D02*
X620899D01*
G01X625249Y850459D02*
X620005D01*
G01X629599Y867192D02*
X625249D01*
G01X630481Y857152D02*
X625249D01*
G01D02*
X620058D01*
G01X625249Y867192D02*
X620899D01*
G01X629599Y880577D02*
X625249D01*
G01X629599Y873885D02*
X625249D01*
G01D02*
X620899D01*
G01X625249Y880577D02*
X620899D01*
G01Y893963D02*
X625249D01*
G01X620899Y887270D02*
X625249D01*
G01D02*
X629599D01*
G01X625249Y893963D02*
X630756D01*
G01X629599Y910696D02*
X625249D01*
G01X620899Y917389D02*
X625249D01*
G01X620899Y904003D02*
X625249D01*
G01D02*
X629599D01*
G01X625249Y910696D02*
X620899D01*
G01X625249Y917389D02*
X629599D01*
G01X619905Y930774D02*
X625249D01*
G01X629599Y924081D02*
X625249D01*
G01D02*
X620899D01*
G01X625249Y930774D02*
X628812D01*
X628889Y930697D01*
X630399D01*
G01X620899Y947507D02*
X625249D01*
G01X630777Y940814D02*
X625249D01*
G01D02*
X619964D01*
G01X625249Y947507D02*
X629599D01*
G01X620899Y964239D02*
X625249D01*
G01X620899Y954200D02*
X625249D01*
G01D02*
X629599D01*
G01X625249Y964239D02*
X629599D01*
G01Y977625D02*
X625249D01*
G01X620899Y970932D02*
X625249D01*
G01D02*
X629599D01*
G01X625249Y977625D02*
X620899D01*
G01Y991011D02*
X625249D01*
G01X620899Y984318D02*
X625249D01*
G01D02*
X629599D01*
G01X625249Y991011D02*
X629599D01*
G01Y1031168D02*
X625249D01*
G01X629599Y1017782D02*
X625249D01*
G01X629599Y1024475D02*
X625249D01*
G01Y1017782D02*
X620899D01*
G01X625249Y1024475D02*
X620899D01*
G01X625249Y1031168D02*
X620899D01*
G01X629599Y1044554D02*
X625249D01*
G01X629599Y1037861D02*
X625249D01*
G01D02*
X620899D01*
G01X625249Y1044554D02*
X620899D01*
G01X629599Y1057940D02*
X625249D01*
G01X620899Y1051247D02*
X625249D01*
G01D02*
X629599D01*
G01X625249Y1057940D02*
X620899D01*
G01X629599Y1078018D02*
X625249D01*
G01X619999Y1071326D02*
X625249D01*
G01X629599Y1064633D02*
X625249D01*
G01D02*
X620899D01*
G01X625249Y1071326D02*
X630399D01*
G01X625249Y1078018D02*
X620899D01*
G01X629599Y1088058D02*
X625249D01*
G01X620899Y1094751D02*
X625249D01*
G01Y1088058D02*
X620899D01*
G01X625249Y1094751D02*
X629599D01*
G01Y1108137D02*
X625249D01*
G01X620899Y1101444D02*
X625249D01*
G01D02*
X629599D01*
G01X625249Y1108137D02*
X620899D01*
G01X620099Y1114829D02*
X625249D01*
G01X630363Y1124674D02*
X629294D01*
X629099Y1124869D01*
X625249D01*
G01Y1114829D02*
X630399D01*
G01X625249Y1124869D02*
X620469D01*
X620369Y1124969D01*
G01X629599Y1131562D02*
X625249D01*
G01X620899Y1144948D02*
X625249D01*
G01X620899Y1138255D02*
X625249D01*
G01Y1131562D02*
X620899D01*
G01X625249Y1138255D02*
X629599D01*
G01X625249Y1144948D02*
X629599D01*
G01X620899Y1151641D02*
X625249D01*
G01D02*
X629599D01*
G01X625249Y1161680D02*
X629734D01*
X629833Y1161581D01*
G01X620899Y1175066D02*
X625249D01*
G01X620899Y1168373D02*
X625249D01*
G01X620511Y1161680D02*
X625249D01*
G01Y1168373D02*
X629599D01*
G01X625249Y1175066D02*
X629599D01*
G01X620899Y1188452D02*
X625249D01*
G01X620899Y1181759D02*
X625249D01*
G01D02*
X629599D01*
G01X625249Y1188452D02*
X630623D01*
G01X620899Y1205184D02*
X625249D01*
G01X629599Y1198491D02*
X625249D01*
G01D02*
X620899D01*
G01X625249Y1205184D02*
X629599D01*
G01Y1225263D02*
X625249D01*
G01X620899Y1218570D02*
X625249D01*
G01X620899Y1211877D02*
X625249D01*
G01D02*
X629599D01*
G01X625249Y1218570D02*
X629599D01*
G01X625249Y1225263D02*
X620899D01*
G01Y1241995D02*
X625249D01*
G01X620036Y1235302D02*
X625249D01*
G01D02*
X630922D01*
G01X625249Y1241995D02*
X629599D01*
G01Y1248688D02*
X625249D01*
G01D02*
X620899D01*
G01X629931Y1258727D02*
X625249D01*
G01X646425Y93362D02*
X646517Y93270D01*
Y91128D01*
X646425Y91036D01*
Y89232D01*
X648320Y87337D01*
G01X647220Y96929D02*
X646425Y96134D01*
Y93362D01*
G01X646145Y171362D02*
X643170D01*
G01X642709Y249202D02*
X645109D01*
G01X642709Y260202D02*
X645109D01*
G01X640720Y294327D02*
X643800D01*
G01X640720Y306547D02*
X643800D01*
G01X646645Y452862D02*
X644220D01*
G01X646645Y457862D02*
Y452862D01*
G01Y477862D02*
X644220D01*
G01X640798Y472934D02*
X643266Y475402D01*
X645780D01*
X646645Y474537D01*
Y472862D01*
G01X646815Y515459D02*
Y517974D01*
G01X637020Y522362D02*
X636295Y523087D01*
Y526362D01*
G01X637041Y766798D02*
X641391D01*
G01D02*
X645741D01*
G01Y773491D02*
X641391D01*
G01X637041Y780184D02*
X641391D01*
G01Y773491D02*
X637041D01*
G01X641391Y780184D02*
X645741D01*
G01Y803609D02*
X641391D01*
G01X645741Y796916D02*
X641391D01*
G01X637041Y790223D02*
X641391D01*
G01D02*
X645741D01*
G01X641391Y796916D02*
X637041D01*
G01X641391Y803609D02*
X637041D01*
G01X646844Y810302D02*
X641391D01*
G01X637041Y816995D02*
X641391D01*
G01Y810302D02*
X636221D01*
G01X641391Y816995D02*
X646774D01*
G01X637041Y833727D02*
X641391D01*
G01X645741Y827034D02*
X641391D01*
G01D02*
X637041D01*
G01X641391Y833727D02*
X645741D01*
G01X645801Y847113D02*
X641391D01*
G01X645741Y840420D02*
X641391D01*
G01D02*
X637041D01*
G01X641391Y847113D02*
X637041D01*
G01X646819Y853806D02*
X641391D01*
G01X636266Y863845D02*
X641391D01*
G01Y853806D02*
X636755D01*
X636606Y853955D01*
X636332D01*
G01X641391Y863845D02*
X645918D01*
G01X645741Y877231D02*
X641391D01*
G01X645741Y870538D02*
X641391D01*
G01X637041Y883924D02*
X641391D01*
G01Y870538D02*
X637041D01*
G01X641391Y877231D02*
X637041D01*
G01X641391Y883924D02*
X645741D01*
G01Y900656D02*
X641391D01*
G01X645741Y890617D02*
X641391D01*
G01D02*
X637041D01*
G01X641391Y900656D02*
X637041D01*
G01X645741Y914042D02*
X641391D01*
G01X637041Y907349D02*
X641391D01*
G01D02*
X645741D01*
G01X641391Y914042D02*
X637041D01*
G01X636026Y927428D02*
X641391D01*
G01X637041Y920735D02*
X641391D01*
G01D02*
X645741D01*
G01X641391Y927428D02*
X641489Y927526D01*
X646393D01*
G01X637041Y944160D02*
X641391D01*
G01X646703Y937467D02*
X641391D01*
G01D02*
X636170D01*
G01X641391Y944160D02*
X645741D01*
G01X637041Y960892D02*
X641391D01*
G01X645741Y950853D02*
X641391D01*
G01D02*
X637041D01*
G01X641391Y960892D02*
X645741D01*
G01Y980971D02*
X641391D01*
G01X645741Y974278D02*
X641391D01*
G01X645741Y967585D02*
X641391D01*
G01D02*
X637041D01*
G01X641391Y974278D02*
X637041D01*
G01X641391Y980971D02*
X637041D01*
G01X645741Y987664D02*
X641391D01*
G01D02*
X637041D01*
G01X645741Y1027822D02*
X641391D01*
G01X637041Y1017782D02*
X641391D01*
G01D02*
X645741D01*
G01X641391Y1027822D02*
X637041D01*
G01X645741Y1041207D02*
X641391D01*
G01X645741Y1034515D02*
X641391D01*
G01D02*
X637041D01*
G01X641391Y1041207D02*
X637041D01*
G01X645741Y1061286D02*
X641391D01*
G01X637041Y1054593D02*
X641391D01*
G01X637041Y1047900D02*
X641391D01*
G01D02*
X645741D01*
G01X641391Y1054593D02*
X645741D01*
G01X641391Y1061286D02*
X637041D01*
G01X646541Y1074672D02*
X641391D01*
G01X636841Y1067979D02*
X641391D01*
G01D02*
X645741D01*
G01X641391Y1074672D02*
X636141D01*
G01X645741Y1091404D02*
X641391D01*
G01X636241Y1084711D02*
X641391D01*
G01D02*
X645741D01*
G01X641391Y1091404D02*
X637041D01*
G01Y1111483D02*
X641391D01*
G01X637041Y1098097D02*
X641391D01*
G01X637041Y1104790D02*
X641391D01*
G01Y1098097D02*
X645741D01*
G01X641391Y1104790D02*
X645741D01*
G01X641391Y1111483D02*
X645741D01*
G01Y1121522D02*
X641391D01*
G01X645741Y1128215D02*
X641391D01*
G01Y1121522D02*
X637041D01*
G01X641391Y1128215D02*
X637541D01*
X637041Y1128715D01*
Y1128915D01*
G01X635744Y1134908D02*
X641391D01*
G01X637041Y1141601D02*
X641391D01*
G01Y1134908D02*
X645541D01*
X645741Y1135108D01*
X646584D01*
G01X641391Y1141601D02*
X645741D01*
G01X637041Y1148294D02*
X641391D01*
G01X637041Y1158333D02*
X641391D01*
G01Y1148294D02*
X645741D01*
G01X641391Y1158333D02*
X645741D01*
G01Y1171719D02*
X641391D01*
G01X637041Y1165026D02*
X641391D01*
G01D02*
X645741D01*
G01X641391Y1171719D02*
X637041D01*
G01X645741Y1185105D02*
X641391D01*
G01X637041Y1178412D02*
X641391D01*
G01D02*
X645741D01*
G01X641391Y1185105D02*
X637041D01*
G01Y1208530D02*
X641391D01*
G01X637041Y1201837D02*
X641391D01*
G01X645741Y1195144D02*
X641391D01*
G01D02*
X637041D01*
G01X641391Y1201837D02*
X645741D01*
G01X641391Y1208530D02*
X645741D01*
G01X646570Y1221916D02*
X641391D01*
G01X637041Y1215223D02*
X641391D01*
G01D02*
X645741D01*
G01X641391Y1221916D02*
X636005D01*
G01X637041Y1238648D02*
X641391D01*
G01X646539Y1231955D02*
X641391D01*
G01D02*
X636388D01*
X636295Y1231862D01*
X635995D01*
G01X641391Y1238648D02*
X645741D01*
G01X637041Y1245341D02*
X641391D01*
G01D02*
X645741D01*
G01X647725Y1646119D02*
Y1643719D01*
G01X646225Y1705769D02*
Y1708169D01*
G01X642145Y1722362D02*
X639745D01*
G01X642145Y1718362D02*
X639745D01*
G01X648219Y149871D02*
X650790D01*
G01X648219Y154345D02*
Y149871D01*
G01Y140699D02*
X650790D01*
G01X650845Y528255D02*
X648296D01*
G01X650599Y770144D02*
X654949D01*
G01D02*
X659299D01*
G01Y783530D02*
X654949D01*
G01X659299Y776837D02*
X654949D01*
G01D02*
X650599D01*
G01X654949Y783530D02*
X650599D01*
G01Y800263D02*
X654949D01*
G01X659299Y793570D02*
X654949D01*
G01D02*
X650599D01*
G01X654949Y800263D02*
X659299D01*
G01X650599Y806955D02*
X654949D01*
G01X650599Y813648D02*
X654949D01*
G01Y806955D02*
X659299D01*
G01X654949Y813648D02*
X660432D01*
G01X650599Y830381D02*
X654949D01*
G01X650599Y820341D02*
X654949D01*
G01D02*
X660199D01*
G01X654949Y830381D02*
X659299D01*
G01X650599Y850459D02*
X654949D01*
G01X650599Y843766D02*
X654949D01*
G01X659299Y837074D02*
X654949D01*
G01D02*
X650599D01*
G01X654949Y843766D02*
X659299D01*
G01X654949Y850459D02*
X659299D01*
G01X650599Y857152D02*
X654949D01*
G01X660299Y867192D02*
X654949D01*
G01Y857152D02*
X659299D01*
G01X654949Y867192D02*
X649563D01*
G01X650599Y873885D02*
X654949D01*
G01X659299Y880577D02*
X654949D01*
G01Y873885D02*
X659299D01*
G01X654949Y880577D02*
X650599D01*
G01X659299Y893963D02*
X654949D01*
G01X659299Y887270D02*
X654949D01*
G01D02*
X650599D01*
G01X654949Y893963D02*
X650599D01*
G01Y917389D02*
X654949D01*
G01X650599Y910696D02*
X654949D01*
G01X659299Y904003D02*
X654949D01*
G01D02*
X650599D01*
G01X654949Y910696D02*
X659299D01*
G01X654949Y917389D02*
X659299D01*
G01X650599Y924081D02*
X654949D01*
G01X649661Y930774D02*
X654949D01*
G01Y924081D02*
X660504D01*
G01X654949Y930774D02*
X660174D01*
G01X650599Y947507D02*
X654949D01*
G01X650599Y940814D02*
X654949D01*
G01D02*
X659299D01*
G01X654949Y947507D02*
X659299D01*
G01X650599Y964239D02*
X654949D01*
G01X659299Y954200D02*
X654949D01*
G01D02*
X650599D01*
G01X654949Y964239D02*
X659299D01*
G01X650599Y977625D02*
X654949D01*
G01X650599Y970932D02*
X654949D01*
G01D02*
X659299D01*
G01X654949Y977625D02*
X659299D01*
G01X650599Y991011D02*
X654949D01*
G01X650599Y984318D02*
X654949D01*
G01D02*
X659299D01*
G01X654949Y991011D02*
X659299D01*
G01X815789Y1008845D02*
X660647D01*
X652577Y1000775D01*
G01X650599Y1031168D02*
X654949D01*
G01X650599Y1017782D02*
X654949D01*
G01X650599Y1024475D02*
X654949D01*
G01Y1017782D02*
X659299D01*
G01X654949Y1024475D02*
X659299D01*
G01X654949Y1031168D02*
X659299D01*
G01X650599Y1044554D02*
X654949D01*
G01X650599Y1037861D02*
X654949D01*
G01D02*
X659299D01*
G01X654949Y1044554D02*
X659299D01*
G01X650599Y1051247D02*
X654949D01*
G01X659299Y1057940D02*
X654949D01*
G01Y1051247D02*
X659299D01*
G01X654949Y1057940D02*
X650599D01*
G01X649799Y1078018D02*
X654949D01*
G01X650599Y1071326D02*
X654949D01*
G01X650599Y1064633D02*
X654949D01*
G01D02*
X659299D01*
G01X654949Y1071326D02*
X659299D01*
G01X654949Y1078018D02*
X660099D01*
G01X650599Y1094751D02*
X654949D01*
G01X649799Y1088058D02*
X654949D01*
G01D02*
X660099D01*
G01X654949Y1094751D02*
X659299D01*
G01Y1108137D02*
X654949D01*
G01X659299Y1101444D02*
X654949D01*
G01D02*
X650599D01*
G01X654949Y1108137D02*
X650599D01*
G01X660199Y1124869D02*
X654949D01*
G01X650599Y1114829D02*
X654949D01*
G01D02*
X659299D01*
G01X654949Y1124869D02*
X650161D01*
X649932Y1124640D01*
G01X650599Y1138255D02*
X654949D01*
G01X650599Y1144948D02*
X654949D01*
G01X659299Y1130762D02*
X658499Y1131562D01*
X654949D01*
G01D02*
X651399D01*
X650599Y1130762D01*
G01X654949Y1138255D02*
X659299D01*
G01X654949Y1144948D02*
X659299D01*
G01X650599Y1151641D02*
X654949D01*
G01D02*
X659299D01*
G01Y1175066D02*
X654949D01*
G01X659299Y1168373D02*
X654949D01*
G01X659299Y1161680D02*
X654949D01*
G01D02*
X650599D01*
G01X654949Y1168373D02*
X650599D01*
G01X654949Y1175066D02*
X650599D01*
G01X659299Y1188452D02*
X654949D01*
G01X659299Y1181759D02*
X654949D01*
G01D02*
X650599D01*
G01X654949Y1188452D02*
X650599D01*
G01X659299Y1205184D02*
X654949D01*
G01X659299Y1198491D02*
X654949D01*
G01D02*
X650599D01*
G01X654949Y1205184D02*
X650599D01*
G01X649913Y1225263D02*
X654949D01*
G01X650599Y1218570D02*
X654949D01*
G01X650599Y1211877D02*
X654949D01*
G01D02*
X659299D01*
G01X654949Y1218570D02*
X659299D01*
G01X654949Y1225263D02*
X660070D01*
G01X650599Y1241995D02*
X654949D01*
G01X649701Y1235302D02*
X654949D01*
G01D02*
X660234D01*
G01X654949Y1241995D02*
X659299D01*
G01Y1248688D02*
X654949D01*
G01D02*
X650599D01*
G01Y1258727D02*
X654949D01*
G01X653690Y1392362D02*
X654098Y1392770D01*
X656161D01*
G01Y1396300D02*
X653761D01*
G01X665443Y1647557D02*
X663043D01*
G01X665497Y1642667D02*
X663097D01*
G01X665518Y1659557D02*
X663118D01*
G01X654225Y1660769D02*
X651556D01*
X649064Y1663261D01*
Y1665405D01*
G01X656725Y1660769D02*
X654225D01*
G01X665518Y1655557D02*
X663118D01*
G01X665443Y1651557D02*
X663043D01*
G01X665545Y1672862D02*
X663145D01*
G01X665545Y1668862D02*
X663145D01*
G01X663645Y1722862D02*
Y1720362D01*
G01D02*
X658960D01*
G01X667610Y113487D02*
X674145D01*
G01X676203Y432187D02*
X674628Y430612D01*
G01X676203Y447935D02*
X674628Y449510D01*
G01X676203Y460533D02*
X674628Y462108D01*
G01X666741Y766798D02*
X671091D01*
G01D02*
X675441D01*
G01X666741Y773491D02*
X671091D01*
G01X675441Y780184D02*
X671091D01*
G01Y773491D02*
X675441D01*
G01X671091Y780184D02*
X666741D01*
G01Y803609D02*
X671091D01*
G01X675441Y796916D02*
X671091D01*
G01X675441Y790223D02*
X671091D01*
G01D02*
X666741D01*
G01X671091Y796916D02*
X666741D01*
G01X671091Y803609D02*
X675441D01*
G01X665803Y816995D02*
X671091D01*
G01X666741Y810302D02*
X671091D01*
G01D02*
X675441D01*
G01X671091Y816995D02*
X676403D01*
G01X666741Y833727D02*
X671091D01*
G01X665876Y827034D02*
X671091D01*
G01D02*
X676625D01*
G01X671091Y833727D02*
X675441D01*
G01X666741Y847113D02*
X671091D01*
G01X675441Y840420D02*
X671091D01*
G01D02*
X666741D01*
G01X671091Y847113D02*
X675441D01*
G01X665890Y853806D02*
X671091D01*
G01X676600Y863845D02*
X671091D01*
G01Y853806D02*
X676417D01*
G01X671091Y863845D02*
X665916D01*
G01X666741Y877231D02*
X671091D01*
G01X666741Y870538D02*
X671091D01*
G01X675441Y883924D02*
X671091D01*
G01Y870538D02*
X675441D01*
G01X671091Y877231D02*
X675441D01*
G01X671091Y883924D02*
X666741D01*
G01X675441Y900656D02*
X671091D01*
G01X675441Y890617D02*
X671091D01*
G01D02*
X666741D01*
G01X671091Y900656D02*
X666741D01*
G01Y914042D02*
X671091D01*
G01X675441Y907349D02*
X671091D01*
G01D02*
X666741D01*
G01X671091Y914042D02*
X675441D01*
G01X665896Y927428D02*
X671091D01*
G01X666741Y920735D02*
X671091D01*
G01D02*
X675441D01*
G01X671091Y927428D02*
X676488D01*
G01X666741Y944160D02*
X671091D01*
G01X665923Y937467D02*
X671091D01*
G01D02*
X676359D01*
G01X671091Y944160D02*
X675441D01*
G01X666741Y960892D02*
X671091D01*
G01X675441Y950853D02*
X671091D01*
G01D02*
X666741D01*
G01X671091Y960892D02*
X675441D01*
G01X666741Y980971D02*
X671091D01*
G01X666741Y974278D02*
X671091D01*
G01X666741Y967585D02*
X671091D01*
G01D02*
X675441D01*
G01X671091Y974278D02*
X675441D01*
G01X671091Y980971D02*
X675441D01*
G01X666741Y987664D02*
X671091D01*
G01D02*
X675441D01*
G01X666741Y1027822D02*
X671091D01*
G01X666741Y1017782D02*
X671091D01*
G01D02*
X675441D01*
G01X671091Y1027822D02*
X675441D01*
G01X666741Y1041207D02*
X671091D01*
G01X666741Y1034515D02*
X671091D01*
G01D02*
X675441D01*
G01X671091Y1041207D02*
X675441D01*
G01X666741Y1054593D02*
X671091D01*
G01X675441Y1061286D02*
X671091D01*
G01X666741Y1047900D02*
X671091D01*
G01D02*
X675441D01*
G01X671091Y1054593D02*
X675441D01*
G01X671091Y1061286D02*
X666741D01*
G01X665841Y1074672D02*
X671091D01*
G01X666741Y1067979D02*
X671091D01*
G01D02*
X675441D01*
G01X671091Y1074672D02*
X676341D01*
G01X666741Y1091404D02*
X671091D01*
G01X665941Y1084711D02*
X671091D01*
G01D02*
X676241D01*
G01X671091Y1091404D02*
X675441D01*
G01Y1111483D02*
X671091D01*
G01X675441Y1104790D02*
X671091D01*
G01X675441Y1098097D02*
X671091D01*
G01D02*
X666741D01*
G01X671091Y1104790D02*
X666741D01*
G01X671091Y1111483D02*
X666741D01*
G01X675441Y1128215D02*
X671091D01*
G01X675441Y1121522D02*
X671091D01*
G01D02*
X666741D01*
G01X671091Y1128215D02*
X666741D01*
G01X675441Y1141601D02*
X671091D01*
G01X675441Y1134908D02*
X671091D01*
G01D02*
X666741D01*
G01X671091Y1141601D02*
X666741D01*
G01X665602Y1148294D02*
X671091D01*
G01X665941Y1158333D02*
X671091D01*
G01Y1148294D02*
X676652D01*
G01X671091Y1158333D02*
X676241D01*
G01X666741Y1165026D02*
X671091D01*
G01X675441Y1171719D02*
X671091D01*
G01Y1165026D02*
X675441D01*
G01X671091Y1171719D02*
X666741D01*
G01X675441Y1185105D02*
X671091D01*
G01X675441Y1178412D02*
X671091D01*
G01D02*
X666741D01*
G01X671091Y1185105D02*
X666741D01*
G01X675441Y1208530D02*
X671091D01*
G01X675441Y1201837D02*
X671091D01*
G01X675441Y1195144D02*
X671091D01*
G01D02*
X666741D01*
G01X671091Y1201837D02*
X666741D01*
G01X671091Y1208530D02*
X666741D01*
G01X665651Y1221916D02*
X671091D01*
G01X666741Y1215223D02*
X671091D01*
G01D02*
X675441D01*
G01X671091Y1221916D02*
X676448D01*
G01X666741Y1238648D02*
X671091D01*
G01X665912Y1231955D02*
X671091D01*
G01D02*
X676462D01*
G01X671091Y1238648D02*
X675441D01*
G01X666741Y1245341D02*
X671091D01*
G01D02*
X675441D01*
G01X671795Y1712362D02*
X674195D01*
G01X671795Y1728362D02*
X674195D01*
G01X680600Y366687D02*
Y364282D01*
G01X685600Y366687D02*
Y364282D01*
G01X690600Y366687D02*
Y364282D01*
G01X695600Y366687D02*
Y364282D01*
G01X685652Y419588D02*
X684077Y418013D01*
G01X698251Y441636D02*
X696676Y440061D01*
G01X698251Y444785D02*
X696676Y443210D01*
G01X691951Y438486D02*
X690376Y436911D01*
G01X691951Y444785D02*
X690376Y443210D01*
G01X688802Y441636D02*
X687227Y440061D01*
G01X695101Y435336D02*
X693526Y433761D01*
G01X698251Y435336D02*
X696676Y433761D01*
G01X698251Y447935D02*
X696676Y449510D01*
G01X698251Y451084D02*
X696676Y452659D01*
G01X691951Y447935D02*
X690376Y449510D01*
G01X691951Y454234D02*
X690376Y455809D01*
G01X688802Y451084D02*
X687227Y452659D01*
G01X695101Y457384D02*
X693526Y458959D01*
G01X698251Y457384D02*
X696676Y458959D01*
G01X685652Y473132D02*
X684077Y474707D01*
G01X685220Y514437D02*
Y516852D01*
G01X700791Y766798D02*
X696441D01*
G01X688999Y770144D02*
X684649D01*
G01D02*
X680299D01*
G01X700791Y773491D02*
X696441D01*
G01X700791Y780184D02*
X696441D01*
G01X684649Y776837D02*
X680299D01*
G01X688999D02*
X684649D01*
G01Y783530D02*
X680299D01*
G01X688999D02*
X684649D01*
G01X700791Y803609D02*
X696441D01*
G01X700791Y796916D02*
X696441D01*
G01X700791Y790223D02*
X696441D01*
G01X684649Y793570D02*
X680299D01*
G01X688999D02*
X684649D01*
G01Y800263D02*
X680299D01*
G01X688999D02*
X684649D01*
G01X700791Y816995D02*
X696441D01*
G01X700791Y810302D02*
X696441D01*
G01X684649Y806955D02*
X680299D01*
G01X688999D02*
X684649D01*
G01Y813648D02*
X680299D01*
G01X688999D02*
X684649D01*
G01X696441Y833727D02*
X700791D01*
G01X696441Y827034D02*
X700791D01*
G01X684649Y820341D02*
X689888D01*
G01X680299D02*
X684649D01*
G01Y830381D02*
X680299D01*
G01X688999D02*
X684649D01*
G01X700791Y847113D02*
X696441D01*
G01X700791Y840420D02*
X696441D01*
G01X684649Y837074D02*
X680299D01*
G01X688999D02*
X684649D01*
G01Y843766D02*
X680299D01*
G01X688999D02*
X684649D01*
G01Y850459D02*
X680299D01*
G01X688999D02*
X684649D01*
G01X700791Y863845D02*
X696441D01*
G01X700791Y853806D02*
X696441D01*
G01X684649Y857152D02*
X689896D01*
G01X680299D02*
X684649D01*
G01Y867192D02*
X680299D01*
G01X688999D02*
X684649D01*
G01X700791Y883924D02*
X696441D01*
G01X700791Y877231D02*
X696441D01*
G01X700791Y870538D02*
X696441D01*
G01X684649Y873885D02*
X680299D01*
G01X688999D02*
X684649D01*
G01Y880577D02*
X680299D01*
G01X688999D02*
X684649D01*
G01X700791Y900656D02*
X696441D01*
G01X700791Y890617D02*
X696441D01*
G01X684649Y887270D02*
X680299D01*
G01X688999D02*
X684649D01*
G01Y893963D02*
X680299D01*
G01X688999D02*
X684649D01*
G01X700791Y914042D02*
X696441D01*
G01Y907349D02*
X700791D01*
G01X684649Y904003D02*
X680299D01*
G01X688999D02*
X684649D01*
G01Y910696D02*
X680299D01*
G01X688999D02*
X684649D01*
G01Y917389D02*
X680299D01*
G01X688999D02*
X684649D01*
G01X700791Y927428D02*
X696441D01*
G01X700791Y920735D02*
X696441D01*
G01X684649Y930774D02*
X690104D01*
G01X680299D02*
X684649D01*
G01Y924081D02*
X680299D01*
G01X688999D02*
X684649D01*
G01X696441Y944160D02*
X700791D01*
G01Y937467D02*
X696441D01*
G01X684649Y940814D02*
X680299D01*
G01X688999D02*
X684649D01*
G01Y947507D02*
X680299D01*
G01X688999D02*
X684649D01*
G01X700791Y960892D02*
X696441D01*
G01X700791Y950853D02*
X696441D01*
G01X684649Y954200D02*
X680299D01*
G01X688999D02*
X684649D01*
G01X688999Y964239D02*
X684649D01*
G01D02*
X680299D01*
G01X700791Y980971D02*
X696441D01*
G01X700791Y974278D02*
X696441D01*
G01X700791Y967585D02*
X696441D01*
G01X680299Y970932D02*
X684649D01*
G01D02*
X688999D01*
G01X684649Y977625D02*
X688999D01*
G01X680299D02*
X684649D01*
G01X700791Y987664D02*
X696441D01*
G01X684649Y984318D02*
X688999D01*
G01X680299D02*
X684649D01*
G01Y991011D02*
X680299D01*
G01X688999D02*
X684649D01*
G01X700791Y1027822D02*
X696441D01*
G01X700791Y1017782D02*
X696441D01*
G01X688999D02*
X684649D01*
G01D02*
X680299D01*
G01X688999Y1024475D02*
X684649D01*
G01D02*
X680299D01*
G01X688999Y1031168D02*
X684649D01*
G01D02*
X680299D01*
G01X700791Y1041207D02*
X696441D01*
G01X700791Y1034515D02*
X696441D01*
G01X684649Y1044554D02*
X680299D01*
G01X688999D02*
X684649D01*
G01X688999Y1037861D02*
X684649D01*
G01D02*
X680299D01*
G01X700791Y1054593D02*
X696441D01*
G01X700791Y1061286D02*
X696441D01*
G01X680299Y1051247D02*
X684649D01*
G01D02*
X688999D01*
G01Y1057940D02*
X684649D01*
G01D02*
X680299D01*
G01X700791Y1047900D02*
X696441D01*
G01Y1074672D02*
X700791D01*
G01Y1067979D02*
X696441D01*
G01X680299Y1078018D02*
X684649D01*
G01X688999Y1077118D02*
X688099Y1078018D01*
X684649D01*
G01Y1064633D02*
X680299D01*
G01X688999D02*
X684649D01*
G01Y1071326D02*
X680299D01*
G01X688999D02*
X684649D01*
G01X696441Y1091404D02*
X700791D01*
G01X696441Y1084711D02*
X700791D01*
G01X684649Y1094751D02*
X688999D01*
G01X680299D02*
X684649D01*
G01Y1088058D02*
X688999D01*
G01X680299D02*
X684649D01*
G01X696441Y1111483D02*
X700791D01*
G01X696441Y1104790D02*
X700791D01*
G01X696441Y1098097D02*
X700791D01*
G01X684649Y1108137D02*
X688999D01*
G01X680299D02*
X684649D01*
G01Y1101444D02*
X688999D01*
G01X680299D02*
X684649D01*
G01X696441Y1128215D02*
X700791D01*
G01X696441Y1121522D02*
X700791D01*
G01X684649Y1124869D02*
X688999D01*
G01X680299D02*
X684649D01*
G01Y1114829D02*
X688999D01*
G01X680299D02*
X684649D01*
G01X696441Y1141601D02*
X700791D01*
G01X696441Y1134908D02*
X700791D01*
G01X684649Y1144948D02*
X688999D01*
G01X680299D02*
X684649D01*
G01Y1138255D02*
X688999D01*
G01X680299D02*
X684649D01*
G01Y1131562D02*
X688999D01*
G01X680299D02*
X684649D01*
G01X696441Y1158333D02*
X700791D01*
G01X696441Y1148294D02*
X700791D01*
G01X684649Y1151641D02*
X689999D01*
G01X680299D02*
X684649D01*
G01X700791Y1171719D02*
X696441D01*
G01Y1165026D02*
X700791D01*
G01X684649Y1175066D02*
X688999D01*
G01X680299D02*
X684649D01*
G01Y1168373D02*
X688999D01*
G01X680299D02*
X684649D01*
G01Y1161680D02*
X688999D01*
G01X680299D02*
X684649D01*
G01X696441Y1185105D02*
X700791D01*
G01X696441Y1178412D02*
X700791D01*
G01X684649Y1188452D02*
X688999D01*
G01X680299D02*
X684649D01*
G01Y1181759D02*
X688999D01*
G01X680299D02*
X684649D01*
G01X696441Y1208530D02*
X700791D01*
G01X696441Y1201837D02*
X700791D01*
G01X696441Y1195144D02*
X700791D01*
G01X684649Y1205184D02*
X688999D01*
G01X680299D02*
X684649D01*
G01Y1198491D02*
X688999D01*
G01X680299D02*
X684649D01*
G01X696441Y1221916D02*
X700791D01*
G01X696441Y1215223D02*
X700791D01*
G01X680299Y1218570D02*
X684649D01*
G01D02*
X688999D01*
G01X680299Y1225263D02*
X684649D01*
G01D02*
X689799D01*
G01X684649Y1211877D02*
X688999D01*
G01X680299D02*
X684649D01*
G01X696441Y1238648D02*
X700791D01*
G01X696441Y1231955D02*
X700791D01*
G01X684649Y1235302D02*
X688999D01*
G01X680299D02*
X684649D01*
G01Y1241995D02*
X680299D01*
G01X688999D02*
X684649D01*
G01X696441Y1245341D02*
X700791D01*
G01X684649Y1248688D02*
X688999D01*
G01X680299D02*
X684649D01*
G01X680299Y1258727D02*
X684649D01*
G01X694722Y1632667D02*
X697122D01*
G01X694797Y1644667D02*
X697197D01*
G01X694797Y1640667D02*
X697197D01*
G01X694722Y1636667D02*
X697122D01*
G01X689200Y1648843D02*
X691657D01*
G01X695195Y1662862D02*
X697595D01*
G01X687045Y1670862D02*
X682360D01*
G01X687045Y1673362D02*
Y1670862D01*
G01X697730Y1677460D02*
X697580D01*
X696178Y1678862D01*
X695195D01*
G01X712500Y79862D02*
X712000Y80362D01*
X704925D01*
X704000Y79437D01*
G01X700600Y366687D02*
Y364282D01*
G01X705600Y366687D02*
Y364282D01*
G01X710600Y366687D02*
Y364282D01*
G01X715600Y366687D02*
X710600D01*
G01X704550Y419588D02*
X706125Y418013D01*
G01X707699Y441636D02*
X709274Y440061D01*
G01X707699Y444785D02*
X709274Y443210D01*
G01X704550Y444785D02*
X706125Y443210D01*
G01X701400Y444785D02*
X699825Y443210D01*
G01X707699Y435336D02*
X709274Y433761D01*
G01X710849Y435336D02*
X712424Y433761D01*
G01X701400Y435336D02*
X699825Y433761D01*
G01X704550Y435336D02*
X706125Y433761D01*
G01X707699Y447935D02*
X709274Y449510D01*
G01X701400Y447935D02*
X699825Y449510D01*
G01X704550Y447935D02*
X706125Y449510D01*
G01X707699Y451084D02*
X709274Y452659D01*
G01X701400Y457384D02*
X699825Y458959D01*
G01X704550Y457384D02*
X706125Y458959D01*
G01X707699Y457384D02*
X709274Y458959D01*
G01X710849Y457384D02*
X712424Y458959D01*
G01X704550Y466832D02*
X706125Y468407D01*
G01X711220Y501437D02*
Y503842D01*
G01X705220Y501437D02*
Y503842D01*
G01X894897Y871745D02*
Y857459D01*
X878500Y841062D01*
Y770762D01*
X862100Y754362D01*
Y749362D01*
X859000Y746262D01*
X852200D01*
X845400Y739462D01*
X834500D01*
X831100Y736062D01*
X806400D01*
X800400Y730062D01*
X764500D01*
X761500Y733062D01*
X714100D01*
X706300Y740862D01*
X704000D01*
G01X709999Y770144D02*
X714349D01*
G01X705141Y766798D02*
X700791D01*
G01X709999Y783530D02*
X714349D01*
G01X709999Y776837D02*
X714349D01*
G01X705141Y773491D02*
X700791D01*
G01X705141Y780184D02*
X700791D01*
G01X709999Y800263D02*
X714349D01*
G01X709999Y793570D02*
X714349D01*
G01X705141Y803609D02*
X700791D01*
G01X705141Y796916D02*
X700791D01*
G01X705141Y790223D02*
X700791D01*
G01X709999Y813648D02*
X714349D01*
G01X709999Y806955D02*
X714349D01*
G01X705141Y816995D02*
X700791D01*
G01X705141Y810302D02*
X700791D01*
G01X709999Y830381D02*
X714349D01*
G01X709999Y820341D02*
X714349D01*
G01X700791Y833727D02*
X705141D01*
G01X700791Y827034D02*
X705141D01*
G01X709999Y850459D02*
X714349D01*
G01X709999Y843766D02*
X714349D01*
G01X709999Y837074D02*
X714349D01*
G01X705141Y847113D02*
X700791D01*
G01X705141Y840420D02*
X700791D01*
G01X709999Y867192D02*
X714349D01*
G01Y857152D02*
X709999D01*
G01X705141Y863845D02*
X700791D01*
G01X705141Y853806D02*
X700791D01*
G01X709999Y880577D02*
X714349D01*
G01X709999Y873885D02*
X714349D01*
G01X705141Y883924D02*
X700791D01*
G01X705141Y877231D02*
X700791D01*
G01X705141Y870538D02*
X700791D01*
G01X709999Y893963D02*
X714349D01*
G01X709999Y887270D02*
X714349D01*
G01X705141Y900656D02*
X700791D01*
G01X705141Y890617D02*
X700791D01*
G01X709999Y917389D02*
X714349D01*
G01X709999Y910696D02*
X714349D01*
G01X709999Y904003D02*
X714349D01*
G01X705141Y914042D02*
X700791D01*
G01Y907349D02*
X705141D01*
G01X709999Y930774D02*
X714349D01*
G01X709999Y924081D02*
X714349D01*
G01X705141Y927428D02*
X700791D01*
G01X705141Y920735D02*
X700791D01*
G01X709999Y947507D02*
X714349D01*
G01X709999Y940814D02*
X714349D01*
G01X700791Y944160D02*
X705141D01*
G01Y937467D02*
X700791D01*
G01X709999Y964239D02*
X714349D01*
G01X709999Y954200D02*
X714349D01*
G01X705141Y960892D02*
X700791D01*
G01X705141Y950853D02*
X700791D01*
G01X709999Y977625D02*
X714349D01*
G01X709999Y970932D02*
X714349D01*
G01X705141Y980971D02*
X700791D01*
G01X705141Y974278D02*
X700791D01*
G01X705141Y967585D02*
X700791D01*
G01X709999Y991011D02*
X714349D01*
G01X709999Y984318D02*
X714349D01*
G01X705141Y987664D02*
X700791D01*
G01X709999Y1031168D02*
X714349D01*
G01X709999Y1024475D02*
X714349D01*
G01X709999Y1017782D02*
X714349D01*
G01X705141Y1027822D02*
X700791D01*
G01X705141Y1017782D02*
X700791D01*
G01X709999Y1044554D02*
X714349D01*
G01X709999Y1037861D02*
X714349D01*
G01X705141Y1041207D02*
X700791D01*
G01X705141Y1034515D02*
X700791D01*
G01X709999Y1057940D02*
X714349D01*
G01X709999Y1051247D02*
X714349D01*
G01X705141Y1054593D02*
X700791D01*
G01X705141Y1061286D02*
X700791D01*
G01X705141Y1047900D02*
X700791D01*
G01X714349Y1078018D02*
X709999D01*
G01X714349Y1071326D02*
X709999D01*
G01Y1064633D02*
X714349D01*
G01X700791Y1074672D02*
X705141D01*
G01Y1067979D02*
X700791D01*
G01X709999Y1094751D02*
X714349D01*
G01X709999Y1088058D02*
X714349D01*
G01X700791Y1091404D02*
X705141D01*
G01X700791Y1084711D02*
X705141D01*
G01X714349Y1108137D02*
X709999D01*
G01Y1101444D02*
X714349D01*
G01X700791Y1111483D02*
X705141D01*
G01X700791Y1104790D02*
X705141D01*
G01X700791Y1098097D02*
X705141D01*
G01X714349Y1124869D02*
X709999D01*
G01X714349Y1114829D02*
X709999D01*
G01X700791Y1128215D02*
X705141D01*
G01X700791Y1121522D02*
X705141D01*
G01X714349Y1144948D02*
X709999D01*
G01X714349Y1138255D02*
X709999D01*
G01X714349Y1131562D02*
X709999D01*
G01X700791Y1141601D02*
X705141D01*
G01X700791Y1134908D02*
X705141D01*
G01X714349Y1151641D02*
X709999D01*
G01X700791Y1158333D02*
X705141D01*
G01X700791Y1148294D02*
X705141D01*
G01X714349Y1175066D02*
X709999D01*
G01X714349Y1168373D02*
X709999D01*
G01X705141Y1171719D02*
X700791D01*
G01Y1165026D02*
X705141D01*
G01X714349Y1161680D02*
X709999D01*
G01X714349Y1188452D02*
X709999D01*
G01X714349Y1181759D02*
X709999D01*
G01X700791Y1185105D02*
X705141D01*
G01X700791Y1178412D02*
X705141D01*
G01X714349Y1205184D02*
X709999D01*
G01X714349Y1198491D02*
X709999D01*
G01X700791Y1208530D02*
X705141D01*
G01X700791Y1201837D02*
X705141D01*
G01X700791Y1195144D02*
X705141D01*
G01X714349Y1225263D02*
X709999D01*
G01Y1218570D02*
X714349D01*
G01Y1211877D02*
X709999D01*
G01X700791Y1221916D02*
X705141D01*
G01X700791Y1215223D02*
X705141D01*
G01X714349Y1241995D02*
X709999D01*
G01X714349Y1235302D02*
X709999D01*
G01X700791Y1238648D02*
X705141D01*
G01X700791Y1231955D02*
X705141D01*
G01X714349Y1248688D02*
X709999D01*
G01X700791Y1245341D02*
X705141D01*
G01X709999Y1258727D02*
X714349D01*
G01X714455Y1411554D02*
X713814D01*
X713170Y1412198D01*
X711895D01*
G01X704497Y1601963D02*
Y1598927D01*
G01X711780Y1617355D02*
Y1614590D01*
G01X711719Y1642926D02*
X711749Y1642956D01*
Y1648821D01*
X711558Y1649012D01*
Y1651562D01*
G01X714203Y1642926D02*
X711719D01*
G01X713295Y157362D02*
X715940D01*
G01X717020Y220862D02*
X716020Y221862D01*
X713295D01*
G01X713220Y380787D02*
Y378362D01*
G01X723447Y419588D02*
X725022Y418013D01*
G01X713999Y438486D02*
X715574Y436911D01*
G01X713999Y441636D02*
X715574Y440061D01*
G01X713999Y444785D02*
X715574Y443210D01*
G01X726597Y444785D02*
X728172Y443210D01*
G01X726597Y432187D02*
X728172Y430612D01*
G01X713999Y447935D02*
X715574Y449510D01*
G01X713999Y451084D02*
X715574Y452659D01*
G01X713999Y454234D02*
X715574Y455809D01*
G01X726597Y460533D02*
X728172Y462108D01*
G01X723447Y473132D02*
X725022Y474707D01*
G01X723220Y501437D02*
Y503842D01*
G01X717220Y501437D02*
Y503842D01*
G01X723220Y514437D02*
Y516852D01*
G01X717220Y514437D02*
Y516852D01*
G01X726141Y766798D02*
X730491D01*
G01X714349Y770144D02*
X718699D01*
G01X726141Y773491D02*
X730491D01*
G01X726141Y780184D02*
X730491D01*
G01X714349Y783530D02*
X718699D01*
G01X714349Y776837D02*
X718699D01*
G01X730491Y803609D02*
X726141D01*
G01Y796916D02*
X730491D01*
G01X726141Y790223D02*
X730491D01*
G01X714349Y800263D02*
X718699D01*
G01X714349Y793570D02*
X718699D01*
G01X730491Y816995D02*
X726141D01*
G01X730491Y810302D02*
X726141D01*
G01X714349Y813648D02*
X718699D01*
G01X714349Y806955D02*
X718699D01*
G01X726141Y833727D02*
X730491D01*
G01X726141Y827034D02*
X730491D01*
G01X714349Y830381D02*
X718699D01*
G01X714349Y820341D02*
X718699D01*
G01X726141Y847113D02*
X730491D01*
G01X726141Y840420D02*
X730491D01*
G01X714349Y850459D02*
X718699D01*
G01X714349Y843766D02*
X718699D01*
G01X714349Y837074D02*
X718699D01*
G01X726141Y863845D02*
X730491D01*
G01X726141Y853806D02*
X730491D01*
G01X714349Y867192D02*
X718699D01*
G01Y857152D02*
X714349D01*
G01X726141Y883924D02*
X730491D01*
G01X726141Y877231D02*
X730491D01*
G01X726141Y870538D02*
X730491D01*
G01X714349Y880577D02*
X718699D01*
G01X714349Y873885D02*
X718699D01*
G01X726141Y900656D02*
X730491D01*
G01Y890617D02*
X726141D01*
G01X714349Y893963D02*
X718699D01*
G01X714349Y887270D02*
X718699D01*
G01X730491Y914042D02*
X726141D01*
G01Y907349D02*
X730491D01*
G01X714349Y917389D02*
X718699D01*
G01X714349Y910696D02*
X718699D01*
G01X714349Y904003D02*
X718699D01*
G01X726141Y927428D02*
X730491D01*
G01X726141Y920735D02*
X730491D01*
G01X714349Y930774D02*
X718699D01*
G01X714349Y924081D02*
X718699D01*
G01X726141Y944160D02*
X730491D01*
G01X726141Y937467D02*
X730491D01*
G01X714349Y947507D02*
X718699D01*
G01X714349Y940814D02*
X718699D01*
G01X726141Y960892D02*
X730491D01*
G01X726141Y950853D02*
X730491D01*
G01X714349Y964239D02*
X718699D01*
G01X714349Y954200D02*
X718699D01*
G01X726141Y980971D02*
X730491D01*
G01X726141Y974278D02*
X730491D01*
G01X726141Y967585D02*
X730491D01*
G01X714349Y977625D02*
X718699D01*
G01X714349Y970932D02*
X718699D01*
G01X730491Y987664D02*
X726141D01*
G01X714349Y991011D02*
X718699D01*
G01X714349Y984318D02*
X718699D01*
G01X730491Y1027822D02*
X726141D01*
G01Y1017782D02*
X730491D01*
G01X714349Y1031168D02*
X718699D01*
G01X714349Y1024475D02*
X718699D01*
G01X714349Y1017782D02*
X718699D01*
G01X726141Y1041207D02*
X730491D01*
G01X726141Y1034515D02*
X730491D01*
G01X714349Y1044554D02*
X718699D01*
G01X714349Y1037861D02*
X718699D01*
G01X726141Y1061286D02*
X730491D01*
G01X726141Y1054593D02*
X730491D01*
G01X726141Y1047900D02*
X730491D01*
G01X714349Y1057940D02*
X718699D01*
G01X714349Y1051247D02*
X718699D01*
G01X730491Y1074672D02*
X726141D01*
G01Y1067979D02*
X730491D01*
G01X718699Y1078018D02*
X714349D01*
G01X718699Y1071326D02*
X714349D01*
G01Y1064633D02*
X718699D01*
G01X730491Y1091404D02*
X726141D01*
G01X730491Y1084711D02*
X726141D01*
G01X714349Y1094751D02*
X718699D01*
G01X714349Y1088058D02*
X718699D01*
G01X726141Y1111483D02*
X730491D01*
G01X726141Y1104790D02*
X730491D01*
G01Y1098097D02*
X726141D01*
G01X718699Y1108137D02*
X714349D01*
G01Y1101444D02*
X718699D01*
G01X730491Y1128215D02*
X726141D01*
G01X730491Y1121522D02*
X726141D01*
G01X718699Y1124869D02*
X714349D01*
G01X718699Y1114829D02*
X714349D01*
G01X730491Y1141601D02*
X726141D01*
G01X730491Y1134908D02*
X726141D01*
G01X718699Y1144948D02*
X714349D01*
G01X718699Y1138255D02*
X714349D01*
G01X718699Y1131562D02*
X714349D01*
G01X730491Y1158333D02*
X726141D01*
G01X730491Y1148294D02*
X726141D01*
G01X718699Y1151641D02*
X714349D01*
G01X726141Y1171719D02*
X730491D01*
G01Y1165026D02*
X726141D01*
G01X718699Y1175066D02*
X714349D01*
G01X718699Y1168373D02*
X714349D01*
G01X718699Y1161680D02*
X714349D01*
G01X726141Y1185105D02*
X730491D01*
G01X726141Y1178412D02*
X730491D01*
G01X718699Y1188452D02*
X714349D01*
G01X718699Y1181759D02*
X714349D01*
G01X730491Y1208530D02*
X726141D01*
G01X730491Y1201837D02*
X726141D01*
G01X730491Y1195144D02*
X726141D01*
G01X718699Y1205184D02*
X714349D01*
G01X718699Y1198491D02*
X714349D01*
G01X730491Y1221916D02*
X726141D01*
G01X730491Y1215223D02*
X726141D01*
G01X718699Y1225263D02*
X714349D01*
G01Y1218570D02*
X718699D01*
G01Y1211877D02*
X714349D01*
G01X730491Y1238648D02*
X726141D01*
G01X730491Y1231955D02*
X726141D01*
G01X718699Y1241995D02*
X714349D01*
G01X718699Y1235302D02*
X714349D01*
G01X730491Y1245341D02*
X726141D01*
G01X718699Y1248688D02*
X714349D01*
G01X721488Y1610945D02*
X719612Y1609069D01*
Y1605758D01*
G01X718530Y1638245D02*
Y1644215D01*
X718195Y1644550D01*
G01D02*
Y1647300D01*
G01X730680Y1644365D02*
Y1643220D01*
X729150Y1641690D01*
G01X721908Y1680400D02*
X724500D01*
G01X729220Y501437D02*
Y503842D01*
G01X745220Y516852D02*
Y514437D01*
G01D02*
X735220D01*
G01X729220D02*
Y516852D01*
G01X748399Y770144D02*
X744049D01*
G01D02*
X739699D01*
G01X730491Y766798D02*
X734841D01*
G01X748399Y783530D02*
X744049D01*
G01D02*
X739699D01*
G01X748399Y776837D02*
X744049D01*
G01D02*
X739699D01*
G01X730491Y773491D02*
X734841D01*
G01X730491Y780184D02*
X734841D01*
G01X748399Y800263D02*
X744049D01*
G01D02*
X739699D01*
G01X748399Y793570D02*
X744049D01*
G01D02*
X739699D01*
G01X734841Y803609D02*
X730491D01*
G01Y796916D02*
X734841D01*
G01X730491Y790223D02*
X734841D01*
G01X748399Y813648D02*
X744049D01*
G01D02*
X739699D01*
G01X748399Y806955D02*
X744049D01*
G01D02*
X739699D01*
G01X734841Y816995D02*
X730491D01*
G01X734841Y810302D02*
X730491D01*
G01X748399Y830381D02*
X744049D01*
G01D02*
X739699D01*
G01X730491Y833727D02*
X734841D01*
G01X730491Y827034D02*
X734841D01*
G01X748399Y820341D02*
X744049D01*
G01D02*
X739699D01*
G01X748399Y850459D02*
X744049D01*
G01D02*
X739699D01*
G01X748399Y843766D02*
X744049D01*
G01D02*
X739699D01*
G01X748399Y837074D02*
X744049D01*
G01D02*
X739699D01*
G01X730491Y847113D02*
X734841D01*
G01X730491Y840420D02*
X734841D01*
G01X748399Y867192D02*
X744049D01*
G01D02*
X739699D01*
G01X748399Y857152D02*
X744049D01*
G01D02*
X739699D01*
G01X730491Y863845D02*
X734841D01*
G01X730491Y853806D02*
X734841D01*
G01X748399Y880577D02*
X744049D01*
G01D02*
X739699D01*
G01X748399Y873885D02*
X744049D01*
G01D02*
X739699D01*
G01X730491Y883924D02*
X734841D01*
G01X730491Y877231D02*
X734841D01*
G01X730491Y870538D02*
X734841D01*
G01X739699Y893963D02*
X744049D01*
G01D02*
X748399D01*
G01X739699Y887270D02*
X744049D01*
G01D02*
X748399D01*
G01X730491Y900656D02*
X734841D01*
G01Y890617D02*
X730491D01*
G01X748399Y917389D02*
X744049D01*
G01D02*
X739699D01*
G01X748399Y910696D02*
X744049D01*
G01D02*
X739699D01*
G01X748399Y904003D02*
X744049D01*
G01D02*
X739699D01*
G01X734841Y914042D02*
X730491D01*
G01Y907349D02*
X734841D01*
G01X748399Y930774D02*
X744049D01*
G01D02*
X739699D01*
G01X748399Y924081D02*
X744049D01*
G01D02*
X739699D01*
G01X730491Y927428D02*
X734841D01*
G01X730491Y920735D02*
X734841D01*
G01X748399Y947507D02*
X744049D01*
G01D02*
X739699D01*
G01X748399Y940814D02*
X744049D01*
G01D02*
X739699D01*
G01X730491Y944160D02*
X734841D01*
G01X730491Y937467D02*
X734841D01*
G01X748399Y964239D02*
X744049D01*
G01D02*
X739699D01*
G01X748399Y954200D02*
X744049D01*
G01D02*
X739699D01*
G01X730491Y960892D02*
X734841D01*
G01X730491Y950853D02*
X734841D01*
G01X748399Y977625D02*
X744049D01*
G01D02*
X739699D01*
G01X748399Y970932D02*
X744049D01*
G01D02*
X739699D01*
G01X730491Y980971D02*
X734841D01*
G01X730491Y974278D02*
X734841D01*
G01X730491Y967585D02*
X734841D01*
G01X748399Y991011D02*
X744049D01*
G01D02*
X739699D01*
G01X748399Y984318D02*
X744049D01*
G01D02*
X739699D01*
G01X734841Y987664D02*
X730491D01*
G01X748399Y1031168D02*
X744049D01*
G01D02*
X739699D01*
G01X748399Y1024475D02*
X744049D01*
G01D02*
X739699D01*
G01X748399Y1017782D02*
X744049D01*
G01D02*
X739699D01*
G01X734841Y1027822D02*
X730491D01*
G01Y1017782D02*
X734841D01*
G01X748399Y1044554D02*
X744049D01*
G01D02*
X739699D01*
G01X748399Y1037861D02*
X744049D01*
G01D02*
X739699D01*
G01X730491Y1041207D02*
X734841D01*
G01X730491Y1034515D02*
X734841D01*
G01X748399Y1057940D02*
X744049D01*
G01D02*
X739699D01*
G01Y1051247D02*
X744049D01*
G01D02*
X748399D01*
G01X730491Y1061286D02*
X734841D01*
G01X730491Y1054593D02*
X734841D01*
G01X730491Y1047900D02*
X734841D01*
G01X739699Y1078018D02*
X744049D01*
G01D02*
X748399D01*
G01X739699Y1071326D02*
X744049D01*
G01D02*
X748399D01*
G01Y1064633D02*
X744049D01*
G01D02*
X739699D01*
G01X734841Y1074672D02*
X730491D01*
G01Y1067979D02*
X734841D01*
G01X739699Y1094751D02*
X744049D01*
G01D02*
X748399D01*
G01X739699Y1088058D02*
X744049D01*
G01D02*
X748399D01*
G01X734841Y1091404D02*
X730491D01*
G01X734841Y1084711D02*
X730491D01*
G01X739699Y1108137D02*
X744049D01*
G01D02*
X748399D01*
G01X739699Y1101444D02*
X744049D01*
G01D02*
X748399D01*
G01X730491Y1111483D02*
X734841D01*
G01X730491Y1104790D02*
X734841D01*
G01Y1098097D02*
X730491D01*
G01X739699Y1124869D02*
X744049D01*
G01D02*
X748399D01*
G01X739699Y1114829D02*
X744049D01*
G01D02*
X748399D01*
G01X734841Y1128215D02*
X730491D01*
G01X734841Y1121522D02*
X730491D01*
G01X748399Y1144948D02*
X744049D01*
G01D02*
X739699D01*
G01Y1138255D02*
X744049D01*
G01D02*
X748399D01*
G01X739699Y1131562D02*
X744049D01*
G01D02*
X748399D01*
G01X734841Y1141601D02*
X730491D01*
G01X734841Y1134908D02*
X730491D01*
G01X748399Y1151641D02*
X744049D01*
G01D02*
X739699D01*
G01X734841Y1158333D02*
X730491D01*
G01X734841Y1148294D02*
X730491D01*
G01X739699Y1175066D02*
X744049D01*
G01D02*
X748399D01*
G01X739699Y1168373D02*
X744049D01*
G01D02*
X748399D01*
G01X739699Y1161680D02*
X744049D01*
G01D02*
X748399D01*
G01X730491Y1171719D02*
X734841D01*
G01Y1165026D02*
X730491D01*
G01X739699Y1188452D02*
X744049D01*
G01D02*
X748399D01*
G01Y1181759D02*
X744049D01*
G01D02*
X739699D01*
G01X730491Y1185105D02*
X734841D01*
G01X730491Y1178412D02*
X734841D01*
G01X739699Y1205184D02*
X744049D01*
G01D02*
X748399D01*
G01X739699Y1198491D02*
X744049D01*
G01D02*
X748399D01*
G01X734841Y1208530D02*
X730491D01*
G01X734841Y1201837D02*
X730491D01*
G01X734841Y1195144D02*
X730491D01*
G01X739699Y1225263D02*
X744049D01*
G01D02*
X748399D01*
G01X739699Y1218570D02*
X744049D01*
G01D02*
X748399D01*
G01X739699Y1211877D02*
X744049D01*
G01D02*
X748399D01*
G01X734841Y1221916D02*
X730491D01*
G01X734841Y1215223D02*
X730491D01*
G01X739699Y1241995D02*
X744049D01*
G01D02*
X748399D01*
G01X739699Y1235302D02*
X744049D01*
G01D02*
X748399D01*
G01X734841Y1238648D02*
X730491D01*
G01X734841Y1231955D02*
X730491D01*
G01X739699Y1248688D02*
X744049D01*
G01D02*
X748399D01*
G01X734841Y1245341D02*
X730491D01*
G01X739699Y1258727D02*
X744049D01*
G01X748820Y137864D02*
X751220D01*
G01X748125Y167537D02*
X745725D01*
G01X759637Y311585D02*
X759973Y311249D01*
X763568D01*
G01X763095Y317432D02*
X760670D01*
G01X756642Y496522D02*
X757779Y497659D01*
X759775D01*
G01X764541Y766798D02*
X760191D01*
G01D02*
X755841D01*
G01X764541Y780184D02*
X760191D01*
G01D02*
X755841D01*
G01X764541Y773491D02*
X760191D01*
G01D02*
X755841D01*
G01X764541Y803609D02*
X760191D01*
G01D02*
X755841D01*
G01X764541Y796916D02*
X760191D01*
G01D02*
X755841D01*
G01X764541Y790223D02*
X760191D01*
G01D02*
X755841D01*
G01X764541Y816995D02*
X760191D01*
G01D02*
X755841D01*
G01X764541Y810302D02*
X760191D01*
G01D02*
X755841D01*
G01X764541Y833727D02*
X760191D01*
G01D02*
X755841D01*
G01X764541Y827034D02*
X760191D01*
G01D02*
X755841D01*
G01X764541Y847113D02*
X760191D01*
G01D02*
X755841D01*
G01X764541Y840420D02*
X760191D01*
G01D02*
X755841D01*
G01X764541Y863845D02*
X760191D01*
G01D02*
X755841D01*
G01X764541Y853806D02*
X760191D01*
G01D02*
X755841D01*
G01X764541Y883924D02*
X760191D01*
G01D02*
X755841D01*
G01X764541Y877231D02*
X760191D01*
G01D02*
X755841D01*
G01X764541Y870538D02*
X760191D01*
G01D02*
X755841D01*
G01X764541Y900656D02*
X760191D01*
G01D02*
X755841D01*
G01X764541Y890617D02*
X760191D01*
G01D02*
X755841D01*
G01X764541Y914042D02*
X760191D01*
G01D02*
X755841D01*
G01Y907349D02*
X760191D01*
G01D02*
X764541D01*
G01Y927428D02*
X760191D01*
G01D02*
X755841D01*
G01X764541Y920735D02*
X760191D01*
G01D02*
X755841D01*
G01X764541Y944160D02*
X760191D01*
G01D02*
X755841D01*
G01X764541Y937467D02*
X760191D01*
G01D02*
X755841D01*
G01X764541Y960892D02*
X760191D01*
G01D02*
X755841D01*
G01X764541Y950853D02*
X760191D01*
G01D02*
X755841D01*
G01X764541Y980971D02*
X760191D01*
G01D02*
X755841D01*
G01X764541Y974278D02*
X760191D01*
G01D02*
X755841D01*
G01X764541Y967585D02*
X760191D01*
G01D02*
X755841D01*
G01X764541Y987664D02*
X760191D01*
G01D02*
X755841D01*
G01X764541Y1027822D02*
X760191D01*
G01D02*
X755841D01*
G01X764541Y1017782D02*
X760191D01*
G01D02*
X755841D01*
G01X764541Y1041207D02*
X760191D01*
G01D02*
X755841D01*
G01X764541Y1034515D02*
X760191D01*
G01D02*
X755841D01*
G01Y1054593D02*
X760191D01*
G01D02*
X764541D01*
G01X755841Y1061286D02*
X760191D01*
G01D02*
X764541D01*
G01Y1047900D02*
X760191D01*
G01D02*
X755841D01*
G01Y1067979D02*
X760191D01*
G01D02*
X764541D01*
G01X755841Y1074672D02*
X760191D01*
G01D02*
X764541D01*
G01X755841Y1084711D02*
X760191D01*
G01D02*
X764541D01*
G01X755841Y1091404D02*
X760191D01*
G01D02*
X764541D01*
G01X755841Y1111483D02*
X760191D01*
G01D02*
X764541D01*
G01X755841Y1104790D02*
X760191D01*
G01D02*
X764541D01*
G01X755841Y1098097D02*
X760191D01*
G01D02*
X764541D01*
G01X755841Y1128215D02*
X760191D01*
G01D02*
X764541D01*
G01X755841Y1121522D02*
X760191D01*
G01D02*
X764541D01*
G01X755841Y1141601D02*
X760191D01*
G01D02*
X764541D01*
G01X755841Y1134908D02*
X760191D01*
G01D02*
X764541D01*
G01X755841Y1158333D02*
X760191D01*
G01D02*
X764541D01*
G01X755841Y1148294D02*
X760191D01*
G01D02*
X764541D01*
G01X755841Y1171719D02*
X760191D01*
G01D02*
X764541D01*
G01X755841Y1165026D02*
X760191D01*
G01D02*
X764541D01*
G01X755841Y1185105D02*
X760191D01*
G01D02*
X764541D01*
G01X755841Y1178412D02*
X760191D01*
G01D02*
X764541D01*
G01X755841Y1208530D02*
X760191D01*
G01D02*
X764541D01*
G01X755841Y1201837D02*
X760191D01*
G01D02*
X764541D01*
G01X755841Y1195144D02*
X760191D01*
G01D02*
X764541D01*
G01X755841Y1221916D02*
X760191D01*
G01D02*
X764541D01*
G01X755841Y1215223D02*
X760191D01*
G01D02*
X764541D01*
G01X755841Y1238648D02*
X760191D01*
G01D02*
X764541D01*
G01X755841Y1231955D02*
X760191D01*
G01D02*
X764541D01*
G01X755841Y1245341D02*
X760191D01*
G01D02*
X764541D01*
G01X759859Y1689020D02*
Y1686090D01*
G01X759359Y1726670D02*
Y1729520D01*
G01X774728Y153728D02*
X772328D01*
G01X763795Y413212D02*
X766195D01*
G01X763795Y423212D02*
X766195D01*
G01X763795Y428212D02*
X766195D01*
G01X777220Y441437D02*
X775196D01*
X774562Y440803D01*
X771066D01*
G01X780020Y441437D02*
X777220D01*
G01Y445287D02*
X780020D01*
G01X765335Y469552D02*
X765025Y469862D01*
X762915D01*
G01X762975Y493452D02*
X766510D01*
G01X769399Y770144D02*
X773749D01*
G01D02*
X778099D01*
G01X769399Y783530D02*
X773749D01*
G01D02*
X778099D01*
G01X769399Y776837D02*
X773749D01*
G01D02*
X778099D01*
G01X769399Y800263D02*
X773749D01*
G01D02*
X778099D01*
G01X769399Y793570D02*
X773749D01*
G01D02*
X778099D01*
G01X769399Y813648D02*
X773749D01*
G01D02*
X778099D01*
G01X769399Y806955D02*
X773749D01*
G01D02*
X778099D01*
G01X769399Y830381D02*
X773749D01*
G01D02*
X778099D01*
G01X769399Y820341D02*
X773749D01*
G01D02*
X778099D01*
G01X769399Y850459D02*
X773749D01*
G01D02*
X778099D01*
G01Y843766D02*
X773749D01*
G01D02*
X769399D01*
G01Y837074D02*
X773749D01*
G01D02*
X778099D01*
G01Y867192D02*
X773749D01*
G01D02*
X769399D01*
G01Y857152D02*
X773749D01*
G01D02*
X778099D01*
G01X769399Y880577D02*
X773749D01*
G01D02*
X778099D01*
G01X769399Y873885D02*
X773749D01*
G01D02*
X778099D01*
G01Y893963D02*
X773749D01*
G01D02*
X769399D01*
G01Y887270D02*
X773749D01*
G01D02*
X778099D01*
G01X769399Y917389D02*
X773749D01*
G01D02*
X778099D01*
G01X769399Y910696D02*
X773749D01*
G01D02*
X778099D01*
G01X769399Y904003D02*
X773749D01*
G01D02*
X778099D01*
G01X769399Y930774D02*
X773749D01*
G01D02*
X778099D01*
G01X769399Y924081D02*
X773749D01*
G01D02*
X778099D01*
G01X769399Y947507D02*
X773749D01*
G01D02*
X778099D01*
G01X769399Y940814D02*
X773749D01*
G01D02*
X778099D01*
G01X769399Y964239D02*
X773749D01*
G01D02*
X778099D01*
G01X769399Y954200D02*
X773749D01*
G01D02*
X778099D01*
G01X769399Y977625D02*
X773749D01*
G01D02*
X778099D01*
G01X769399Y970932D02*
X773749D01*
G01D02*
X778099D01*
G01X769399Y991011D02*
X773749D01*
G01D02*
X778099D01*
G01X769399Y984318D02*
X773749D01*
G01D02*
X778099D01*
G01X769399Y1031168D02*
X773749D01*
G01D02*
X778099D01*
G01X769399Y1024475D02*
X773749D01*
G01D02*
X778099D01*
G01X769399Y1017782D02*
X773749D01*
G01D02*
X778099D01*
G01Y1044554D02*
X773749D01*
G01D02*
X769399D01*
G01Y1037861D02*
X773749D01*
G01D02*
X778099D01*
G01X769399Y1057940D02*
X773749D01*
G01D02*
X778099D01*
G01X769399Y1051247D02*
X773749D01*
G01D02*
X778099D01*
G01Y1078018D02*
X773749D01*
G01D02*
X769399D01*
G01X778099Y1071326D02*
X773749D01*
G01D02*
X769399D01*
G01Y1064633D02*
X773749D01*
G01D02*
X778099D01*
G01Y1094751D02*
X773749D01*
G01D02*
X769399D01*
G01X778099Y1088058D02*
X773749D01*
G01D02*
X769399D01*
G01X778099Y1108137D02*
X773749D01*
G01D02*
X769399D01*
G01X778099Y1101444D02*
X773749D01*
G01D02*
X769399D01*
G01X778099Y1124869D02*
X773749D01*
G01D02*
X769399D01*
G01X778099Y1114829D02*
X773749D01*
G01D02*
X769399D01*
G01X778099Y1144948D02*
X773749D01*
G01D02*
X769399D01*
G01X778099Y1138255D02*
X773749D01*
G01D02*
X769399D01*
G01X778099Y1131562D02*
X773749D01*
G01D02*
X769399D01*
G01X778099Y1151641D02*
X773749D01*
G01D02*
X769399D01*
G01X778099Y1175066D02*
X773749D01*
G01D02*
X769399D01*
G01X778099Y1168373D02*
X773749D01*
G01D02*
X769399D01*
G01X778099Y1161680D02*
X773749D01*
G01D02*
X769399D01*
G01X778099Y1188452D02*
X773749D01*
G01D02*
X769399D01*
G01X778099Y1181759D02*
X773749D01*
G01D02*
X769399D01*
G01Y1205184D02*
X773749D01*
G01D02*
X778099D01*
G01Y1198491D02*
X773749D01*
G01D02*
X769399D01*
G01X778099Y1225263D02*
X773749D01*
G01D02*
X769399D01*
G01X778099Y1218570D02*
X773749D01*
G01D02*
X769399D01*
G01Y1211877D02*
X773749D01*
G01D02*
X778099D01*
G01Y1241995D02*
X773749D01*
G01D02*
X769399D01*
G01X778099Y1235302D02*
X773749D01*
G01D02*
X769399D01*
G01X778099Y1248688D02*
X773749D01*
G01D02*
X769399D01*
G01Y1258727D02*
X773749D01*
G01X765095Y1384062D02*
X768520D01*
G01X765195Y1375462D02*
X768520D01*
G01X765095Y1397262D02*
X768620D01*
G01X765095Y1401562D02*
Y1397262D01*
G01X764995Y1414762D02*
X767820D01*
G01X764920Y1695347D02*
Y1697391D01*
X763790Y1698521D01*
G01D02*
Y1702039D01*
X762013Y1703816D01*
G01X791075Y385300D02*
X793430Y382945D01*
X796060D01*
G01X791075Y385300D02*
Y388000D01*
G01X778795Y393212D02*
X781195D01*
G01X792995Y398212D02*
X795520D01*
G01X788120Y422942D02*
Y424403D01*
X789004Y425287D01*
X789720D01*
G01X781205Y454402D02*
X780745Y454862D01*
X777915D01*
G01X796315Y469290D02*
X793487D01*
X792915Y469862D01*
G01X783450Y520057D02*
Y522462D01*
G01X785541Y766798D02*
X789891D01*
G01D02*
X794241D01*
G01X785541Y773491D02*
X789891D01*
G01D02*
X794241D01*
G01X785541Y780184D02*
X789891D01*
G01D02*
X794241D01*
G01X785541Y803609D02*
X789891D01*
G01D02*
X794241D01*
G01X785541Y790223D02*
X789891D01*
G01D02*
X794241D01*
G01X785541Y796916D02*
X789891D01*
G01D02*
X794241D01*
G01X785541Y816995D02*
X789891D01*
G01D02*
X794241D01*
G01X785541Y810302D02*
X789891D01*
G01D02*
X794241D01*
G01X785541Y833727D02*
X789891D01*
G01D02*
X794241D01*
G01X785541Y827034D02*
X789891D01*
G01D02*
X794241D01*
G01X785541Y840420D02*
X789891D01*
G01D02*
X794241D01*
G01X785541Y847113D02*
X789891D01*
G01D02*
X794241D01*
G01X785541Y853806D02*
X789891D01*
G01D02*
X794241D01*
G01X785541Y863845D02*
X789891D01*
G01D02*
X794241D01*
G01X785541Y883924D02*
X789891D01*
G01D02*
X794241D01*
G01X785541Y870538D02*
X789891D01*
G01D02*
X794241D01*
G01X785541Y877231D02*
X789891D01*
G01D02*
X794241D01*
G01X785541Y900656D02*
X789891D01*
G01D02*
X794241D01*
G01X785541Y890617D02*
X789891D01*
G01D02*
X794241D01*
G01X785541Y907349D02*
X789891D01*
G01D02*
X794241D01*
G01X785541Y914042D02*
X789891D01*
G01D02*
X794241D01*
G01X785541Y920735D02*
X789891D01*
G01D02*
X794241D01*
G01X785541Y927428D02*
X789891D01*
G01D02*
X794241D01*
G01X785541Y937467D02*
X789891D01*
G01D02*
X794241D01*
G01X785541Y944160D02*
X789891D01*
G01D02*
X794241D01*
G01X785541Y960892D02*
X789891D01*
G01D02*
X794241D01*
G01X785541Y950853D02*
X789891D01*
G01D02*
X794241D01*
G01X785541Y980971D02*
X789891D01*
G01D02*
X794241D01*
G01X785541Y974278D02*
X789891D01*
G01D02*
X794241D01*
G01X785541Y967585D02*
X789891D01*
G01D02*
X794241D01*
G01X785541Y987664D02*
X789891D01*
G01D02*
X794241D01*
G01X785541Y1027822D02*
X789891D01*
G01D02*
X794241D01*
G01X785541Y1017782D02*
X789891D01*
G01D02*
X794241D01*
G01X785541Y1041207D02*
X789891D01*
G01D02*
X794241D01*
G01X785541Y1034515D02*
X789891D01*
G01D02*
X794241D01*
G01X785541Y1054593D02*
X789891D01*
G01D02*
X794241D01*
G01X785541Y1061286D02*
X789891D01*
G01D02*
X794241D01*
G01X785541Y1047900D02*
X789891D01*
G01D02*
X794241D01*
G01X785541Y1074672D02*
X789891D01*
G01D02*
X794241D01*
G01X785541Y1067979D02*
X789891D01*
G01D02*
X794241D01*
G01X785541Y1091404D02*
X789891D01*
G01D02*
X794241D01*
G01X785541Y1084711D02*
X789891D01*
G01D02*
X794241D01*
G01X785541Y1111483D02*
X789891D01*
G01D02*
X794241D01*
G01X785541Y1104790D02*
X789891D01*
G01D02*
X794241D01*
G01X785541Y1098097D02*
X789891D01*
G01D02*
X794241D01*
G01X785541Y1128215D02*
X789891D01*
G01D02*
X794241D01*
G01X785541Y1121522D02*
X789891D01*
G01D02*
X794241D01*
G01X785541Y1141601D02*
X789891D01*
G01D02*
X794241D01*
G01X785541Y1134908D02*
X789891D01*
G01D02*
X794241D01*
G01X785541Y1158333D02*
X789891D01*
G01D02*
X794241D01*
G01X785541Y1148294D02*
X789891D01*
G01D02*
X794241D01*
G01X785541Y1171719D02*
X789891D01*
G01D02*
X794241D01*
G01X785541Y1165026D02*
X789891D01*
G01D02*
X794241D01*
G01X785541Y1178412D02*
X789891D01*
G01D02*
X794241D01*
G01X785541Y1185105D02*
X789891D01*
G01D02*
X794241D01*
G01X785541Y1208530D02*
X789891D01*
G01D02*
X794241D01*
G01X785541Y1195144D02*
X789891D01*
G01D02*
X794241D01*
G01X785541Y1201837D02*
X789891D01*
G01D02*
X794241D01*
G01X785541Y1221916D02*
X789891D01*
G01D02*
X794241D01*
G01X785541Y1215223D02*
X789891D01*
G01D02*
X794241D01*
G01X785541Y1238648D02*
X789891D01*
G01D02*
X794241D01*
G01X785541Y1231955D02*
X789891D01*
G01D02*
X794241D01*
G01X785541Y1245341D02*
X789891D01*
G01D02*
X794241D01*
G01X806037Y269800D02*
X806900D01*
X808800Y267900D01*
G01X806000Y363125D02*
Y360600D01*
G01X798400Y363125D02*
Y360600D01*
G01X805495Y441060D02*
X803130D01*
X802010Y439940D01*
G01X812810Y519957D02*
X807640D01*
G01D02*
X801622D01*
X801547Y519882D01*
G01X799099Y770144D02*
X803449D01*
G01D02*
X807799D01*
G01X799099Y783530D02*
X803449D01*
G01D02*
X807799D01*
G01X799099Y776837D02*
X803449D01*
G01D02*
X807799D01*
G01X799099Y800263D02*
X803449D01*
G01D02*
X807799D01*
G01X799099Y793570D02*
X803449D01*
G01D02*
X807799D01*
G01X799099Y806955D02*
X803449D01*
G01D02*
X807799D01*
G01X799099Y813648D02*
X803449D01*
G01D02*
X807799D01*
G01X799099Y830381D02*
X803449D01*
G01D02*
X807799D01*
G01X799099Y820341D02*
X803449D01*
G01D02*
X807799D01*
G01X799099Y850459D02*
X803449D01*
G01D02*
X807799D01*
G01X799099Y837074D02*
X803449D01*
G01D02*
X807799D01*
G01X799099Y843766D02*
X803449D01*
G01D02*
X807799D01*
G01X799099Y867192D02*
X803449D01*
G01D02*
X807799D01*
G01X799099Y857152D02*
X803449D01*
G01D02*
X807799D01*
G01X799099Y873885D02*
X803449D01*
G01D02*
X807799D01*
G01X799099Y880577D02*
X803449D01*
G01D02*
X807799D01*
G01X799099Y887270D02*
X803449D01*
G01D02*
X807799D01*
G01X799099Y893963D02*
X803449D01*
G01D02*
X807799D01*
G01X799099Y917389D02*
X803449D01*
G01D02*
X807799D01*
G01X799099Y904003D02*
X803449D01*
G01D02*
X807799D01*
G01X799099Y910696D02*
X803449D01*
G01D02*
X807799D01*
G01X799099Y930774D02*
X803449D01*
G01D02*
X807799D01*
G01X799099Y924081D02*
X803449D01*
G01D02*
X807799D01*
G01X799099Y947507D02*
X803449D01*
G01D02*
X807799D01*
G01X799099Y940814D02*
X803449D01*
G01D02*
X807799D01*
G01X799099Y964239D02*
X803449D01*
G01D02*
X807799D01*
G01X799099Y954200D02*
X803449D01*
G01D02*
X807799D01*
G01X799099Y970932D02*
X803449D01*
G01D02*
X807799D01*
G01X799099Y977625D02*
X803449D01*
G01D02*
X807799D01*
G01X799099Y991011D02*
X803449D01*
G01D02*
X807799D01*
G01X799099Y984318D02*
X803449D01*
G01D02*
X807799D01*
G01X799099Y1031168D02*
X803449D01*
G01D02*
X807799D01*
G01X799099Y1024475D02*
X803449D01*
G01D02*
X807799D01*
G01X799099Y1017782D02*
X803449D01*
G01D02*
X807799D01*
G01X799099Y1037861D02*
X803449D01*
G01D02*
X807799D01*
G01X799099Y1044554D02*
X803449D01*
G01D02*
X807799D01*
G01X799099Y1057940D02*
X803449D01*
G01D02*
X807799D01*
G01X799099Y1051247D02*
X803449D01*
G01D02*
X807799D01*
G01X799099Y1078018D02*
X803449D01*
G01D02*
X807799D01*
G01X799099Y1071326D02*
X803449D01*
G01D02*
X807799D01*
G01X799099Y1064633D02*
X803449D01*
G01D02*
X807799D01*
G01X799099Y1094751D02*
X803449D01*
G01D02*
X807799D01*
G01X799099Y1088058D02*
X803449D01*
G01D02*
X807799D01*
G01X799099Y1108137D02*
X803449D01*
G01D02*
X807799D01*
G01X799099Y1101444D02*
X803449D01*
G01D02*
X807799D01*
G01X799099Y1124869D02*
X803449D01*
G01D02*
X807799D01*
G01X799099Y1114829D02*
X803449D01*
G01D02*
X807799D01*
G01X799099Y1144948D02*
X803449D01*
G01D02*
X807799D01*
G01X799099Y1138255D02*
X803449D01*
G01D02*
X807799D01*
G01X799099Y1131562D02*
X803449D01*
G01D02*
X807799D01*
G01X799099Y1151641D02*
X803449D01*
G01D02*
X807799D01*
G01X799099Y1175066D02*
X803449D01*
G01D02*
X807799D01*
G01X799099Y1168373D02*
X803449D01*
G01D02*
X807799D01*
G01X799099Y1161680D02*
X803449D01*
G01D02*
X807799D01*
G01X799099Y1188452D02*
X803449D01*
G01D02*
X807799D01*
G01X799099Y1181759D02*
X803449D01*
G01D02*
X807799D01*
G01X799099Y1205184D02*
X803449D01*
G01D02*
X807799D01*
G01X799099Y1198491D02*
X803449D01*
G01D02*
X807799D01*
G01X799099Y1225263D02*
X803449D01*
G01D02*
X807799D01*
G01X799099Y1211877D02*
X803449D01*
G01D02*
X807799D01*
G01X799099Y1218570D02*
X803449D01*
G01D02*
X807799D01*
G01X799099Y1241995D02*
X803449D01*
G01D02*
X807799D01*
G01X799099Y1235302D02*
X803449D01*
G01D02*
X807799D01*
G01X799099Y1248688D02*
X803449D01*
G01D02*
X807799D01*
G01X799099Y1258727D02*
X803449D01*
G01X823114Y117623D02*
Y115223D01*
G01X826614Y147123D02*
X829114D01*
G01X818000Y383025D02*
Y378800D01*
G01X827403Y389012D02*
X825003D01*
G01X827403Y397276D02*
X825003D01*
G01X827402Y413260D02*
X824980D01*
G01X822415Y476800D02*
X824099D01*
X825199Y475700D01*
X827500D01*
X828959Y474241D01*
X832084D01*
G01X822415Y476800D02*
Y479600D01*
G01Y468900D02*
X825100D01*
G01X812810Y516807D02*
X815650D01*
G01X824195Y515082D02*
X821720D01*
G01X824195Y523082D02*
X821720D01*
G01X815241Y766798D02*
X819591D01*
G01D02*
X823941D01*
G01X815241Y773491D02*
X819591D01*
G01D02*
X823941D01*
G01X815241Y780184D02*
X819591D01*
G01D02*
X823941D01*
G01X815241Y803609D02*
X819591D01*
G01D02*
X823941D01*
G01X815241Y790223D02*
X819591D01*
G01D02*
X823941D01*
G01X815241Y796916D02*
X819591D01*
G01D02*
X823941D01*
G01X815241Y816995D02*
X819591D01*
G01D02*
X823941D01*
G01X815241Y810302D02*
X819591D01*
G01D02*
X823941D01*
G01X815241Y833727D02*
X819591D01*
G01D02*
X823941D01*
G01X815241Y827034D02*
X819591D01*
G01D02*
X823941D01*
G01X815241Y840420D02*
X819591D01*
G01D02*
X823941D01*
G01X815241Y847113D02*
X819591D01*
G01D02*
X823941D01*
G01X815241Y853806D02*
X819591D01*
G01D02*
X823941D01*
G01X815241Y863845D02*
X819591D01*
G01D02*
X823941D01*
G01X815241Y883924D02*
X819591D01*
G01D02*
X823941D01*
G01X815241Y870538D02*
X819591D01*
G01D02*
X823941D01*
G01X815241Y877231D02*
X819591D01*
G01D02*
X823941D01*
G01X815241Y900656D02*
X819591D01*
G01D02*
X823941D01*
G01X815241Y890617D02*
X819591D01*
G01D02*
X823941D01*
G01X815241Y907349D02*
X819591D01*
G01D02*
X823941D01*
G01X815241Y914042D02*
X819591D01*
G01D02*
X823941D01*
G01X815241Y920735D02*
X819591D01*
G01D02*
X823941D01*
G01X815241Y927428D02*
X819591D01*
G01D02*
X823941D01*
G01X815241Y937467D02*
X819591D01*
G01D02*
X823941D01*
G01X815241Y944160D02*
X819591D01*
G01D02*
X823941D01*
G01X815241Y960892D02*
X819591D01*
G01D02*
X823941D01*
G01X815241Y950853D02*
X819591D01*
G01D02*
X823941D01*
G01X815241Y980971D02*
X819591D01*
G01D02*
X823941D01*
G01X815241Y974278D02*
X819591D01*
G01D02*
X823941D01*
G01X815241Y967585D02*
X819591D01*
G01D02*
X823941D01*
G01X815241Y987664D02*
X819591D01*
G01D02*
X823941D01*
G01X815241Y1027822D02*
X819591D01*
G01D02*
X823941D01*
G01X815241Y1017782D02*
X819591D01*
G01D02*
X823941D01*
G01X815241Y1041207D02*
X819591D01*
G01D02*
X823941D01*
G01X815241Y1034515D02*
X819591D01*
G01D02*
X823941D01*
G01X815241Y1054593D02*
X819591D01*
G01D02*
X823941D01*
G01X815241Y1061286D02*
X819591D01*
G01D02*
X823941D01*
G01X815241Y1047900D02*
X819591D01*
G01D02*
X823941D01*
G01X815241Y1074672D02*
X819591D01*
G01D02*
X823941D01*
G01X815241Y1067979D02*
X819591D01*
G01D02*
X823941D01*
G01X815241Y1091404D02*
X819591D01*
G01D02*
X823941D01*
G01X815241Y1084711D02*
X819591D01*
G01D02*
X823941D01*
G01X815241Y1111483D02*
X819591D01*
G01D02*
X823941D01*
G01X815241Y1104790D02*
X819591D01*
G01D02*
X823941D01*
G01X815241Y1098097D02*
X819591D01*
G01D02*
X823941D01*
G01X815241Y1128215D02*
X819591D01*
G01D02*
X823941D01*
G01X815241Y1121522D02*
X819591D01*
G01D02*
X823941D01*
G01X815241Y1141601D02*
X819591D01*
G01D02*
X823941D01*
G01X815241Y1134908D02*
X819591D01*
G01D02*
X823941D01*
G01X815241Y1158333D02*
X819591D01*
G01D02*
X823941D01*
G01X815241Y1148294D02*
X819591D01*
G01D02*
X823941D01*
G01X815241Y1171719D02*
X819591D01*
G01D02*
X823941D01*
G01X815241Y1165026D02*
X819591D01*
G01D02*
X823941D01*
G01X815241Y1178412D02*
X819591D01*
G01D02*
X823941D01*
G01X815241Y1185105D02*
X819591D01*
G01D02*
X823941D01*
G01X815241Y1208530D02*
X819591D01*
G01D02*
X823941D01*
G01X815241Y1195144D02*
X819591D01*
G01D02*
X823941D01*
G01X815241Y1201837D02*
X819591D01*
G01D02*
X823941D01*
G01X815241Y1221916D02*
X819591D01*
G01D02*
X823941D01*
G01X815241Y1215223D02*
X819591D01*
G01D02*
X823941D01*
G01X815241Y1238648D02*
X819591D01*
G01D02*
X823941D01*
G01X815241Y1231955D02*
X819591D01*
G01D02*
X823941D01*
G01X815241Y1245341D02*
X819591D01*
G01D02*
X823941D01*
G01X831386Y58632D02*
Y55461D01*
X833283Y53564D01*
X841420D01*
X842596Y54740D01*
Y58448D01*
G01X828600Y61752D02*
Y60731D01*
X830699Y58632D01*
X831386D01*
G01X834615Y107356D02*
X840337D01*
X841742Y105951D01*
G01X839360Y117507D02*
Y114862D01*
G01D02*
X834615Y110117D01*
Y107356D01*
G01X828145Y166862D02*
Y160362D01*
G01X848745Y162762D02*
X848820Y162837D01*
Y165662D01*
X846418Y168064D01*
X842562D01*
G01X835400Y268800D02*
X833911Y270289D01*
X832500D01*
G01X842470Y410760D02*
X836260D01*
G01X830552Y413260D02*
X833760D01*
X836260Y410760D01*
G01X830552Y413260D02*
Y409260D01*
G01Y405260D02*
Y409260D01*
G01X836300Y421325D02*
Y418800D01*
G01X832400Y424475D02*
Y427100D01*
G01X835460Y440815D02*
Y446765D01*
X835425Y446800D01*
G01D02*
X832700D01*
G01X828075Y449200D02*
X830600D01*
G01X838645Y495362D02*
Y492862D01*
G01X838530Y500523D02*
Y495477D01*
X838645Y495362D01*
G01X833149Y770144D02*
X837499D01*
G01X828799D02*
X833149D01*
G01X828799Y783530D02*
X833149D01*
G01D02*
X837499D01*
G01X828799Y776837D02*
X833149D01*
G01D02*
X837499D01*
G01Y800263D02*
X833149D01*
G01D02*
X828799D01*
G01X837499Y793570D02*
X833149D01*
G01D02*
X828799D01*
G01Y813648D02*
X833149D01*
G01D02*
X837499D01*
G01X828799Y806955D02*
X833149D01*
G01D02*
X837499D01*
G01X828799Y830381D02*
X833149D01*
G01D02*
X837499D01*
G01X828799Y820341D02*
X833149D01*
G01D02*
X837499D01*
G01X828799Y850459D02*
X833149D01*
G01D02*
X837499D01*
G01X828799Y843766D02*
X833149D01*
G01D02*
X837499D01*
G01X828799Y837074D02*
X833149D01*
G01D02*
X837499D01*
G01X828799Y867192D02*
X833149D01*
G01D02*
X837499D01*
G01X828799Y857152D02*
X833149D01*
G01D02*
X837499D01*
G01X828799Y880577D02*
X833149D01*
G01D02*
X837499D01*
G01X828799Y873885D02*
X833149D01*
G01D02*
X837499D01*
G01X828799Y893963D02*
X833149D01*
G01D02*
X837499D01*
G01X828799Y887270D02*
X833149D01*
G01D02*
X837499D01*
G01X828799Y917389D02*
X833149D01*
G01D02*
X837499D01*
G01Y904003D02*
X833149D01*
G01D02*
X828799D01*
G01X837499Y910696D02*
X833149D01*
G01D02*
X828799D01*
G01Y930774D02*
X833149D01*
G01D02*
X837499D01*
G01X828799Y924081D02*
X833149D01*
G01D02*
X837499D01*
G01X828799Y947507D02*
X833149D01*
G01D02*
X837499D01*
G01X828799Y940814D02*
X833149D01*
G01D02*
X837499D01*
G01X828799Y964239D02*
X833149D01*
G01D02*
X837499D01*
G01X828799Y954200D02*
X833149D01*
G01D02*
X837499D01*
G01X828799Y977625D02*
X833149D01*
G01D02*
X837499D01*
G01X828799Y970932D02*
X833149D01*
G01D02*
X837499D01*
G01X828799Y991011D02*
X833149D01*
G01D02*
X837499D01*
G01X828799Y984318D02*
X833149D01*
G01D02*
X837499D01*
G01X828799Y1031168D02*
X833149D01*
G01D02*
X837499D01*
G01X828799Y1024475D02*
X833149D01*
G01D02*
X837499D01*
G01X828799Y1017782D02*
X833149D01*
G01D02*
X837499D01*
G01X828799Y1044554D02*
X833149D01*
G01D02*
X837499D01*
G01X828799Y1037861D02*
X833149D01*
G01D02*
X837499D01*
G01X828799Y1057940D02*
X833149D01*
G01D02*
X837499D01*
G01X828799Y1051247D02*
X833149D01*
G01D02*
X837499D01*
G01X828799Y1078018D02*
X833149D01*
G01D02*
X837499D01*
G01X828799Y1071326D02*
X833149D01*
G01D02*
X837499D01*
G01X828799Y1064633D02*
X833149D01*
G01D02*
X837499D01*
G01X828799Y1094751D02*
X833149D01*
G01D02*
X837499D01*
G01Y1088058D02*
X833149D01*
G01D02*
X828799D01*
G01X837499Y1108137D02*
X833149D01*
G01D02*
X828799D01*
G01Y1101444D02*
X833149D01*
G01D02*
X837499D01*
G01Y1124869D02*
X833149D01*
G01D02*
X828799D01*
G01X837499Y1114829D02*
X833149D01*
G01D02*
X828799D01*
G01X837499Y1144948D02*
X833149D01*
G01D02*
X828799D01*
G01X837499Y1138255D02*
X833149D01*
G01D02*
X828799D01*
G01X837499Y1131562D02*
X833149D01*
G01D02*
X828799D01*
G01X837499Y1151641D02*
X833149D01*
G01D02*
X828799D01*
G01X837499Y1175066D02*
X833149D01*
G01D02*
X828799D01*
G01X833149Y1168373D02*
X828799D01*
G01X837499D02*
X833149D01*
G01X837499Y1161680D02*
X833149D01*
G01D02*
X828799D01*
G01Y1188452D02*
X833149D01*
G01D02*
X837499D01*
G01Y1181759D02*
X833149D01*
G01D02*
X828799D01*
G01X837499Y1205184D02*
X833149D01*
G01D02*
X828799D01*
G01X837499Y1198491D02*
X833149D01*
G01D02*
X828799D01*
G01X837499Y1225263D02*
X833149D01*
G01D02*
X828799D01*
G01X837499Y1218570D02*
X833149D01*
G01D02*
X828799D01*
G01X837499Y1211877D02*
X833149D01*
G01D02*
X828799D01*
G01X837499Y1241995D02*
X833149D01*
G01D02*
X828799D01*
G01X837499Y1235302D02*
X833149D01*
G01D02*
X828799D01*
G01X837499Y1248688D02*
X833149D01*
G01D02*
X828799D01*
G01Y1258727D02*
X833149D01*
G01X843855Y87711D02*
Y89096D01*
X844935Y90176D01*
G01X848745Y160187D02*
Y162762D01*
G01X846822Y271049D02*
X850133D01*
G01X852998Y392880D02*
X857240D01*
X859621Y395261D01*
G01X849325Y476900D02*
X846700D01*
G01X857195Y519582D02*
Y522162D01*
G01X845483Y518006D02*
X849064D01*
X850640Y519582D01*
X857195D01*
G01X844941Y766798D02*
X849291D01*
G01D02*
X853641D01*
G01X844941Y780184D02*
X849291D01*
G01D02*
X853641D01*
G01X844941Y773491D02*
X849291D01*
G01D02*
X853641D01*
G01X844941Y803609D02*
X849291D01*
G01D02*
X853641D01*
G01X844941Y796916D02*
X849291D01*
G01D02*
X853641D01*
G01X844941Y790223D02*
X849291D01*
G01D02*
X853641D01*
G01X844941Y816995D02*
X849291D01*
G01D02*
X853641D01*
G01X844941Y810302D02*
X849291D01*
G01D02*
X853641D01*
G01X844941Y833727D02*
X849291D01*
G01D02*
X853641D01*
G01X844941Y827034D02*
X849291D01*
G01D02*
X853641D01*
G01X844941Y847113D02*
X849291D01*
G01D02*
X853641D01*
G01X844941Y840420D02*
X849291D01*
G01D02*
X853641D01*
G01X844941Y863845D02*
X849291D01*
G01D02*
X853641D01*
G01X844941Y853806D02*
X849291D01*
G01D02*
X853641D01*
G01X844941Y883924D02*
X849291D01*
G01D02*
X853641D01*
G01X844941Y877231D02*
X849291D01*
G01D02*
X853641D01*
G01X844941Y870538D02*
X849291D01*
G01D02*
X853641D01*
G01X844941Y900656D02*
X849291D01*
G01D02*
X853641D01*
G01X844941Y890617D02*
X849291D01*
G01D02*
X853641D01*
G01X844941Y914042D02*
X849291D01*
G01D02*
X853641D01*
G01X844941Y907349D02*
X849291D01*
G01D02*
X853641D01*
G01X844941Y927428D02*
X849291D01*
G01D02*
X853641D01*
G01X844941Y920735D02*
X849291D01*
G01D02*
X853641D01*
G01X844941Y944160D02*
X849291D01*
G01D02*
X853641D01*
G01X844941Y937467D02*
X849291D01*
G01D02*
X853641D01*
G01X844941Y960892D02*
X849291D01*
G01D02*
X853641D01*
G01X844941Y950853D02*
X849291D01*
G01D02*
X853641D01*
G01X844941Y980971D02*
X849291D01*
G01D02*
X853641D01*
G01X844941Y974278D02*
X849291D01*
G01D02*
X853641D01*
G01X844941Y967585D02*
X849291D01*
G01D02*
X853641D01*
G01X844941Y987664D02*
X849291D01*
G01D02*
X853641D01*
G01X844941Y1027822D02*
X849291D01*
G01D02*
X853641D01*
G01X844941Y1017782D02*
X849291D01*
G01D02*
X853641D01*
G01X844941Y1041207D02*
X849291D01*
G01D02*
X853641D01*
G01X844941Y1034515D02*
X849291D01*
G01D02*
X853641D01*
G01X844941Y1061286D02*
X849291D01*
G01D02*
X853641D01*
G01X844941Y1054593D02*
X849291D01*
G01D02*
X853641D01*
G01X844941Y1047900D02*
X849291D01*
G01D02*
X853641D01*
G01X844941Y1074672D02*
X849291D01*
G01D02*
X853641D01*
G01X844941Y1067979D02*
X849291D01*
G01D02*
X853641D01*
G01X844941Y1091404D02*
X849291D01*
G01D02*
X853641D01*
G01X844941Y1084711D02*
X849291D01*
G01D02*
X853641D01*
G01X844941Y1111483D02*
X849291D01*
G01D02*
X853641D01*
G01X844941Y1104790D02*
X849291D01*
G01D02*
X853641D01*
G01X844941Y1098097D02*
X849291D01*
G01D02*
X853641D01*
G01X844941Y1128215D02*
X849291D01*
G01D02*
X853641D01*
G01X844941Y1121522D02*
X849291D01*
G01D02*
X853641D01*
G01X844941Y1141601D02*
X849291D01*
G01D02*
X853641D01*
G01X844941Y1134908D02*
X849291D01*
G01D02*
X853641D01*
G01X844941Y1158333D02*
X849291D01*
G01D02*
X853641D01*
G01X844941Y1148294D02*
X849291D01*
G01D02*
X853641D01*
G01X844941Y1171719D02*
X849291D01*
G01D02*
X853641D01*
G01X844941Y1165026D02*
X849291D01*
G01D02*
X853641D01*
G01X844941Y1185105D02*
X849291D01*
G01D02*
X853641D01*
G01X844941Y1178412D02*
X849291D01*
G01D02*
X853641D01*
G01X844941Y1208530D02*
X849291D01*
G01D02*
X853641D01*
G01X844941Y1201837D02*
X849291D01*
G01D02*
X853641D01*
G01X844941Y1195144D02*
X849291D01*
G01D02*
X853641D01*
G01X844941Y1221916D02*
X849291D01*
G01D02*
X853641D01*
G01X844941Y1215223D02*
X849291D01*
G01D02*
X853641D01*
G01X844941Y1238648D02*
X849291D01*
G01D02*
X853641D01*
G01X844941Y1231955D02*
X849291D01*
G01D02*
X853641D01*
G01X844941Y1245341D02*
X849291D01*
G01D02*
X853641D01*
G01X871145Y166362D02*
X868730D01*
G01X871145Y163862D02*
Y166362D01*
G01X868730D02*
X866190Y163822D01*
G01X862519Y168064D02*
X859688D01*
G01X866190Y163822D02*
Y164393D01*
X862519Y168064D01*
G01X874295Y171362D02*
X876695D01*
G01X874295Y176862D02*
X876695D01*
G01X869075Y196500D02*
Y189553D01*
X871288Y187340D01*
G01X871890Y196740D02*
X871650Y196500D01*
X869075D01*
G01X862575Y378362D02*
Y377870D01*
X860531Y375826D01*
G01X868061Y386476D02*
X870700D01*
G01X864911Y398620D02*
Y394620D01*
G01Y398620D02*
X862980D01*
X859621Y395261D01*
G01X864911Y390620D02*
Y394620D01*
G01X868061Y398620D02*
X870700D01*
G01X868061Y402581D02*
X870700D01*
G01X868113Y414276D02*
X870513D01*
G01X864745Y431462D02*
X862320D01*
G01X860195Y507162D02*
X862620D01*
G01X881140Y183169D02*
X878327D01*
G01X881150Y187449D02*
X878220D01*
G01X880772Y876760D02*
X878152D01*
G01X882000Y886962D02*
Y882482D01*
X880772Y881254D01*
Y879910D01*
G01X884747Y874405D02*
Y871745D01*
G01X881372Y914880D02*
X882758Y913494D01*
Y911372D01*
X882000Y910614D01*
Y907762D01*
G01X879100Y912608D02*
X881372Y914880D01*
G01X880102Y923235D02*
X883427D01*
X885317Y921345D01*
Y920325D01*
G01X894897Y874405D02*
Y871745D01*
G01X894965Y917422D02*
X895467Y917924D01*
Y920325D01*
G01X913386Y195925D02*
X909386D01*
G01Y203011D02*
X909387Y203012D01*
X913386D01*
G01Y210098D02*
X909386D01*
G01X913386Y217185D02*
X909386D01*
G01Y224271D02*
X909387Y224272D01*
X913386D01*
G01Y231358D02*
X909386D01*
G01X921757Y964612D02*
Y962082D01*
G01X931496Y195925D02*
X935496D01*
G01X931496Y203012D02*
X935496D01*
G01X931496Y210098D02*
X935496D01*
G01X931496Y217185D02*
X935496D01*
G01X931496Y224272D02*
X935496D01*
G01X931496Y231358D02*
X935496D01*
G01X931496Y964612D02*
Y962082D01*
G01X926823Y964577D02*
Y962082D01*
G01X946490Y184912D02*
X949120D01*
G01X948885Y997422D02*
X951560D01*
G01X1001500Y150883D02*
Y148374D01*
X1001575Y148299D01*
G01X1008163Y363356D02*
X1003889D01*
X1003885Y363352D01*
G01X1001440Y359702D02*
X1003885Y362147D01*
Y363352D01*
G01X1003841Y770144D02*
X1008191D01*
G01X1003841Y783530D02*
X1008191D01*
G01X1003841Y776837D02*
X1008191D01*
G01X1003841Y800263D02*
X1008191D01*
G01X1003841Y793570D02*
X1008191D01*
G01X1003841Y813648D02*
X1008191D01*
G01X1003841Y806955D02*
X1008191D01*
G01X1003841Y830381D02*
X1008191D01*
G01X1003841Y820341D02*
X1008191D01*
G01X1003841Y850459D02*
X1008191D01*
G01X1003841Y843766D02*
X1008191D01*
G01X1003841Y837074D02*
X1008191D01*
G01X1003841Y867192D02*
X1008191D01*
G01X1003841Y857152D02*
X1008191D01*
G01X1003841Y880577D02*
X1008191D01*
G01X1003841Y873885D02*
X1008191D01*
G01X1003841Y893963D02*
X1008191D01*
G01X1003841Y887270D02*
X1008191D01*
G01X1003841Y917389D02*
X1008191D01*
G01X1003841Y910696D02*
X1008191D01*
G01X1003841Y904003D02*
X1008191D01*
G01X1003841Y930774D02*
X1008191D01*
G01X1003841Y924081D02*
X1008191D01*
G01X1003841Y947507D02*
X1008191D01*
G01X1003841Y940814D02*
X1008191D01*
G01X1003841Y964239D02*
X1008191D01*
G01X1003841Y954200D02*
X1008191D01*
G01X1003841Y977625D02*
X1008191D01*
G01X1003841Y970932D02*
X1008191D01*
G01X1003841Y991011D02*
X1008191D01*
G01X1003841Y984318D02*
X1008191D01*
G01X1003841Y1031168D02*
X1008191D01*
G01X1003841Y1024475D02*
X1008191D01*
G01X1003841Y1017782D02*
X1008191D01*
G01X1003841Y1044554D02*
X1008191D01*
G01X1003841Y1037861D02*
X1008191D01*
G01X1003841Y1057940D02*
X1008191D01*
G01X1003841Y1051247D02*
X1008191D01*
G01X1003841Y1078018D02*
X1008191D01*
G01X1003841Y1071326D02*
X1008191D01*
G01X1003841Y1064633D02*
X1008191D01*
G01X1003841Y1094751D02*
X1008191D01*
G01X1003841Y1088058D02*
X1008191D01*
G01X1003841Y1108137D02*
X1008191D01*
G01X1003841Y1101444D02*
X1008191D01*
G01X1003841Y1124869D02*
X1008191D01*
G01X1003841Y1114829D02*
X1008191D01*
G01X1003841Y1144948D02*
X1008191D01*
G01X1003841Y1138255D02*
X1008191D01*
G01X1003841Y1131562D02*
X1008191D01*
G01X1003841Y1151641D02*
X1008191D01*
G01X1003841Y1175066D02*
X1008191D01*
G01X1003841Y1168373D02*
X1008191D01*
G01X1003841Y1161680D02*
X1008191D01*
G01X1003841Y1188452D02*
X1008191D01*
G01X1003841Y1181759D02*
X1008191D01*
G01X1003841Y1205184D02*
X1008191D01*
G01X1003841Y1198491D02*
X1008191D01*
G01X1003841Y1225263D02*
X1008191D01*
G01X1003841Y1218570D02*
X1008191D01*
G01X1003841Y1211877D02*
X1008191D01*
G01X1003841Y1241995D02*
X1008191D01*
G01X1003841Y1235302D02*
X1008191D01*
G01X1003841Y1248688D02*
X1008191D01*
G01X1003831Y1259077D02*
X1007841D01*
X1008191Y1258727D01*
G01X1008129Y150948D02*
X1009735Y152554D01*
Y153868D01*
G01D02*
X1009827Y153960D01*
X1011969D01*
X1011975Y153966D01*
X1014608D01*
X1014700Y153874D01*
X1015275D01*
G01X1021695Y364518D02*
X1020399Y363222D01*
X1018045D01*
G01X1018194Y512574D02*
Y517728D01*
G01X1018092Y520212D02*
X1018194Y520110D01*
Y517728D01*
G01X1024333Y766798D02*
X1019983D01*
G01X1008191Y770144D02*
X1012541D01*
G01X1024333Y780184D02*
X1019983D01*
G01X1024333Y773491D02*
X1019983D01*
G01X1008191Y783530D02*
X1012541D01*
G01X1008191Y776837D02*
X1012541D01*
G01X1024333Y803609D02*
X1019983D01*
G01X1024333Y796916D02*
X1019983D01*
G01X1024333Y790223D02*
X1019983D01*
G01X1008191Y800263D02*
X1012541D01*
G01X1008191Y793570D02*
X1012541D01*
G01X1024333Y816995D02*
X1019983D01*
G01X1024333Y810302D02*
X1019983D01*
G01X1008191Y813648D02*
X1012541D01*
G01X1008191Y806955D02*
X1012541D01*
G01X1024333Y833727D02*
X1019983D01*
G01X1024333Y827034D02*
X1019983D01*
G01X1008191Y830381D02*
X1012541D01*
G01X1008191Y820341D02*
X1012541D01*
G01X1024333Y847113D02*
X1019983D01*
G01X1024333Y840420D02*
X1019983D01*
G01X1008191Y850459D02*
X1012541D01*
G01X1008191Y843766D02*
X1012541D01*
G01X1008191Y837074D02*
X1012541D01*
G01X1024333Y863845D02*
X1019983D01*
G01X1024333Y853806D02*
X1019983D01*
G01X1008191Y867192D02*
X1012541D01*
G01X1008191Y857152D02*
X1012541D01*
G01X1024333Y883924D02*
X1019983D01*
G01X1024333Y877231D02*
X1019983D01*
G01X1024333Y870538D02*
X1019983D01*
G01X1008191Y880577D02*
X1012541D01*
G01X1008191Y873885D02*
X1012541D01*
G01X1024333Y900656D02*
X1019983D01*
G01X1024333Y890617D02*
X1019983D01*
G01X1008191Y893963D02*
X1012541D01*
G01X1008191Y887270D02*
X1012541D01*
G01X1024333Y914042D02*
X1019983D01*
G01X1024333Y907349D02*
X1019983D01*
G01X1008191Y917389D02*
X1012541D01*
G01X1008191Y910696D02*
X1012541D01*
G01X1008191Y904003D02*
X1012541D01*
G01X1019983Y927428D02*
X1024333D01*
G01Y920735D02*
X1019983D01*
G01X1008191Y930774D02*
X1012541D01*
G01X1008191Y924081D02*
X1012541D01*
G01X1024333Y944160D02*
X1019983D01*
G01X1024333Y937467D02*
X1019983D01*
G01X1008191Y947507D02*
X1012541D01*
G01X1008191Y940814D02*
X1012541D01*
G01X1024333Y960892D02*
X1019983D01*
G01X1024333Y950853D02*
X1019983D01*
G01X1008191Y964239D02*
X1012541D01*
G01X1008191Y954200D02*
X1012541D01*
G01X1024333Y980971D02*
X1019983D01*
G01X1024333Y974278D02*
X1019983D01*
G01X1024333Y967585D02*
X1019983D01*
G01X1008191Y977625D02*
X1012541D01*
G01X1008191Y970932D02*
X1012541D01*
G01X1024333Y987664D02*
X1019983D01*
G01X1008191Y991011D02*
X1012541D01*
G01X1008191Y984318D02*
X1012541D01*
G01X1024333Y1027822D02*
X1019983D01*
G01X1024333Y1017782D02*
X1019983D01*
G01X1008191Y1031168D02*
X1012541D01*
G01X1008191Y1024475D02*
X1012541D01*
G01X1008191Y1017782D02*
X1012541D01*
G01X1024333Y1041207D02*
X1019983D01*
G01X1024333Y1034515D02*
X1019983D01*
G01X1008191Y1044554D02*
X1012541D01*
G01X1008191Y1037861D02*
X1012541D01*
G01X1024333Y1061286D02*
X1019983D01*
G01X1024333Y1054593D02*
X1019983D01*
G01X1008191Y1057940D02*
X1012541D01*
G01X1008191Y1051247D02*
X1012541D01*
G01X1024333Y1047900D02*
X1019983D01*
G01X1024333Y1067979D02*
X1019983D01*
G01Y1074672D02*
X1024333D01*
G01X1008191Y1078018D02*
X1012541D01*
G01X1008191Y1071326D02*
X1012541D01*
G01X1008191Y1064633D02*
X1012541D01*
G01X1024333Y1091404D02*
X1019983D01*
G01X1024333Y1084711D02*
X1019983D01*
G01X1008191Y1094751D02*
X1012541D01*
G01X1008191Y1088058D02*
X1012541D01*
G01X1024333Y1111483D02*
X1019983D01*
G01X1024333Y1104790D02*
X1019983D01*
G01X1024333Y1098097D02*
X1019983D01*
G01X1008191Y1108137D02*
X1012541D01*
G01X1008191Y1101444D02*
X1012541D01*
G01X1024333Y1128215D02*
X1019983D01*
G01X1024333Y1121522D02*
X1019983D01*
G01X1008191Y1124869D02*
X1012541D01*
G01X1008191Y1114829D02*
X1012541D01*
G01X1024333Y1141601D02*
X1019983D01*
G01X1024333Y1134908D02*
X1019983D01*
G01X1008191Y1144948D02*
X1012541D01*
G01X1008191Y1138255D02*
X1012541D01*
G01X1008191Y1131562D02*
X1012541D01*
G01X1024333Y1158333D02*
X1019983D01*
G01X1024333Y1148294D02*
X1019983D01*
G01X1008191Y1151641D02*
X1012541D01*
G01X1024333Y1171719D02*
X1019983D01*
G01X1024333Y1165026D02*
X1019983D01*
G01X1008191Y1175066D02*
X1012541D01*
G01X1008191Y1168373D02*
X1012541D01*
G01X1008191Y1161680D02*
X1012541D01*
G01X1024333Y1185105D02*
X1019983D01*
G01X1024333Y1178412D02*
X1019983D01*
G01X1008191Y1188452D02*
X1012541D01*
G01X1008191Y1181759D02*
X1012541D01*
G01X1024333Y1208530D02*
X1019983D01*
G01X1024333Y1201837D02*
X1019983D01*
G01X1024333Y1195144D02*
X1019983D01*
G01X1008191Y1205184D02*
X1012541D01*
G01X1008191Y1198491D02*
X1012541D01*
G01X1024333Y1221916D02*
X1019983D01*
G01X1024333Y1215223D02*
X1019983D01*
G01X1008191Y1225263D02*
X1012541D01*
G01X1008191Y1218570D02*
X1012541D01*
G01X1008191Y1211877D02*
X1012541D01*
G01X1024333Y1238648D02*
X1019983D01*
G01X1024333Y1231955D02*
X1019983D01*
G01X1008191Y1241995D02*
X1012541D01*
G01X1008191Y1235302D02*
X1012541D01*
G01X1019983Y1245341D02*
X1024333D01*
G01X1008191Y1248688D02*
X1012541D01*
G01X1034258Y264130D02*
X1031702D01*
G01X1029922Y362594D02*
X1029917Y362589D01*
X1025958D01*
G01X1033285Y353627D02*
X1029922Y356990D01*
Y362594D01*
G01X1033541Y770144D02*
X1037891D01*
G01D02*
X1042241D01*
G01X1028683Y766798D02*
X1024333D01*
G01X1033541Y783530D02*
X1037891D01*
G01D02*
X1042241D01*
G01X1033541Y776837D02*
X1037891D01*
G01D02*
X1042241D01*
G01X1028683Y780184D02*
X1024333D01*
G01X1028683Y773491D02*
X1024333D01*
G01X1033541Y800263D02*
X1037891D01*
G01D02*
X1042241D01*
G01X1033541Y793570D02*
X1037891D01*
G01D02*
X1042241D01*
G01X1028683Y803609D02*
X1024333D01*
G01X1028683Y796916D02*
X1024333D01*
G01X1028683Y790223D02*
X1024333D01*
G01X1033541Y813648D02*
X1037891D01*
G01D02*
X1042241D01*
G01X1033541Y806955D02*
X1037891D01*
G01D02*
X1042241D01*
G01X1028683Y816995D02*
X1024333D01*
G01X1028683Y810302D02*
X1024333D01*
G01X1033541Y830381D02*
X1037891D01*
G01D02*
X1042241D01*
G01X1033541Y820341D02*
X1037891D01*
G01D02*
X1042241D01*
G01X1028683Y833727D02*
X1024333D01*
G01X1028683Y827034D02*
X1024333D01*
G01X1033541Y850459D02*
X1037891D01*
G01D02*
X1042241D01*
G01X1033541Y843766D02*
X1037891D01*
G01D02*
X1042241D01*
G01X1033541Y837074D02*
X1037891D01*
G01D02*
X1042241D01*
G01X1028683Y847113D02*
X1024333D01*
G01X1028683Y840420D02*
X1024333D01*
G01X1033541Y867192D02*
X1037891D01*
G01D02*
X1042241D01*
G01X1033541Y857152D02*
X1037891D01*
G01D02*
X1042241D01*
G01X1028683Y863845D02*
X1024333D01*
G01X1028683Y853806D02*
X1024333D01*
G01X1033541Y880577D02*
X1037891D01*
G01D02*
X1042241D01*
G01X1033541Y873885D02*
X1037891D01*
G01D02*
X1042241D01*
G01X1028683Y883924D02*
X1024333D01*
G01X1028683Y877231D02*
X1024333D01*
G01X1028683Y870538D02*
X1024333D01*
G01X1033541Y893963D02*
X1037891D01*
G01D02*
X1042241D01*
G01X1033541Y887270D02*
X1037891D01*
G01D02*
X1042241D01*
G01X1028683Y900656D02*
X1024333D01*
G01X1028683Y890617D02*
X1024333D01*
G01X1033541Y917389D02*
X1037891D01*
G01D02*
X1042241D01*
G01X1033541Y910696D02*
X1037891D01*
G01D02*
X1042241D01*
G01X1033541Y904003D02*
X1037891D01*
G01D02*
X1042241D01*
G01X1028683Y914042D02*
X1024333D01*
G01X1028683Y907349D02*
X1024333D01*
G01X1033541Y930774D02*
X1037891D01*
G01D02*
X1042241D01*
G01X1033541Y924081D02*
X1037891D01*
G01D02*
X1042241D01*
G01X1024333Y927428D02*
X1028683D01*
G01Y920735D02*
X1024333D01*
G01X1033541Y947507D02*
X1037891D01*
G01D02*
X1042241D01*
G01X1033541Y940814D02*
X1037891D01*
G01D02*
X1042241D01*
G01X1028683Y944160D02*
X1024333D01*
G01X1028683Y937467D02*
X1024333D01*
G01X1033541Y964239D02*
X1037891D01*
G01D02*
X1042241D01*
G01X1033541Y954200D02*
X1037891D01*
G01D02*
X1042241D01*
G01X1028683Y960892D02*
X1024333D01*
G01X1028683Y950853D02*
X1024333D01*
G01X1033541Y977625D02*
X1037891D01*
G01D02*
X1042241D01*
G01X1033541Y970932D02*
X1037891D01*
G01D02*
X1042241D01*
G01X1028683Y980971D02*
X1024333D01*
G01X1028683Y974278D02*
X1024333D01*
G01X1028683Y967585D02*
X1024333D01*
G01X1033541Y991011D02*
X1037891D01*
G01D02*
X1042241D01*
G01X1033541Y984318D02*
X1037891D01*
G01D02*
X1042241D01*
G01X1028683Y987664D02*
X1024333D01*
G01X1037891Y1031168D02*
X1042241D01*
G01X1033541D02*
X1037891D01*
G01Y1017782D02*
X1042241D01*
G01X1033541D02*
X1037891D01*
G01Y1024475D02*
X1042241D01*
G01X1033541D02*
X1037891D01*
G01X1028683Y1027822D02*
X1024333D01*
G01X1028683Y1017782D02*
X1024333D01*
G01X1037891Y1044554D02*
X1042241D01*
G01X1033541D02*
X1037891D01*
G01Y1037861D02*
X1042241D01*
G01X1033541D02*
X1037891D01*
G01X1028683Y1041207D02*
X1024333D01*
G01X1028683Y1034515D02*
X1024333D01*
G01X1037891Y1057940D02*
X1042241D01*
G01X1033541D02*
X1037891D01*
G01Y1051247D02*
X1042241D01*
G01X1033541D02*
X1037891D01*
G01X1028683Y1061286D02*
X1024333D01*
G01X1028683Y1054593D02*
X1024333D01*
G01X1028683Y1047900D02*
X1024333D01*
G01X1037891Y1078018D02*
X1042241D01*
G01X1033541D02*
X1037891D01*
G01Y1071326D02*
X1042241D01*
G01X1033541D02*
X1037891D01*
G01Y1064633D02*
X1042241D01*
G01X1033541D02*
X1037891D01*
G01X1028683Y1067979D02*
X1024333D01*
G01Y1074672D02*
X1028683D01*
G01X1037891Y1094751D02*
X1042241D01*
G01X1033541D02*
X1037891D01*
G01Y1088058D02*
X1042241D01*
G01X1033541D02*
X1037891D01*
G01X1028683Y1091404D02*
X1024333D01*
G01X1028683Y1084711D02*
X1024333D01*
G01X1037891Y1108137D02*
X1042241D01*
G01X1033541D02*
X1037891D01*
G01Y1101444D02*
X1042241D01*
G01X1033541D02*
X1037891D01*
G01X1028683Y1111483D02*
X1024333D01*
G01X1028683Y1104790D02*
X1024333D01*
G01X1028683Y1098097D02*
X1024333D01*
G01X1033541Y1114829D02*
X1037891D01*
G01D02*
X1042241D01*
G01X1037891Y1124869D02*
X1042241D01*
G01X1033541D02*
X1037891D01*
G01X1028683Y1128215D02*
X1024333D01*
G01X1028683Y1121522D02*
X1024333D01*
G01X1037891Y1144948D02*
X1042241D01*
G01X1033541D02*
X1037891D01*
G01Y1138255D02*
X1042241D01*
G01X1033541D02*
X1037891D01*
G01Y1131562D02*
X1042241D01*
G01X1033541D02*
X1037891D01*
G01X1028683Y1141601D02*
X1024333D01*
G01X1028683Y1134908D02*
X1024333D01*
G01X1037891Y1151641D02*
X1042241D01*
G01X1033541D02*
X1037891D01*
G01X1028683Y1158333D02*
X1024333D01*
G01X1028683Y1148294D02*
X1024333D01*
G01X1037891Y1175066D02*
X1042241D01*
G01X1033541D02*
X1037891D01*
G01Y1168373D02*
X1042241D01*
G01X1033541D02*
X1037891D01*
G01X1033541Y1161680D02*
X1037891D01*
G01D02*
X1042241D01*
G01X1028683Y1171719D02*
X1024333D01*
G01X1028683Y1165026D02*
X1024333D01*
G01X1037891Y1188452D02*
X1042241D01*
G01X1033541D02*
X1037891D01*
G01Y1181759D02*
X1042241D01*
G01X1033541D02*
X1037891D01*
G01X1028683Y1185105D02*
X1024333D01*
G01X1028683Y1178412D02*
X1024333D01*
G01X1037891Y1205184D02*
X1042241D01*
G01X1033541D02*
X1037891D01*
G01Y1198491D02*
X1042241D01*
G01X1033541D02*
X1037891D01*
G01X1028683Y1208530D02*
X1024333D01*
G01X1028683Y1201837D02*
X1024333D01*
G01X1028683Y1195144D02*
X1024333D01*
G01X1037891Y1225263D02*
X1042241D01*
G01X1033541D02*
X1037891D01*
G01Y1218570D02*
X1042241D01*
G01X1033541D02*
X1037891D01*
G01Y1211877D02*
X1042241D01*
G01X1033541D02*
X1037891D01*
G01X1028683Y1221916D02*
X1024333D01*
G01X1028683Y1215223D02*
X1024333D01*
G01X1037891Y1241995D02*
X1042241D01*
G01X1033541D02*
X1037891D01*
G01Y1235302D02*
X1042241D01*
G01X1033541D02*
X1037891D01*
G01X1028683Y1238648D02*
X1024333D01*
G01X1028683Y1231955D02*
X1024333D01*
G01X1037891Y1248688D02*
X1042241D01*
G01X1033541D02*
X1037891D01*
G01X1024333Y1245341D02*
X1028683D01*
G01X1037891Y1258727D02*
X1033541D01*
G01X1043424Y286073D02*
X1040924D01*
G01X1054820Y370162D02*
X1052705Y368047D01*
Y366270D01*
G01X1041444Y506504D02*
X1042413Y505535D01*
Y502161D01*
G01X1041444Y509606D02*
Y506504D01*
G01Y509606D02*
X1041628Y509790D01*
X1049186D01*
G01X1054033Y766798D02*
X1058383D01*
G01X1049683D02*
X1054033D01*
G01X1049683Y780184D02*
X1054033D01*
G01D02*
X1058383D01*
G01X1049683Y773491D02*
X1054033D01*
G01D02*
X1058383D01*
G01X1049683Y803609D02*
X1054033D01*
G01D02*
X1058383D01*
G01X1049683Y796916D02*
X1054033D01*
G01D02*
X1058383D01*
G01X1049683Y790223D02*
X1054033D01*
G01D02*
X1058383D01*
G01X1049683Y816995D02*
X1054033D01*
G01D02*
X1058383D01*
G01X1049683Y810302D02*
X1054033D01*
G01D02*
X1058383D01*
G01X1049683Y833727D02*
X1054033D01*
G01D02*
X1058383D01*
G01X1049683Y827034D02*
X1054033D01*
G01D02*
X1058383D01*
G01X1049683Y847113D02*
X1054033D01*
G01D02*
X1058383D01*
G01X1049683Y840420D02*
X1054033D01*
G01D02*
X1058383D01*
G01X1049683Y863845D02*
X1054033D01*
G01D02*
X1058383D01*
G01X1049683Y853806D02*
X1054033D01*
G01D02*
X1058383D01*
G01X1049683Y883924D02*
X1054033D01*
G01D02*
X1058383D01*
G01X1049683Y877231D02*
X1054033D01*
G01D02*
X1058383D01*
G01X1049683Y870538D02*
X1054033D01*
G01D02*
X1058383D01*
G01X1049683Y900656D02*
X1054033D01*
G01D02*
X1058383D01*
G01X1049683Y890617D02*
X1054033D01*
G01D02*
X1058383D01*
G01X1049683Y914042D02*
X1054033D01*
G01D02*
X1058383D01*
G01X1049683Y907349D02*
X1054033D01*
G01D02*
X1058383D01*
G01X1049683Y927428D02*
X1054033D01*
G01D02*
X1058383D01*
G01X1049683Y920735D02*
X1054033D01*
G01D02*
X1058383D01*
G01X1049683Y944160D02*
X1054033D01*
G01D02*
X1058383D01*
G01X1049683Y937467D02*
X1054033D01*
G01D02*
X1058383D01*
G01X1049683Y960892D02*
X1054033D01*
G01D02*
X1058383D01*
G01X1049683Y950853D02*
X1054033D01*
G01D02*
X1058383D01*
G01X1049683Y980971D02*
X1054033D01*
G01D02*
X1058383D01*
G01X1049683Y974278D02*
X1054033D01*
G01D02*
X1058383D01*
G01X1049683Y967585D02*
X1054033D01*
G01D02*
X1058383D01*
G01X1049683Y987664D02*
X1054033D01*
G01D02*
X1058383D01*
G01X1054033Y1027822D02*
X1058383D01*
G01X1049683D02*
X1054033D01*
G01Y1017782D02*
X1058383D01*
G01X1049683D02*
X1054033D01*
G01Y1041207D02*
X1058383D01*
G01X1049683D02*
X1054033D01*
G01Y1034515D02*
X1058383D01*
G01X1049683D02*
X1054033D01*
G01Y1061286D02*
X1058383D01*
G01X1049683D02*
X1054033D01*
G01Y1054593D02*
X1058383D01*
G01X1049683D02*
X1054033D01*
G01Y1047900D02*
X1058383D01*
G01X1049683D02*
X1054033D01*
G01Y1074672D02*
X1058383D01*
G01X1049683D02*
X1054033D01*
G01Y1067979D02*
X1058383D01*
G01X1049683D02*
X1054033D01*
G01Y1091404D02*
X1058383D01*
G01X1049683D02*
X1054033D01*
G01Y1084711D02*
X1058383D01*
G01X1049683D02*
X1054033D01*
G01Y1111483D02*
X1058383D01*
G01X1049683D02*
X1054033D01*
G01Y1104790D02*
X1058383D01*
G01X1049683D02*
X1054033D01*
G01Y1098097D02*
X1058383D01*
G01X1049683D02*
X1054033D01*
G01Y1128215D02*
X1058383D01*
G01X1049683D02*
X1054033D01*
G01Y1121522D02*
X1058383D01*
G01X1049683D02*
X1054033D01*
G01Y1141601D02*
X1058383D01*
G01X1049683D02*
X1054033D01*
G01Y1134908D02*
X1058383D01*
G01X1049683D02*
X1054033D01*
G01Y1158333D02*
X1058383D01*
G01X1049683D02*
X1054033D01*
G01Y1148294D02*
X1058383D01*
G01X1049683D02*
X1054033D01*
G01Y1171719D02*
X1058383D01*
G01X1049683D02*
X1054033D01*
G01Y1165026D02*
X1058383D01*
G01X1049683D02*
X1054033D01*
G01Y1185105D02*
X1058383D01*
G01X1049683D02*
X1054033D01*
G01Y1178412D02*
X1058383D01*
G01X1049683D02*
X1054033D01*
G01Y1208530D02*
X1058383D01*
G01X1049683D02*
X1054033D01*
G01Y1201837D02*
X1058383D01*
G01X1049683D02*
X1054033D01*
G01Y1195144D02*
X1058383D01*
G01X1049683D02*
X1054033D01*
G01Y1215223D02*
X1058383D01*
G01X1049683D02*
X1054033D01*
G01Y1221916D02*
X1058383D01*
G01X1049683D02*
X1054033D01*
G01Y1238648D02*
X1058383D01*
G01X1049683D02*
X1054033D01*
G01Y1231955D02*
X1058383D01*
G01X1049683D02*
X1054033D01*
G01Y1245341D02*
X1058383D01*
G01X1049683D02*
X1054033D01*
G01X1073589Y509645D02*
X1073444Y509790D01*
X1066312D01*
G01X1071941Y770144D02*
X1067591D01*
G01D02*
X1063241D01*
G01X1071941Y783530D02*
X1067591D01*
G01D02*
X1063241D01*
G01X1071941Y776837D02*
X1067591D01*
G01D02*
X1063241D01*
G01X1071941Y800263D02*
X1067591D01*
G01D02*
X1063241D01*
G01X1071941Y793570D02*
X1067591D01*
G01D02*
X1063241D01*
G01X1071941Y813648D02*
X1067591D01*
G01D02*
X1063241D01*
G01X1071941Y806955D02*
X1067591D01*
G01D02*
X1063241D01*
G01X1071941Y830381D02*
X1067591D01*
G01D02*
X1063241D01*
G01X1071941Y820341D02*
X1067591D01*
G01D02*
X1063241D01*
G01X1071941Y850459D02*
X1067591D01*
G01D02*
X1063241D01*
G01X1071941Y843766D02*
X1067591D01*
G01D02*
X1063241D01*
G01X1071941Y837074D02*
X1067591D01*
G01D02*
X1063241D01*
G01X1071941Y867192D02*
X1067591D01*
G01D02*
X1063241D01*
G01X1071941Y857152D02*
X1067591D01*
G01D02*
X1063241D01*
G01X1071941Y880577D02*
X1067591D01*
G01D02*
X1063241D01*
G01X1071941Y873885D02*
X1067591D01*
G01D02*
X1063241D01*
G01Y893963D02*
X1067591D01*
G01D02*
X1071941D01*
G01X1063241Y887270D02*
X1067591D01*
G01D02*
X1071941D01*
G01Y917389D02*
X1067591D01*
G01D02*
X1063241D01*
G01X1071941Y910696D02*
X1067591D01*
G01D02*
X1063241D01*
G01X1071941Y904003D02*
X1067591D01*
G01D02*
X1063241D01*
G01X1071941Y930774D02*
X1067591D01*
G01D02*
X1063241D01*
G01X1071941Y924081D02*
X1067591D01*
G01D02*
X1063241D01*
G01X1071941Y947507D02*
X1067591D01*
G01D02*
X1063241D01*
G01X1071941Y940814D02*
X1067591D01*
G01D02*
X1063241D01*
G01X1071941Y964239D02*
X1067591D01*
G01D02*
X1063241D01*
G01X1071941Y954200D02*
X1067591D01*
G01D02*
X1063241D01*
G01X1071941Y977625D02*
X1067591D01*
G01D02*
X1063241D01*
G01X1071941Y970932D02*
X1067591D01*
G01D02*
X1063241D01*
G01X1071941Y991011D02*
X1067591D01*
G01D02*
X1063241D01*
G01X1071941Y984318D02*
X1067591D01*
G01D02*
X1063241D01*
G01X1067591Y1031168D02*
X1063241D01*
G01X1071941D02*
X1067591D01*
G01Y1024475D02*
X1063241D01*
G01X1071941D02*
X1067591D01*
G01Y1017782D02*
X1071941D01*
G01X1063241D02*
X1067591D01*
G01Y1044554D02*
X1063241D01*
G01X1071941D02*
X1067591D01*
G01Y1037861D02*
X1063241D01*
G01X1071941D02*
X1067591D01*
G01Y1057940D02*
X1063241D01*
G01X1071941D02*
X1067591D01*
G01Y1051247D02*
X1063241D01*
G01X1071941D02*
X1067591D01*
G01Y1078018D02*
X1063241D01*
G01X1071941D02*
X1067591D01*
G01X1071941Y1071326D02*
X1067591D01*
G01D02*
X1063241D01*
G01X1067591Y1064633D02*
X1063241D01*
G01X1071941D02*
X1067591D01*
G01Y1094751D02*
X1063241D01*
G01X1071941D02*
X1067591D01*
G01Y1088058D02*
X1063241D01*
G01X1071941D02*
X1067591D01*
G01Y1108137D02*
X1071941D01*
G01X1063241D02*
X1067591D01*
G01Y1101444D02*
X1063241D01*
G01X1071941D02*
X1067591D01*
G01Y1124869D02*
X1063241D01*
G01X1071941D02*
X1067591D01*
G01Y1114829D02*
X1071941D01*
G01X1063241D02*
X1067591D01*
G01Y1144948D02*
X1063241D01*
G01X1071941D02*
X1067591D01*
G01Y1138255D02*
X1063241D01*
G01X1071941D02*
X1067591D01*
G01Y1131562D02*
X1063241D01*
G01X1071941D02*
X1067591D01*
G01Y1151641D02*
X1063241D01*
G01X1071941D02*
X1067591D01*
G01Y1175066D02*
X1063241D01*
G01X1071941D02*
X1067591D01*
G01Y1168373D02*
X1063241D01*
G01X1071941D02*
X1067591D01*
G01Y1161680D02*
X1063241D01*
G01X1071941D02*
X1067591D01*
G01Y1188452D02*
X1063241D01*
G01X1071941D02*
X1067591D01*
G01Y1181759D02*
X1063241D01*
G01X1071941D02*
X1067591D01*
G01Y1205184D02*
X1063241D01*
G01X1071941D02*
X1067591D01*
G01Y1198491D02*
X1063241D01*
G01X1071941D02*
X1067591D01*
G01Y1225263D02*
X1063241D01*
G01X1071941D02*
X1067591D01*
G01Y1218570D02*
X1063241D01*
G01X1071941D02*
X1067591D01*
G01Y1211877D02*
X1063241D01*
G01X1071941D02*
X1067591D01*
G01Y1241995D02*
X1063241D01*
G01X1071941D02*
X1067591D01*
G01Y1235302D02*
X1063241D01*
G01X1071941D02*
X1067591D01*
G01Y1248688D02*
X1071941D01*
G01X1063241D02*
X1067591D01*
G01Y1258727D02*
X1063241D01*
G01X1079114Y78553D02*
Y75775D01*
G01X1072730Y386723D02*
X1075462D01*
G01X1073589Y506461D02*
Y509645D01*
G01X1083733Y766798D02*
X1079383D01*
G01X1088083D02*
X1083733D01*
G01X1088083Y780184D02*
X1083733D01*
G01D02*
X1079383D01*
G01X1088083Y773491D02*
X1083733D01*
G01D02*
X1079383D01*
G01X1088083Y803609D02*
X1083733D01*
G01D02*
X1079383D01*
G01X1088083Y796916D02*
X1083733D01*
G01D02*
X1079383D01*
G01X1088083Y790223D02*
X1083733D01*
G01D02*
X1079383D01*
G01X1088083Y816995D02*
X1083733D01*
G01D02*
X1079383D01*
G01X1088083Y810302D02*
X1083733D01*
G01D02*
X1079383D01*
G01X1088083Y833727D02*
X1083733D01*
G01D02*
X1079383D01*
G01Y827034D02*
X1083733D01*
G01D02*
X1088083D01*
G01Y847113D02*
X1083733D01*
G01D02*
X1079383D01*
G01X1088083Y840420D02*
X1083733D01*
G01D02*
X1079383D01*
G01X1088083Y863845D02*
X1083733D01*
G01D02*
X1079383D01*
G01X1088083Y853806D02*
X1083733D01*
G01D02*
X1079383D01*
G01X1088083Y883924D02*
X1083733D01*
G01D02*
X1079383D01*
G01Y877231D02*
X1083733D01*
G01D02*
X1088083D01*
G01X1079383Y870538D02*
X1083733D01*
G01D02*
X1088083D01*
G01Y900656D02*
X1083733D01*
G01D02*
X1079383D01*
G01X1088083Y890617D02*
X1083733D01*
G01D02*
X1079383D01*
G01X1088083Y914042D02*
X1083733D01*
G01D02*
X1079383D01*
G01Y907349D02*
X1083733D01*
G01D02*
X1088083D01*
G01Y927428D02*
X1083733D01*
G01D02*
X1079383D01*
G01X1088083Y920735D02*
X1083733D01*
G01D02*
X1079383D01*
G01Y944160D02*
X1083733D01*
G01D02*
X1088083D01*
G01Y937467D02*
X1083733D01*
G01D02*
X1079383D01*
G01X1088083Y960892D02*
X1083733D01*
G01D02*
X1079383D01*
G01Y950853D02*
X1083733D01*
G01D02*
X1088083D01*
G01X1079383Y980971D02*
X1083733D01*
G01D02*
X1088083D01*
G01Y974278D02*
X1083733D01*
G01D02*
X1079383D01*
G01X1088083Y967585D02*
X1083733D01*
G01D02*
X1079383D01*
G01X1088083Y987664D02*
X1083733D01*
G01D02*
X1079383D01*
G01X1083733Y1027822D02*
X1079383D01*
G01X1088083D02*
X1083733D01*
G01Y1017782D02*
X1079383D01*
G01X1088083D02*
X1083733D01*
G01Y1041207D02*
X1079383D01*
G01X1088083D02*
X1083733D01*
G01Y1034515D02*
X1079383D01*
G01X1088083D02*
X1083733D01*
G01Y1061286D02*
X1079383D01*
G01X1088083D02*
X1083733D01*
G01Y1054593D02*
X1079383D01*
G01X1088083D02*
X1083733D01*
G01Y1047900D02*
X1079383D01*
G01X1088083D02*
X1083733D01*
G01Y1074672D02*
X1079383D01*
G01X1088083D02*
X1083733D01*
G01Y1067979D02*
X1079383D01*
G01X1088083D02*
X1083733D01*
G01Y1091404D02*
X1079383D01*
G01X1088083D02*
X1083733D01*
G01Y1084711D02*
X1079383D01*
G01X1088083D02*
X1083733D01*
G01Y1111483D02*
X1079383D01*
G01X1088083D02*
X1083733D01*
G01Y1104790D02*
X1079383D01*
G01X1088083D02*
X1083733D01*
G01Y1098097D02*
X1079383D01*
G01X1088083D02*
X1083733D01*
G01Y1128215D02*
X1079383D01*
G01X1088083D02*
X1083733D01*
G01Y1121522D02*
X1079383D01*
G01X1088083D02*
X1083733D01*
G01Y1141601D02*
X1079383D01*
G01X1088083D02*
X1083733D01*
G01Y1134908D02*
X1079383D01*
G01X1088083D02*
X1083733D01*
G01Y1158333D02*
X1079383D01*
G01X1088083D02*
X1083733D01*
G01Y1148294D02*
X1079383D01*
G01X1088083D02*
X1083733D01*
G01Y1171719D02*
X1079383D01*
G01X1088083D02*
X1083733D01*
G01Y1165026D02*
X1079383D01*
G01X1088083D02*
X1083733D01*
G01Y1185105D02*
X1079383D01*
G01X1088083D02*
X1083733D01*
G01Y1178412D02*
X1079383D01*
G01X1088083D02*
X1083733D01*
G01Y1208530D02*
X1079383D01*
G01X1088083D02*
X1083733D01*
G01Y1201837D02*
X1079383D01*
G01X1088083D02*
X1083733D01*
G01Y1195144D02*
X1088083D01*
G01X1079383D02*
X1083733D01*
G01Y1221916D02*
X1079383D01*
G01X1088083D02*
X1083733D01*
G01Y1215223D02*
X1079383D01*
G01X1088083D02*
X1083733D01*
G01Y1238648D02*
X1079383D01*
G01X1088083D02*
X1083733D01*
G01Y1231955D02*
X1079383D01*
G01X1088083D02*
X1083733D01*
G01Y1245341D02*
X1079383D01*
G01X1088083D02*
X1083733D01*
G01X1087296Y69602D02*
X1087316Y69622D01*
Y71766D01*
X1088893Y73343D01*
X1092381D01*
G01X1094644Y67992D02*
X1093034Y69602D01*
X1087296D01*
G01X1094644Y67992D02*
Y65262D01*
G01D02*
Y64462D01*
X1093344Y63162D01*
X1088673D01*
G01X1110754Y60028D02*
Y65519D01*
X1106930Y69343D01*
X1101291D01*
X1100220Y70414D01*
X1097066D01*
X1094644Y67992D01*
G01X1091535Y379251D02*
X1087330D01*
G01X1091475Y374131D02*
X1087330D01*
G01X1091415Y369061D02*
X1087330D01*
G01X1101641Y770144D02*
X1097291D01*
G01D02*
X1092941D01*
G01X1101641Y783530D02*
X1097291D01*
G01D02*
X1092941D01*
G01X1101641Y776837D02*
X1097291D01*
G01D02*
X1092941D01*
G01Y800263D02*
X1097291D01*
G01D02*
X1101641D01*
G01X1092941Y793570D02*
X1097291D01*
G01D02*
X1101641D01*
G01X1092941Y813648D02*
X1097291D01*
G01D02*
X1101641D01*
G01X1092941Y806955D02*
X1097291D01*
G01D02*
X1101641D01*
G01X1092941Y830381D02*
X1097291D01*
G01D02*
X1101641D01*
G01X1092941Y820341D02*
X1097291D01*
G01D02*
X1101641D01*
G01X1092941Y850459D02*
X1097291D01*
G01D02*
X1101641D01*
G01X1092941Y843766D02*
X1097291D01*
G01D02*
X1101641D01*
G01X1092941Y837074D02*
X1097291D01*
G01D02*
X1101641D01*
G01X1092941Y867192D02*
X1097291D01*
G01D02*
X1101641D01*
G01X1092941Y857152D02*
X1097291D01*
G01D02*
X1101641D01*
G01X1092941Y880577D02*
X1097291D01*
G01D02*
X1101641D01*
G01X1092941Y873885D02*
X1097291D01*
G01D02*
X1101641D01*
G01X1092941Y893963D02*
X1097291D01*
G01D02*
X1101641D01*
G01X1092941Y887270D02*
X1097291D01*
G01D02*
X1101641D01*
G01X1092941Y917389D02*
X1097291D01*
G01D02*
X1101641D01*
G01X1092941Y910696D02*
X1097291D01*
G01D02*
X1101641D01*
G01X1092941Y904003D02*
X1097291D01*
G01D02*
X1101641D01*
G01X1092941Y930774D02*
X1097291D01*
G01D02*
X1101641D01*
G01X1092941Y924081D02*
X1097291D01*
G01D02*
X1101641D01*
G01X1092941Y947507D02*
X1097291D01*
G01D02*
X1101641D01*
G01X1092941Y940814D02*
X1097291D01*
G01D02*
X1101641D01*
G01X1092941Y964239D02*
X1097291D01*
G01D02*
X1101641D01*
G01X1092941Y954200D02*
X1097291D01*
G01D02*
X1101641D01*
G01X1092941Y977625D02*
X1097291D01*
G01D02*
X1101641D01*
G01X1092941Y970932D02*
X1097291D01*
G01D02*
X1101641D01*
G01X1092941Y991011D02*
X1097291D01*
G01D02*
X1101641D01*
G01X1092941Y984318D02*
X1097291D01*
G01D02*
X1101641D01*
G01X1097291Y1031168D02*
X1101641D01*
G01X1092941D02*
X1097291D01*
G01Y1024475D02*
X1101641D01*
G01X1092941D02*
X1097291D01*
G01Y1017782D02*
X1101641D01*
G01X1092941D02*
X1097291D01*
G01Y1044554D02*
X1101641D01*
G01X1092941D02*
X1097291D01*
G01Y1037861D02*
X1101641D01*
G01X1092941D02*
X1097291D01*
G01Y1057940D02*
X1101641D01*
G01X1092941D02*
X1097291D01*
G01Y1051247D02*
X1101641D01*
G01X1092941D02*
X1097291D01*
G01Y1078018D02*
X1101641D01*
G01X1092941D02*
X1097291D01*
G01Y1071326D02*
X1101641D01*
G01X1092941D02*
X1097291D01*
G01Y1064633D02*
X1101641D01*
G01X1092941D02*
X1097291D01*
G01Y1094751D02*
X1101641D01*
G01X1092941D02*
X1097291D01*
G01Y1088058D02*
X1101641D01*
G01X1092941D02*
X1097291D01*
G01Y1108137D02*
X1101641D01*
G01X1092941D02*
X1097291D01*
G01Y1101444D02*
X1101641D01*
G01X1092941D02*
X1097291D01*
G01Y1124869D02*
X1101641D01*
G01X1092941D02*
X1097291D01*
G01Y1114829D02*
X1101641D01*
G01X1092941D02*
X1097291D01*
G01Y1144948D02*
X1101641D01*
G01X1092941D02*
X1097291D01*
G01Y1138255D02*
X1101641D01*
G01X1092941D02*
X1097291D01*
G01Y1131562D02*
X1101641D01*
G01X1092941D02*
X1097291D01*
G01Y1151641D02*
X1101641D01*
G01X1092941D02*
X1097291D01*
G01Y1175066D02*
X1101641D01*
G01X1092941D02*
X1097291D01*
G01Y1168373D02*
X1101641D01*
G01X1092941D02*
X1097291D01*
G01Y1161680D02*
X1092941D01*
G01X1101641D02*
X1097291D01*
G01Y1181759D02*
X1101641D01*
G01X1092941D02*
X1097291D01*
G01Y1188452D02*
X1092941D01*
G01X1101641D02*
X1097291D01*
G01Y1205184D02*
X1092941D01*
G01X1101641D02*
X1097291D01*
G01Y1198491D02*
X1092941D01*
G01X1101641D02*
X1097291D01*
G01Y1225263D02*
X1101641D01*
G01X1092941D02*
X1097291D01*
G01Y1218570D02*
X1101641D01*
G01X1092941D02*
X1097291D01*
G01Y1211877D02*
X1092941D01*
G01X1101641D02*
X1097291D01*
G01Y1241995D02*
X1101641D01*
G01X1092941D02*
X1097291D01*
G01Y1235302D02*
X1101641D01*
G01X1092941D02*
X1097291D01*
G01Y1248688D02*
X1101641D01*
G01X1092941D02*
X1097291D01*
G01Y1258727D02*
X1092941D01*
G01X1091457Y1641275D02*
X1089345D01*
X1088790Y1641830D01*
G01X1096680Y1667260D02*
X1096357Y1666937D01*
Y1661265D01*
G01X1091365Y1670963D02*
X1093478D01*
X1094225Y1671710D01*
G01X1096975Y1672030D02*
X1094545D01*
X1094225Y1671710D01*
G01X1100125Y1672030D02*
Y1670705D01*
X1096680Y1667260D01*
G01X1098455Y1675970D02*
Y1679870D01*
G01Y1675970D02*
Y1674700D01*
X1100125Y1673030D01*
Y1672030D01*
G01X1107247Y60028D02*
X1110754D01*
G01X1113594Y69862D02*
Y72803D01*
G01D02*
Y77559D01*
G01X1109083Y766798D02*
X1113433D01*
G01D02*
X1117783D01*
G01X1109083Y780184D02*
X1113433D01*
G01D02*
X1117783D01*
G01X1109083Y773491D02*
X1113433D01*
G01D02*
X1117783D01*
G01X1109083Y803609D02*
X1113433D01*
G01D02*
X1117783D01*
G01X1109083Y796916D02*
X1113433D01*
G01D02*
X1117783D01*
G01Y790223D02*
X1113433D01*
G01D02*
X1109083D01*
G01Y816995D02*
X1113433D01*
G01D02*
X1117783D01*
G01X1109083Y810302D02*
X1113433D01*
G01D02*
X1117783D01*
G01X1109083Y833727D02*
X1113433D01*
G01D02*
X1117783D01*
G01X1109083Y827034D02*
X1113433D01*
G01D02*
X1117783D01*
G01X1109083Y847113D02*
X1113433D01*
G01D02*
X1117783D01*
G01X1109083Y840420D02*
X1113433D01*
G01D02*
X1117783D01*
G01X1109083Y863845D02*
X1113433D01*
G01D02*
X1117783D01*
G01X1109083Y853806D02*
X1113433D01*
G01D02*
X1117783D01*
G01X1109083Y883924D02*
X1113433D01*
G01D02*
X1117783D01*
G01X1109083Y877231D02*
X1113433D01*
G01D02*
X1117783D01*
G01X1109083Y870538D02*
X1113433D01*
G01D02*
X1117783D01*
G01X1109083Y900656D02*
X1113433D01*
G01D02*
X1117783D01*
G01X1109083Y890617D02*
X1113433D01*
G01D02*
X1117783D01*
G01X1109083Y914042D02*
X1113433D01*
G01D02*
X1117783D01*
G01X1109083Y907349D02*
X1113433D01*
G01D02*
X1117783D01*
G01X1109083Y927428D02*
X1113433D01*
G01D02*
X1117783D01*
G01X1109083Y920735D02*
X1113433D01*
G01D02*
X1117783D01*
G01X1109083Y944160D02*
X1113433D01*
G01D02*
X1117783D01*
G01X1109083Y937467D02*
X1113433D01*
G01D02*
X1117783D01*
G01X1109083Y960892D02*
X1113433D01*
G01D02*
X1117783D01*
G01X1109083Y950853D02*
X1113433D01*
G01D02*
X1117783D01*
G01X1109083Y980971D02*
X1113433D01*
G01D02*
X1117783D01*
G01X1109083Y974278D02*
X1113433D01*
G01D02*
X1117783D01*
G01X1109083Y967585D02*
X1113433D01*
G01D02*
X1117783D01*
G01X1109083Y987664D02*
X1113433D01*
G01D02*
X1117783D01*
G01X1113433Y1027822D02*
X1117783D01*
G01X1109083D02*
X1113433D01*
G01Y1017782D02*
X1117783D01*
G01X1109083D02*
X1113433D01*
G01Y1041207D02*
X1117783D01*
G01X1109083D02*
X1113433D01*
G01Y1034515D02*
X1117783D01*
G01X1109083D02*
X1113433D01*
G01Y1061286D02*
X1117783D01*
G01X1109083D02*
X1113433D01*
G01Y1054593D02*
X1117783D01*
G01X1109083D02*
X1113433D01*
G01Y1047900D02*
X1117783D01*
G01X1109083D02*
X1113433D01*
G01Y1074672D02*
X1117783D01*
G01X1109083D02*
X1113433D01*
G01Y1067979D02*
X1117783D01*
G01X1109083D02*
X1113433D01*
G01Y1091404D02*
X1117783D01*
G01X1109083D02*
X1113433D01*
G01Y1084711D02*
X1117783D01*
G01X1109083D02*
X1113433D01*
G01Y1111483D02*
X1117783D01*
G01X1109083D02*
X1113433D01*
G01Y1104790D02*
X1117783D01*
G01X1109083D02*
X1113433D01*
G01Y1098097D02*
X1117783D01*
G01X1109083D02*
X1113433D01*
G01Y1128215D02*
X1117783D01*
G01X1109083D02*
X1113433D01*
G01Y1121522D02*
X1117783D01*
G01X1109083D02*
X1113433D01*
G01Y1141601D02*
X1117783D01*
G01X1109083D02*
X1113433D01*
G01Y1134908D02*
X1117783D01*
G01X1109083D02*
X1113433D01*
G01Y1158333D02*
X1117783D01*
G01X1109083D02*
X1113433D01*
G01Y1148294D02*
X1117783D01*
G01X1109083D02*
X1113433D01*
G01Y1171719D02*
X1117783D01*
G01X1109083D02*
X1113433D01*
G01Y1165026D02*
X1117783D01*
G01X1109083D02*
X1113433D01*
G01Y1185105D02*
X1117783D01*
G01X1109083D02*
X1113433D01*
G01Y1178412D02*
X1117783D01*
G01X1109083D02*
X1113433D01*
G01Y1208530D02*
X1117783D01*
G01X1109083D02*
X1113433D01*
G01Y1201837D02*
X1117783D01*
G01X1109083D02*
X1113433D01*
G01Y1195144D02*
X1117783D01*
G01X1109083D02*
X1113433D01*
G01Y1221916D02*
X1117783D01*
G01X1109083D02*
X1113433D01*
G01Y1215223D02*
X1117783D01*
G01X1109083D02*
X1113433D01*
G01Y1238648D02*
X1117783D01*
G01X1109083D02*
X1113433D01*
G01Y1231955D02*
X1117783D01*
G01X1109083D02*
X1113433D01*
G01Y1245341D02*
X1117783D01*
G01X1109083D02*
X1113433D01*
G01X1115853Y1429074D02*
Y1426342D01*
G01Y1432604D02*
Y1435532D01*
G01X1120432Y1628495D02*
X1117407D01*
G01X1137315Y377011D02*
X1137266Y376962D01*
X1135210D01*
X1132937Y379235D01*
X1129901D01*
G01X1122641Y770144D02*
X1126991D01*
G01D02*
X1131341D01*
G01X1122641Y783530D02*
X1126991D01*
G01D02*
X1131341D01*
G01X1122641Y776837D02*
X1126991D01*
G01D02*
X1131341D01*
G01X1122641Y800263D02*
X1126991D01*
G01D02*
X1131341D01*
G01X1122641Y793570D02*
X1126991D01*
G01D02*
X1131341D01*
G01X1122641Y813648D02*
X1126991D01*
G01D02*
X1131341D01*
G01X1122641Y806955D02*
X1126991D01*
G01D02*
X1131341D01*
G01X1122641Y830381D02*
X1126991D01*
G01D02*
X1131341D01*
G01X1122641Y820341D02*
X1126991D01*
G01D02*
X1131341D01*
G01X1122641Y850459D02*
X1126991D01*
G01D02*
X1131341D01*
G01X1122641Y843766D02*
X1126991D01*
G01D02*
X1131341D01*
G01X1122641Y837074D02*
X1126991D01*
G01D02*
X1131341D01*
G01X1122641Y867192D02*
X1126991D01*
G01D02*
X1131341D01*
G01X1122641Y857152D02*
X1126991D01*
G01D02*
X1131341D01*
G01X1122641Y880577D02*
X1126991D01*
G01D02*
X1131341D01*
G01X1122641Y873885D02*
X1126991D01*
G01D02*
X1131341D01*
G01X1122641Y893963D02*
X1126991D01*
G01D02*
X1131341D01*
G01X1122641Y887270D02*
X1126991D01*
G01D02*
X1131341D01*
G01X1122641Y917389D02*
X1126991D01*
G01D02*
X1131341D01*
G01X1122641Y910696D02*
X1126991D01*
G01D02*
X1131341D01*
G01X1122641Y904003D02*
X1126991D01*
G01D02*
X1131341D01*
G01X1122641Y930774D02*
X1126991D01*
G01D02*
X1131341D01*
G01X1122641Y924081D02*
X1126991D01*
G01D02*
X1131341D01*
G01Y947507D02*
X1126991D01*
G01D02*
X1122641D01*
G01Y940814D02*
X1126991D01*
G01D02*
X1131341D01*
G01X1122641Y964239D02*
X1126991D01*
G01D02*
X1131341D01*
G01X1122641Y954200D02*
X1126991D01*
G01D02*
X1131341D01*
G01X1122641Y977625D02*
X1126991D01*
G01D02*
X1131341D01*
G01X1122641Y970932D02*
X1126991D01*
G01D02*
X1131341D01*
G01X1122641Y991011D02*
X1126991D01*
G01D02*
X1131341D01*
G01X1122641Y984318D02*
X1126991D01*
G01D02*
X1131341D01*
G01X1122641Y1031168D02*
X1126991D01*
G01D02*
X1131341D01*
G01X1122641Y1024475D02*
X1126991D01*
G01D02*
X1131341D01*
G01X1122641Y1017782D02*
X1126991D01*
G01D02*
X1131341D01*
G01X1122641Y1044554D02*
X1126991D01*
G01D02*
X1131341D01*
G01X1122641Y1037861D02*
X1126991D01*
G01D02*
X1131341D01*
G01X1122641Y1057940D02*
X1126991D01*
G01D02*
X1131341D01*
G01X1122641Y1051247D02*
X1126991D01*
G01D02*
X1131341D01*
G01X1122641Y1078018D02*
X1126991D01*
G01D02*
X1131341D01*
G01X1122641Y1071326D02*
X1126991D01*
G01D02*
X1131341D01*
G01X1122641Y1064633D02*
X1126991D01*
G01D02*
X1131341D01*
G01X1122641Y1094751D02*
X1126991D01*
G01D02*
X1131341D01*
G01X1122641Y1088058D02*
X1126991D01*
G01D02*
X1131341D01*
G01X1122641Y1108137D02*
X1126991D01*
G01D02*
X1131341D01*
G01X1122641Y1101444D02*
X1126991D01*
G01D02*
X1131341D01*
G01X1122641Y1124869D02*
X1126991D01*
G01D02*
X1131341D01*
G01X1122641Y1114829D02*
X1126991D01*
G01D02*
X1131341D01*
G01X1122641Y1144948D02*
X1126991D01*
G01D02*
X1131341D01*
G01X1122641Y1138255D02*
X1126991D01*
G01D02*
X1131341D01*
G01X1122641Y1131562D02*
X1126991D01*
G01D02*
X1131341D01*
G01X1122641Y1151641D02*
X1126991D01*
G01D02*
X1131341D01*
G01X1122641Y1175066D02*
X1126991D01*
G01D02*
X1131341D01*
G01X1122641Y1168373D02*
X1126991D01*
G01D02*
X1131341D01*
G01X1122641Y1161680D02*
X1126991D01*
G01D02*
X1131341D01*
G01X1122641Y1188452D02*
X1126991D01*
G01D02*
X1131341D01*
G01X1122641Y1181759D02*
X1126991D01*
G01D02*
X1131341D01*
G01X1122641Y1205184D02*
X1126991D01*
G01D02*
X1131341D01*
G01X1122641Y1198491D02*
X1126991D01*
G01D02*
X1131341D01*
G01X1122641Y1225263D02*
X1126991D01*
G01D02*
X1131341D01*
G01X1122641Y1218570D02*
X1126991D01*
G01D02*
X1131341D01*
G01X1122641Y1211877D02*
X1126991D01*
G01D02*
X1131341D01*
G01X1122641Y1241995D02*
X1126991D01*
G01D02*
X1131341D01*
G01X1122641Y1235302D02*
X1126991D01*
G01D02*
X1131341D01*
G01Y1248688D02*
X1126991D01*
G01D02*
X1122641D01*
G01X1126991Y1258727D02*
X1122641D01*
G01X1136004Y1447858D02*
Y1448002D01*
X1135504Y1448502D01*
X1133444D01*
G01X1126117Y1447863D02*
Y1450504D01*
G01X1124862Y1617675D02*
Y1615010D01*
G01X1152112Y73679D02*
Y69871D01*
X1154057Y67926D01*
X1159378D01*
G01X1148795Y211231D02*
Y213731D01*
G01X1137315Y379592D02*
Y377011D01*
G01X1143133Y766798D02*
X1147483D01*
G01X1138783D02*
X1143133D01*
G01X1138783Y780184D02*
X1143133D01*
G01D02*
X1147483D01*
G01Y773491D02*
X1143133D01*
G01D02*
X1138783D01*
G01Y803609D02*
X1143133D01*
G01D02*
X1147483D01*
G01X1138783Y796916D02*
X1143133D01*
G01D02*
X1147483D01*
G01X1138783Y790223D02*
X1143133D01*
G01D02*
X1147483D01*
G01X1138783Y816995D02*
X1143133D01*
G01D02*
X1147483D01*
G01X1138783Y810302D02*
X1143133D01*
G01D02*
X1147483D01*
G01X1138783Y833727D02*
X1143133D01*
G01D02*
X1147483D01*
G01X1138783Y827034D02*
X1143133D01*
G01D02*
X1147483D01*
G01X1138783Y847113D02*
X1143133D01*
G01D02*
X1147483D01*
G01X1138783Y840420D02*
X1143133D01*
G01D02*
X1147483D01*
G01X1138783Y863845D02*
X1143133D01*
G01D02*
X1147483D01*
G01X1138783Y853806D02*
X1143133D01*
G01D02*
X1147483D01*
G01X1138783Y883924D02*
X1143133D01*
G01D02*
X1147483D01*
G01X1138783Y877231D02*
X1143133D01*
G01D02*
X1147483D01*
G01X1138783Y870538D02*
X1143133D01*
G01D02*
X1147483D01*
G01Y900656D02*
X1143133D01*
G01D02*
X1138783D01*
G01X1147483Y890617D02*
X1143133D01*
G01D02*
X1138783D01*
G01Y914042D02*
X1143133D01*
G01D02*
X1147483D01*
G01X1138783Y907349D02*
X1143133D01*
G01D02*
X1147483D01*
G01X1138783Y927428D02*
X1143133D01*
G01D02*
X1147483D01*
G01X1138783Y920735D02*
X1143133D01*
G01D02*
X1147483D01*
G01X1138783Y944160D02*
X1143133D01*
G01D02*
X1147483D01*
G01X1138783Y937467D02*
X1143133D01*
G01D02*
X1147483D01*
G01X1138783Y960892D02*
X1143133D01*
G01D02*
X1147483D01*
G01X1138783Y950853D02*
X1143133D01*
G01D02*
X1147483D01*
G01X1138783Y980971D02*
X1143133D01*
G01D02*
X1147483D01*
G01X1138783Y974278D02*
X1143133D01*
G01D02*
X1147483D01*
G01X1138783Y967585D02*
X1143133D01*
G01D02*
X1147483D01*
G01X1138783Y987664D02*
X1143133D01*
G01D02*
X1147483D01*
G01X1138783Y1027822D02*
X1143133D01*
G01D02*
X1147483D01*
G01X1138783Y1017782D02*
X1143133D01*
G01D02*
X1147483D01*
G01X1138783Y1041207D02*
X1143133D01*
G01D02*
X1147483D01*
G01X1138783Y1034515D02*
X1143133D01*
G01D02*
X1147483D01*
G01X1138783Y1061286D02*
X1143133D01*
G01D02*
X1147483D01*
G01X1138783Y1054593D02*
X1143133D01*
G01D02*
X1147483D01*
G01Y1047900D02*
X1143133D01*
G01D02*
X1138783D01*
G01Y1074672D02*
X1143133D01*
G01D02*
X1147483D01*
G01X1138783Y1067979D02*
X1143133D01*
G01D02*
X1147483D01*
G01X1138783Y1091404D02*
X1143133D01*
G01D02*
X1147483D01*
G01X1138783Y1084711D02*
X1143133D01*
G01D02*
X1147483D01*
G01X1138783Y1111483D02*
X1143133D01*
G01D02*
X1147483D01*
G01X1138783Y1104790D02*
X1143133D01*
G01D02*
X1147483D01*
G01X1138783Y1098097D02*
X1143133D01*
G01D02*
X1147483D01*
G01X1138783Y1128215D02*
X1143133D01*
G01D02*
X1147483D01*
G01X1138783Y1121522D02*
X1143133D01*
G01D02*
X1147483D01*
G01X1138783Y1141601D02*
X1143133D01*
G01D02*
X1147483D01*
G01X1138783Y1134908D02*
X1143133D01*
G01D02*
X1147483D01*
G01X1138783Y1158333D02*
X1143133D01*
G01D02*
X1147483D01*
G01Y1148294D02*
X1143133D01*
G01D02*
X1138783D01*
G01Y1171719D02*
X1143133D01*
G01D02*
X1147483D01*
G01X1138783Y1165026D02*
X1143133D01*
G01D02*
X1147483D01*
G01X1138783Y1185105D02*
X1143133D01*
G01D02*
X1147483D01*
G01X1138783Y1178412D02*
X1143133D01*
G01D02*
X1147483D01*
G01X1138783Y1208530D02*
X1143133D01*
G01D02*
X1147483D01*
G01X1138783Y1201837D02*
X1143133D01*
G01D02*
X1147483D01*
G01X1138783Y1195144D02*
X1143133D01*
G01D02*
X1147483D01*
G01X1138783Y1221916D02*
X1143133D01*
G01D02*
X1147483D01*
G01X1138783Y1215223D02*
X1143133D01*
G01D02*
X1147483D01*
G01X1138783Y1238648D02*
X1143133D01*
G01D02*
X1147483D01*
G01X1138783Y1231955D02*
X1143133D01*
G01D02*
X1147483D01*
G01X1138783Y1245341D02*
X1143133D01*
G01D02*
X1147483D01*
G01X1137717Y1555301D02*
Y1558020D01*
G01X1139125Y1597630D02*
X1141525D01*
G01X1149395Y1618960D02*
Y1614935D01*
X1147649Y1613189D01*
X1145335D01*
G01X1149395Y1618960D02*
X1146960D01*
G01X1156086Y1626220D02*
X1152317D01*
X1152257Y1626280D01*
G01X1155703Y73679D02*
X1152112D01*
G01X1201700Y110000D02*
Y108001D01*
X1200399Y106700D01*
X1184500D01*
X1155703Y77903D01*
Y73679D01*
G01X1160630Y213870D02*
X1160595Y213835D01*
Y211370D01*
G01X1153655Y363231D02*
X1153585Y363301D01*
Y368041D01*
G01X1156790Y363231D02*
X1153655D01*
G01X1161041Y770144D02*
X1156691D01*
G01D02*
X1152341D01*
G01X1161041Y776837D02*
X1156691D01*
G01D02*
X1152341D01*
G01X1161041Y783530D02*
X1156691D01*
G01D02*
X1152341D01*
G01X1161041Y793570D02*
X1156691D01*
G01D02*
X1152341D01*
G01X1161041Y800263D02*
X1156691D01*
G01D02*
X1152341D01*
G01X1161041Y806955D02*
X1156691D01*
G01D02*
X1152341D01*
G01X1161041Y813648D02*
X1156691D01*
G01D02*
X1152341D01*
G01X1167633Y827034D02*
X1172833D01*
G01X1161041Y820341D02*
X1156691D01*
G01D02*
X1152341D01*
G01X1161041Y830381D02*
X1156691D01*
G01D02*
X1152341D01*
G01Y850459D02*
X1156691D01*
G01D02*
X1161041D01*
G01Y837074D02*
X1156691D01*
G01D02*
X1152341D01*
G01X1161041Y843766D02*
X1156691D01*
G01D02*
X1152341D01*
G01X1167633Y863845D02*
X1172833D01*
G01X1161041Y857152D02*
X1156691D01*
G01D02*
X1152341D01*
G01X1156691Y867192D02*
X1152341D01*
G01X1161041D02*
X1156691D01*
G01Y873885D02*
X1152341D01*
G01X1161041D02*
X1156691D01*
G01Y880577D02*
X1152341D01*
G01X1161041D02*
X1156691D01*
G01Y887270D02*
X1152341D01*
G01X1161041D02*
X1156691D01*
G01Y893963D02*
X1152341D01*
G01X1161041D02*
X1156691D01*
G01Y917389D02*
X1161041D01*
G01X1152341D02*
X1156691D01*
G01Y904003D02*
X1152341D01*
G01X1161041D02*
X1156691D01*
G01Y910696D02*
X1152341D01*
G01X1161041D02*
X1156691D01*
G01X1167633Y927428D02*
X1172833D01*
G01X1156691Y924081D02*
X1152341D01*
G01X1161041D02*
X1156691D01*
G01Y930774D02*
X1152341D01*
G01X1161041D02*
X1156691D01*
G01Y940814D02*
X1152341D01*
G01X1161041D02*
X1156691D01*
G01Y947507D02*
X1152341D01*
G01X1161041D02*
X1156691D01*
G01Y954200D02*
X1152341D01*
G01X1161041D02*
X1156691D01*
G01Y964239D02*
X1152341D01*
G01X1161041D02*
X1156691D01*
G01Y977625D02*
X1161041D01*
G01X1152341D02*
X1156691D01*
G01Y970932D02*
X1152341D01*
G01X1161041D02*
X1156691D01*
G01Y984318D02*
X1152341D01*
G01X1161041D02*
X1156691D01*
G01Y991011D02*
X1152341D01*
G01X1161041D02*
X1156691D01*
G01Y1017782D02*
X1152341D01*
G01X1161041D02*
X1156691D01*
G01Y1024475D02*
X1152341D01*
G01X1161041D02*
X1156691D01*
G01Y1031168D02*
X1152341D01*
G01X1161041D02*
X1156691D01*
G01Y1037861D02*
X1152341D01*
G01X1161041D02*
X1156691D01*
G01Y1044554D02*
X1152341D01*
G01X1161041D02*
X1156691D01*
G01Y1051247D02*
X1152341D01*
G01X1161041D02*
X1156691D01*
G01Y1057940D02*
X1152341D01*
G01X1161041D02*
X1156691D01*
G01Y1064633D02*
X1152341D01*
G01X1161041D02*
X1156691D01*
G01Y1071326D02*
X1152341D01*
G01X1161041D02*
X1156691D01*
G01Y1078018D02*
X1152341D01*
G01X1161041D02*
X1156691D01*
G01X1167633Y1084711D02*
X1172833D01*
G01X1156691Y1088058D02*
X1152341D01*
G01X1161041D02*
X1156691D01*
G01Y1094751D02*
X1152341D01*
G01X1161041D02*
X1156691D01*
G01Y1108137D02*
X1161041D01*
G01X1152341D02*
X1156691D01*
G01Y1101444D02*
X1152341D01*
G01X1161041D02*
X1156691D01*
G01Y1114829D02*
X1161041D01*
G01X1152341D02*
X1156691D01*
G01Y1124869D02*
X1152341D01*
G01X1161041D02*
X1156691D01*
G01Y1131562D02*
X1152341D01*
G01X1161041D02*
X1156691D01*
G01Y1138255D02*
X1152341D01*
G01X1161041D02*
X1156691D01*
G01Y1144948D02*
X1152341D01*
G01X1161041D02*
X1156691D01*
G01X1167633Y1158333D02*
X1172833D01*
G01X1156691Y1151641D02*
X1152341D01*
G01X1161041D02*
X1156691D01*
G01Y1175066D02*
X1161041D01*
G01X1152341D02*
X1156691D01*
G01Y1161680D02*
X1152341D01*
G01X1161041D02*
X1156691D01*
G01Y1168373D02*
X1152341D01*
G01X1161041D02*
X1156691D01*
G01Y1181759D02*
X1152341D01*
G01X1161041D02*
X1156691D01*
G01Y1188452D02*
X1152341D01*
G01X1161041D02*
X1156691D01*
G01Y1198491D02*
X1152341D01*
G01X1161041D02*
X1156691D01*
G01Y1205184D02*
X1152341D01*
G01X1161041D02*
X1156691D01*
G01Y1211877D02*
X1152341D01*
G01X1161041D02*
X1156691D01*
G01Y1218570D02*
X1152341D01*
G01X1161041D02*
X1156691D01*
G01Y1225263D02*
X1152341D01*
G01X1161041D02*
X1156691D01*
G01X1167633Y1231955D02*
X1172833D01*
G01X1156691Y1241995D02*
X1161041D01*
G01X1152341D02*
X1156691D01*
G01Y1235302D02*
X1152341D01*
G01X1161041D02*
X1156691D01*
G01Y1248688D02*
X1161041D01*
G01X1152341D02*
X1156691D01*
G01Y1258727D02*
X1152341D01*
G01X1164260Y1447863D02*
Y1450423D01*
G01X1152257Y1626280D02*
Y1628910D01*
G01X1164830Y1657540D02*
Y1654632D01*
G01X1159930Y1657540D02*
Y1654632D01*
G01X1163576Y1680624D02*
X1161076D01*
G01X1171466Y57111D02*
Y61291D01*
X1171446Y61311D01*
G01X1171466Y57111D02*
X1174120D01*
G01X1171446Y65811D02*
X1172586D01*
X1175926Y69151D01*
G01X1181476Y166881D02*
Y172247D01*
G01X1173374Y170056D02*
X1170595D01*
G01X1175670Y198174D02*
Y202174D01*
G01X1173100Y186962D02*
Y186469D01*
X1173395Y186174D01*
X1175670D01*
G01Y214174D02*
Y218174D01*
G01Y202174D02*
X1172925D01*
G01X1175670Y218174D02*
X1172835D01*
G01X1182041Y770144D02*
X1186391D01*
G01X1168483Y766798D02*
X1172833D01*
G01D02*
X1177183D01*
G01X1182041Y783530D02*
X1186391D01*
G01X1182041Y776837D02*
X1186391D01*
G01X1168483Y780184D02*
X1172833D01*
G01D02*
X1177183D01*
G01X1168483Y773491D02*
X1172833D01*
G01D02*
X1177183D01*
G01X1182041Y800263D02*
X1186391D01*
G01X1182041Y793570D02*
X1186391D01*
G01X1168483Y803609D02*
X1172833D01*
G01D02*
X1177183D01*
G01X1168483Y796916D02*
X1172833D01*
G01D02*
X1177183D01*
G01X1168483Y790223D02*
X1172833D01*
G01D02*
X1177183D01*
G01X1182041Y813648D02*
X1186391D01*
G01X1182041Y806955D02*
X1186391D01*
G01X1168483Y816995D02*
X1172833D01*
G01D02*
X1177183D01*
G01X1168483Y810302D02*
X1172833D01*
G01D02*
X1177183D01*
G01X1181191Y830381D02*
X1186391D01*
G01X1181191Y820341D02*
X1186391D01*
G01X1168483Y833727D02*
X1172833D01*
G01D02*
X1177183D01*
G01X1172833Y827034D02*
X1177183D01*
G01X1182041Y850459D02*
X1186391D01*
G01X1182041Y837074D02*
X1186391D01*
G01X1182041Y843766D02*
X1186391D01*
G01X1168483Y847113D02*
X1172833D01*
G01D02*
X1177183D01*
G01X1168483Y840420D02*
X1172833D01*
G01D02*
X1177183D01*
G01X1181191Y867192D02*
X1186391D01*
G01X1181191Y857152D02*
X1186391D01*
G01X1172833Y863845D02*
X1177183D01*
G01X1168483Y853806D02*
X1172833D01*
G01D02*
X1177183D01*
G01X1182041Y873885D02*
X1186391D01*
G01X1182041Y880577D02*
X1186391D01*
G01X1172833Y883924D02*
X1177183D01*
G01X1168483D02*
X1172833D01*
G01Y877231D02*
X1177183D01*
G01X1168483D02*
X1172833D01*
G01Y870538D02*
X1177183D01*
G01X1168483D02*
X1172833D01*
G01X1182041Y893963D02*
X1186391D01*
G01X1182041Y887270D02*
X1186391D01*
G01X1172833Y900656D02*
X1177183D01*
G01X1168483D02*
X1172833D01*
G01Y890617D02*
X1177183D01*
G01X1168483D02*
X1172833D01*
G01X1182041Y917389D02*
X1186391D01*
G01X1182041Y910696D02*
X1186391D01*
G01X1182041Y904003D02*
X1186391D01*
G01X1172833Y914042D02*
X1177183D01*
G01X1168483D02*
X1172833D01*
G01Y907349D02*
X1177183D01*
G01X1168483D02*
X1172833D01*
G01X1181191Y930774D02*
X1186391D01*
G01X1181191Y924081D02*
X1186391D01*
G01X1172833Y927428D02*
X1177183D01*
G01X1172833Y920735D02*
X1177183D01*
G01X1168483D02*
X1172833D01*
G01X1182041Y940814D02*
X1186391D01*
G01X1182041Y947507D02*
X1186391D01*
G01X1168483Y937467D02*
X1172833D01*
G01D02*
X1177183D01*
G01X1172833Y944160D02*
X1177183D01*
G01X1168483D02*
X1172833D01*
G01X1182041Y964239D02*
X1186391D01*
G01X1182041Y954200D02*
X1186391D01*
G01X1172833Y960892D02*
X1177183D01*
G01X1168483D02*
X1172833D01*
G01Y950853D02*
X1177183D01*
G01X1168483D02*
X1172833D01*
G01X1182041Y970932D02*
X1186391D01*
G01X1182041Y977625D02*
X1186391D01*
G01X1168483Y974278D02*
X1172833D01*
G01D02*
X1177183D01*
G01X1168483Y980971D02*
X1172833D01*
G01D02*
X1177183D01*
G01X1168483Y967585D02*
X1172833D01*
G01D02*
X1177183D01*
G01X1182041Y991011D02*
X1186391D01*
G01X1182041Y984318D02*
X1186391D01*
G01X1168483Y987664D02*
X1172833D01*
G01D02*
X1177183D01*
G01X1182041Y1017782D02*
X1186391D01*
G01X1182041Y1024475D02*
X1186391D01*
G01X1172833Y1027822D02*
X1177183D01*
G01X1168483D02*
X1172833D01*
G01Y1017782D02*
X1177183D01*
G01X1168483D02*
X1172833D01*
G01X1182041Y1044554D02*
X1186391D01*
G01X1182041Y1037861D02*
X1186391D01*
G01X1168483Y1041207D02*
X1172833D01*
G01D02*
X1177183D01*
G01X1168483Y1034515D02*
X1172833D01*
G01D02*
X1177183D01*
G01X1182041Y1057940D02*
X1186391D01*
G01X1168483Y1054593D02*
X1172833D01*
G01D02*
X1177183D01*
G01X1172833Y1061286D02*
X1177183D01*
G01X1168483D02*
X1172833D01*
G01X1168483Y1047900D02*
X1172833D01*
G01D02*
X1177183D01*
G01X1181191Y1078018D02*
X1186391D01*
G01X1182041Y1071326D02*
X1186391D01*
G01X1182041Y1064633D02*
X1186391D01*
G01X1172833Y1074672D02*
X1177183D01*
G01X1168483D02*
X1172833D01*
G01Y1067979D02*
X1177183D01*
G01X1168483D02*
X1172833D01*
G01X1182041Y1094751D02*
X1186391D01*
G01X1181191Y1088058D02*
X1186391D01*
G01X1172833Y1091404D02*
X1177183D01*
G01X1168483D02*
X1172833D01*
G01Y1084711D02*
X1177183D01*
G01X1182041Y1101444D02*
X1186391D01*
G01X1182041Y1108137D02*
X1186391D01*
G01X1172833Y1111483D02*
X1177183D01*
G01X1168483D02*
X1172833D01*
G01Y1104790D02*
X1177183D01*
G01X1168483D02*
X1172833D01*
G01Y1098097D02*
X1177183D01*
G01X1168483D02*
X1172833D01*
G01X1182041Y1114829D02*
X1186391D01*
G01X1182041Y1124869D02*
X1186391D01*
G01X1172833Y1128215D02*
X1177183D01*
G01X1168483D02*
X1172833D01*
G01Y1121522D02*
X1177183D01*
G01X1168483D02*
X1172833D01*
G01X1182041Y1144948D02*
X1186391D01*
G01X1182041Y1138255D02*
X1186391D01*
G01X1182041Y1131562D02*
X1186391D01*
G01X1172833Y1141601D02*
X1177183D01*
G01X1168483D02*
X1172833D01*
G01Y1134908D02*
X1177183D01*
G01X1168483D02*
X1172833D01*
G01X1181191Y1151641D02*
X1186391D01*
G01X1172833Y1158333D02*
X1177183D01*
G01X1172833Y1148294D02*
X1177183D01*
G01X1168483D02*
X1172833D01*
G01X1182041Y1168373D02*
X1186391D01*
G01X1182041Y1175066D02*
X1186391D01*
G01X1181191Y1161680D02*
X1186391D01*
G01X1172833Y1171719D02*
X1177183D01*
G01X1168483D02*
X1172833D01*
G01Y1165026D02*
X1177183D01*
G01X1168483D02*
X1172833D01*
G01X1182041Y1188452D02*
X1186391D01*
G01X1182041Y1181759D02*
X1186391D01*
G01X1172833Y1185105D02*
X1177183D01*
G01X1168483D02*
X1172833D01*
G01Y1178412D02*
X1177183D01*
G01X1168483D02*
X1172833D01*
G01X1182041Y1205184D02*
X1186391D01*
G01X1182041Y1198491D02*
X1186391D01*
G01X1172833Y1208530D02*
X1177183D01*
G01X1168483D02*
X1172833D01*
G01Y1201837D02*
X1177183D01*
G01X1168483D02*
X1172833D01*
G01Y1195144D02*
X1177183D01*
G01X1168483D02*
X1172833D01*
G01X1181191Y1225263D02*
X1186391D01*
G01X1182041Y1211877D02*
X1186391D01*
G01X1182041Y1218570D02*
X1186391D01*
G01X1172833Y1221916D02*
X1177183D01*
G01X1168483D02*
X1172833D01*
G01Y1215223D02*
X1177183D01*
G01X1168483D02*
X1172833D01*
G01X1182041Y1241995D02*
X1186391D01*
G01X1181191Y1235302D02*
X1186391D01*
G01X1172833Y1238648D02*
X1177183D01*
G01X1168483D02*
X1172833D01*
G01Y1231955D02*
X1177183D01*
G01X1182041Y1248688D02*
X1186391D01*
G01X1168483Y1245341D02*
X1172833D01*
G01D02*
X1177183D01*
G01X1181850Y1260192D02*
X1183315Y1258727D01*
X1186391D01*
G01X1174147Y1447858D02*
X1173506D01*
X1172862Y1448502D01*
X1171587D01*
G01X1172305Y1601100D02*
X1171238D01*
X1169968Y1602370D01*
G01X1180193Y1622267D02*
X1184879D01*
X1185080Y1622066D01*
Y1622064D01*
G01X1181930Y1657540D02*
Y1654632D01*
G01X1175830Y1657540D02*
Y1654632D01*
G01X1170930Y1657540D02*
Y1654632D01*
G01X1185576Y1680624D02*
X1183076D01*
G01X1174576D02*
X1172076D01*
G01X1195225Y93200D02*
X1192700D01*
X1188200Y97700D01*
Y100200D01*
X1188700Y100700D01*
G01X1198453Y110227D02*
X1201473D01*
X1201700Y110000D01*
G01X1193401Y127804D02*
Y125232D01*
X1194713Y123920D01*
G01X1191206Y135974D02*
Y134970D01*
X1193532Y132644D01*
G01D02*
X1193401Y132513D01*
Y127804D01*
G01X1197400Y236592D02*
X1194840D01*
G01X1198183Y766798D02*
X1202533D01*
G01X1186391Y770144D02*
X1190741D01*
G01X1198183Y780184D02*
X1202533D01*
G01X1198183Y773491D02*
X1202533D01*
G01X1186391Y783530D02*
X1190741D01*
G01X1186391Y776837D02*
X1190741D01*
G01X1198183Y803609D02*
X1202533D01*
G01X1198183Y796916D02*
X1202533D01*
G01X1198183Y790223D02*
X1202533D01*
G01X1186391Y800263D02*
X1190741D01*
G01X1186391Y793570D02*
X1190741D01*
G01X1197333Y816995D02*
X1202533D01*
G01X1198183Y810302D02*
X1202533D01*
G01X1186391Y813648D02*
X1190741D01*
G01X1186391Y806955D02*
X1190741D01*
G01X1198183Y833727D02*
X1202533D01*
G01X1197333Y827034D02*
X1202533D01*
G01X1186391Y830381D02*
X1191591D01*
G01X1186391Y820341D02*
X1191591D01*
G01X1198183Y847113D02*
X1202533D01*
G01X1198183Y840420D02*
X1202533D01*
G01X1186391Y850459D02*
X1190741D01*
G01X1186391Y837074D02*
X1190741D01*
G01X1186391Y843766D02*
X1190741D01*
G01X1197333Y863845D02*
X1202533D01*
G01X1198183Y853806D02*
X1202533D01*
G01X1186391Y867192D02*
X1191591D01*
G01X1186391Y857152D02*
X1191591D01*
G01X1198183Y877231D02*
X1202533D01*
G01X1197333Y870538D02*
X1202533D01*
G01X1198183Y883924D02*
X1202533D01*
G01X1186391Y873885D02*
X1190741D01*
G01X1186391Y880577D02*
X1190741D01*
G01X1198183Y900656D02*
X1202533D01*
G01X1198183Y890617D02*
X1202533D01*
G01X1186391Y893963D02*
X1190741D01*
G01X1186391Y887270D02*
X1190741D01*
G01X1198183Y914042D02*
X1202533D01*
G01X1198183Y907349D02*
X1202533D01*
G01X1186391Y917389D02*
X1190741D01*
G01X1186391Y910696D02*
X1190741D01*
G01X1186391Y904003D02*
X1190741D01*
G01X1197383Y927428D02*
X1202533D01*
G01X1198183Y920735D02*
X1202533D01*
G01X1186391Y930774D02*
X1191591D01*
G01X1186391Y924081D02*
X1191591D01*
G01X1198183Y944160D02*
X1202533D01*
G01X1197333Y937467D02*
X1202533D01*
G01X1186391Y940814D02*
X1190741D01*
G01X1186391Y947507D02*
X1190741D01*
G01X1198183Y960892D02*
X1202533D01*
G01X1198183Y950853D02*
X1202533D01*
G01X1186391Y964239D02*
X1190741D01*
G01X1186391Y954200D02*
X1190741D01*
G01X1198183Y980971D02*
X1202533D01*
G01X1198183Y974278D02*
X1202533D01*
G01X1198183Y967585D02*
X1202533D01*
G01X1186391Y970932D02*
X1190741D01*
G01X1186391Y977625D02*
X1190741D01*
G01X1198183Y987664D02*
X1202533D01*
G01X1186391Y991011D02*
X1190741D01*
G01X1186391Y984318D02*
X1190741D01*
G01X1198183Y1027822D02*
X1202533D01*
G01X1198183Y1017782D02*
X1202533D01*
G01X1186391D02*
X1190741D01*
G01X1186391Y1024475D02*
X1190741D01*
G01X1198183Y1041207D02*
X1202533D01*
G01X1198183Y1034515D02*
X1202533D01*
G01X1186391Y1044554D02*
X1190741D01*
G01X1186391Y1037861D02*
X1190741D01*
G01X1198183Y1054593D02*
X1202533D01*
G01X1198183Y1061286D02*
X1202533D01*
G01X1198183Y1047900D02*
X1202533D01*
G01X1186391Y1057940D02*
X1190741D01*
G01X1197333Y1074672D02*
X1202533D01*
G01X1198183Y1067979D02*
X1202533D01*
G01X1186391Y1078018D02*
X1191591D01*
G01X1186391Y1071326D02*
X1190741D01*
G01X1186391Y1064633D02*
X1190741D01*
G01X1198183Y1091404D02*
X1202533D01*
G01X1197333Y1084711D02*
X1202533D01*
G01X1186391Y1094751D02*
X1190741D01*
G01X1186391Y1088058D02*
X1191591D01*
G01X1198183Y1111483D02*
X1202533D01*
G01X1198183Y1098097D02*
X1202533D01*
G01X1198183Y1104790D02*
X1202533D01*
G01X1186391Y1101444D02*
X1190741D01*
G01X1186391Y1108137D02*
X1190741D01*
G01X1198183Y1128215D02*
X1202533D01*
G01X1198183Y1121522D02*
X1202533D01*
G01X1186391Y1114829D02*
X1190741D01*
G01X1186391Y1124869D02*
X1190741D01*
G01X1198183Y1141601D02*
X1202533D01*
G01X1197333Y1134908D02*
X1202533D01*
G01X1186391Y1144948D02*
X1190741D01*
G01X1186391Y1138255D02*
X1190741D01*
G01X1186391Y1131562D02*
X1190741D01*
G01X1198183Y1158333D02*
X1202533D01*
G01X1197333Y1148294D02*
X1202533D01*
G01X1186391Y1151641D02*
X1191591D01*
G01X1198183Y1165026D02*
X1202533D01*
G01X1198183Y1171719D02*
X1202533D01*
G01X1186391Y1168373D02*
X1190741D01*
G01X1186391Y1175066D02*
X1190741D01*
G01X1186391Y1161680D02*
X1191591D01*
G01X1198183Y1185105D02*
X1202533D01*
G01X1198183Y1178412D02*
X1202533D01*
G01X1186391Y1188452D02*
X1190741D01*
G01X1186391Y1181759D02*
X1190741D01*
G01X1198183Y1208530D02*
X1202533D01*
G01X1198183Y1201837D02*
X1202533D01*
G01X1198183Y1195144D02*
X1202533D01*
G01X1186391Y1205184D02*
X1190741D01*
G01X1186391Y1198491D02*
X1190741D01*
G01X1198183Y1221916D02*
X1202533D01*
G01X1198183Y1215223D02*
X1202533D01*
G01X1186391Y1225263D02*
X1191591D01*
G01X1186391Y1211877D02*
X1190741D01*
G01X1186391Y1218570D02*
X1190741D01*
G01X1197333Y1238648D02*
X1202533D01*
G01X1197333Y1231955D02*
X1202533D01*
G01X1186391Y1241995D02*
X1190741D01*
G01X1186391Y1235302D02*
X1191591D01*
G01X1198183Y1245341D02*
X1202533D01*
G01X1186391Y1248688D02*
X1190741D01*
G01X1185080Y1622064D02*
X1187600D01*
G01X1197400Y1657850D02*
Y1654942D01*
G01X1192500Y1657850D02*
Y1654942D01*
G01X1186830Y1657540D02*
Y1654632D01*
G01X1196146Y1680934D02*
X1193646D01*
G01X1192340Y1703330D02*
Y1700422D01*
G01X1197240Y1703330D02*
Y1700422D01*
G01X1195986Y1726414D02*
X1193174D01*
G01X1216176Y56742D02*
Y53860D01*
G01D02*
X1216416Y54100D01*
X1223507D01*
G01X1204186Y57130D02*
X1201158D01*
G01X1212975Y113200D02*
Y110730D01*
X1216165Y107540D01*
X1219515D01*
G01X1215800Y111300D02*
X1214875D01*
X1212975Y113200D01*
G01X1217018Y168962D02*
X1214593D01*
G01X1214534Y157462D02*
X1216519D01*
X1217018Y157962D01*
G01X1208518Y176962D02*
Y174162D01*
G01X1209900Y247148D02*
X1207220D01*
G01X1210084Y236369D02*
Y243814D01*
X1209900Y243998D01*
G01X1207220D02*
X1209900D01*
G01X1211741Y770144D02*
X1216091D01*
G01D02*
X1220441D01*
G01X1202533Y766798D02*
X1206883D01*
G01X1211741Y783530D02*
X1216091D01*
G01D02*
X1220441D01*
G01X1211741Y776837D02*
X1216091D01*
G01D02*
X1220441D01*
G01X1202533Y780184D02*
X1206883D01*
G01X1202533Y773491D02*
X1206883D01*
G01X1211741Y800263D02*
X1216091D01*
G01D02*
X1220441D01*
G01X1211741Y793570D02*
X1216091D01*
G01D02*
X1220441D01*
G01X1202533Y803609D02*
X1206883D01*
G01X1202533Y796916D02*
X1206883D01*
G01X1202533Y790223D02*
X1206883D01*
G01X1216091Y813648D02*
X1221291D01*
G01X1210891D02*
X1216091D01*
G01Y806955D02*
X1220441D01*
G01X1211741D02*
X1216091D01*
G01X1207148Y817554D02*
X1206589Y816995D01*
X1202533D01*
G01Y810302D02*
X1206883D01*
G01X1216091Y830381D02*
X1220441D01*
G01X1211741D02*
X1216091D01*
G01Y820341D02*
X1221291D01*
G01X1210891D02*
X1216091D01*
G01X1202533Y833727D02*
X1206883D01*
G01X1202533Y827034D02*
X1207733D01*
G01X1216091Y850459D02*
X1220441D01*
G01X1211741D02*
X1216091D01*
G01Y837074D02*
X1220441D01*
G01X1211741D02*
X1216091D01*
G01X1211741Y843766D02*
X1216091D01*
G01D02*
X1220441D01*
G01X1202533Y847113D02*
X1206883D01*
G01X1202533Y840420D02*
X1206883D01*
G01X1221291Y867192D02*
X1216091D01*
G01X1210891Y867492D02*
X1211191Y867192D01*
X1216091D01*
G01Y857152D02*
X1221291D01*
G01X1210891D02*
X1216091D01*
G01X1202533Y863845D02*
X1207733D01*
G01X1202533Y853806D02*
X1206883D01*
G01X1220441Y873885D02*
X1216091D01*
G01X1211741Y874185D02*
X1212041Y873885D01*
X1216091D01*
G01Y880577D02*
X1211741D01*
G01X1220441D02*
X1216091D01*
G01X1202533Y877231D02*
X1206883D01*
G01X1207201Y871084D02*
X1206655Y870538D01*
X1202533D01*
G01Y883924D02*
X1206883D01*
G01X1216091Y893963D02*
X1220441D01*
G01X1211741D02*
X1216091D01*
G01Y887270D02*
X1220441D01*
G01X1211741D02*
X1216091D01*
G01X1202533Y900656D02*
X1206883D01*
G01X1202533Y890617D02*
X1206883D01*
G01X1211741Y917389D02*
X1216091D01*
G01D02*
X1220441D01*
G01X1216091Y910696D02*
X1220441D01*
G01X1211741D02*
X1216091D01*
G01Y904003D02*
X1220441D01*
G01X1211741D02*
X1216091D01*
G01X1202533Y914042D02*
X1206883D01*
G01X1202533Y907349D02*
X1206883D01*
G01X1211741Y930774D02*
X1216091D01*
G01D02*
X1221291D01*
G01X1211741Y924081D02*
X1216091D01*
G01D02*
X1220441D01*
G01X1202533Y927428D02*
X1207683D01*
G01X1202533Y920735D02*
X1206883D01*
G01X1211741Y947507D02*
X1216091D01*
G01D02*
X1220441D01*
G01X1211001Y940814D02*
X1216091D01*
G01D02*
X1221291D01*
G01X1206883Y944660D02*
X1206383Y944160D01*
X1202533D01*
G01Y937467D02*
X1207733D01*
G01X1211741Y964239D02*
X1216091D01*
G01D02*
X1220441D01*
G01X1216091Y954200D02*
X1220441D01*
G01X1211741D02*
X1216091D01*
G01X1202533Y960892D02*
X1206883D01*
G01X1202533Y950853D02*
X1206883D01*
G01X1211741Y977625D02*
X1216091D01*
G01D02*
X1220441D01*
G01X1211741Y970932D02*
X1216091D01*
G01D02*
X1220441D01*
G01X1202533Y980971D02*
X1206883D01*
G01X1202533Y974278D02*
X1206883D01*
G01X1202533Y967585D02*
X1206883D01*
G01X1211741Y991011D02*
X1216091D01*
G01D02*
X1220441D01*
G01X1211741Y984318D02*
X1216091D01*
G01D02*
X1220441D01*
G01X1202533Y987664D02*
X1206883D01*
G01X1211741Y1031168D02*
X1216091D01*
G01D02*
X1220441D01*
G01Y1017782D02*
X1216091D01*
G01D02*
X1211741D01*
G01Y1024475D02*
X1216091D01*
G01D02*
X1220441D01*
G01X1202533Y1027822D02*
X1206883D01*
G01X1202533Y1017782D02*
X1206883D01*
G01X1211741Y1044554D02*
X1216091D01*
G01D02*
X1220441D01*
G01X1211741Y1037861D02*
X1216091D01*
G01D02*
X1220441D01*
G01X1202533Y1041207D02*
X1206883D01*
G01X1202533Y1034515D02*
X1206883D01*
G01X1211741Y1051247D02*
X1216091D01*
G01D02*
X1220441D01*
G01X1216091Y1057940D02*
X1220441D01*
G01X1211741D02*
X1216091D01*
G01X1202533Y1054593D02*
X1206883D01*
G01X1202533Y1061286D02*
X1206883D01*
G01X1202533Y1047900D02*
X1206883D01*
G01X1210891Y1078018D02*
X1216091D01*
G01D02*
X1221291D01*
G01X1211741Y1064633D02*
X1216091D01*
G01D02*
X1220441D01*
G01X1211741Y1071326D02*
X1216091D01*
G01D02*
X1220441D01*
G01X1202533Y1074672D02*
X1207733D01*
G01X1202533Y1067979D02*
X1206883D01*
G01X1211741Y1094751D02*
X1216091D01*
G01D02*
X1220441D01*
G01X1210891Y1088058D02*
X1216091D01*
G01D02*
X1221291D01*
G01X1202533Y1091404D02*
X1206883D01*
G01X1202533Y1084711D02*
X1206883D01*
G01X1211741Y1108137D02*
X1216091D01*
G01D02*
X1220441D01*
G01X1216091Y1101444D02*
X1220441D01*
G01X1211741D02*
X1216091D01*
G01X1202533Y1111483D02*
X1206883D01*
G01X1202533Y1098097D02*
X1206883D01*
G01X1202533Y1104790D02*
X1206883D01*
G01X1216091Y1124869D02*
X1210891D01*
G01X1221291D02*
X1216091D01*
G01Y1114829D02*
X1220441D01*
G01X1211741D02*
X1216091D01*
G01X1202533Y1128215D02*
X1206883D01*
G01X1202533Y1121522D02*
X1206883D01*
G01X1211741Y1144948D02*
X1216091D01*
G01D02*
X1220441D01*
G01X1216091Y1138255D02*
X1220441D01*
G01X1211741D02*
X1216091D01*
G01Y1131562D02*
X1210891D01*
G01X1221291D02*
X1216091D01*
G01X1202533Y1141601D02*
X1206883D01*
G01X1202533Y1134908D02*
X1207733D01*
G01X1211741Y1151641D02*
X1216091D01*
G01D02*
X1220441D01*
G01X1202533Y1158333D02*
X1206883D01*
G01X1202533Y1148294D02*
X1207733D01*
G01X1216091Y1175066D02*
X1220441D01*
G01X1211741D02*
X1216091D01*
G01Y1168373D02*
X1211741D01*
G01X1220441D02*
X1216091D01*
G01X1202533Y1165026D02*
X1206883D01*
G01X1202533Y1171719D02*
X1206883D01*
G01X1216091Y1161680D02*
X1211741D01*
G01X1220441D02*
X1216091D01*
G01Y1188452D02*
X1220441D01*
G01X1211741D02*
X1216091D01*
G01Y1181759D02*
X1220441D01*
G01X1211741D02*
X1216091D01*
G01X1202533Y1185105D02*
X1206883D01*
G01X1202533Y1178412D02*
X1206883D01*
G01X1216091Y1205184D02*
X1220441D01*
G01X1211741D02*
X1216091D01*
G01Y1198491D02*
X1220441D01*
G01X1211741D02*
X1216091D01*
G01X1202533Y1208530D02*
X1206883D01*
G01X1202533Y1201837D02*
X1206883D01*
G01X1202533Y1195144D02*
X1206883D01*
G01X1210891Y1225263D02*
X1216091D01*
G01D02*
X1221291D01*
G01X1211741Y1218570D02*
X1216091D01*
G01D02*
X1220441D01*
G01X1216091Y1211877D02*
X1220441D01*
G01X1211741D02*
X1216091D01*
G01X1202533Y1221916D02*
X1206883D01*
G01X1202533Y1215223D02*
X1206883D01*
G01X1211741Y1241995D02*
X1216091D01*
G01D02*
X1220441D01*
G01X1221291Y1235302D02*
X1216091D01*
G01X1211328Y1234977D02*
X1211653Y1235302D01*
X1216091D01*
G01X1202533Y1238648D02*
X1207733D01*
G01X1202533Y1231955D02*
X1207733D01*
G01X1202533Y1245341D02*
X1206883D01*
G01X1211741Y1248688D02*
X1216091D01*
G01D02*
X1220441D01*
G01X1208830Y1256692D02*
Y1258053D01*
X1209504Y1258727D01*
X1216091D01*
G01X1203506Y1677873D02*
X1201106D01*
G01X1210830Y1676500D02*
Y1673963D01*
G01D02*
X1210922Y1673871D01*
Y1671729D01*
X1210457Y1671264D01*
Y1668595D01*
G01X1208010Y1703375D02*
Y1700467D01*
G01X1213910Y1703640D02*
Y1700732D01*
G01X1203110Y1703375D02*
Y1700467D01*
G01X1206756Y1726459D02*
X1203939D01*
G01X1217556Y1726724D02*
X1214834D01*
G01X1232815Y102608D02*
X1232816Y102609D01*
Y106609D01*
G01X1228425Y94200D02*
Y91500D01*
G01X1219575Y93600D02*
X1220100D01*
X1222100Y91600D01*
G01X1232182Y110659D02*
X1232816Y110025D01*
Y106609D01*
G01X1224614Y116962D02*
X1222919Y115267D01*
Y113982D01*
G01X1219534Y116492D02*
Y118828D01*
X1220168Y119462D01*
G01X1226093Y140962D02*
X1228370D01*
X1228518Y141110D01*
G01X1220168Y140962D02*
X1222593D01*
G01X1222594Y154242D02*
X1220448D01*
X1220168Y153962D01*
G01X1228518Y163462D02*
X1225874D01*
G01X1222720Y163362D02*
X1221768D01*
X1220168Y164962D01*
G01X1226093Y193462D02*
X1225843Y193712D01*
X1223595D01*
X1222445Y194862D01*
X1220295D01*
G01X1232233Y766798D02*
X1236583D01*
G01X1227883D02*
X1232233D01*
G01X1227883Y780184D02*
X1232233D01*
G01D02*
X1236583D01*
G01X1227883Y773491D02*
X1232233D01*
G01D02*
X1236583D01*
G01X1232233Y803609D02*
X1236583D01*
G01X1227883D02*
X1232233D01*
G01X1227883Y796916D02*
X1232233D01*
G01D02*
X1236583D01*
G01X1227883Y790223D02*
X1232233D01*
G01D02*
X1236583D01*
G01X1232233Y816995D02*
X1237433D01*
G01X1227033D02*
X1232233D01*
G01Y810302D02*
X1236583D01*
G01X1227883D02*
X1232233D01*
G01Y833727D02*
X1236583D01*
G01X1227883D02*
X1232233D01*
G01Y827034D02*
X1237433D01*
G01X1227033D02*
X1232233D01*
G01Y847113D02*
X1236583D01*
G01X1227883D02*
X1232233D01*
G01X1227883Y840420D02*
X1232233D01*
G01D02*
X1236583D01*
G01X1227033Y863845D02*
X1232233D01*
G01D02*
X1237433D01*
G01X1232233Y853806D02*
X1237433D01*
G01X1227033D02*
X1232233D01*
G01X1227883Y870538D02*
X1232233D01*
G01D02*
X1236583D01*
G01X1232233Y883924D02*
X1236583D01*
G01X1227883D02*
X1232233D01*
G01Y877231D02*
X1236583D01*
G01X1227883D02*
X1232233D01*
G01Y900656D02*
X1227033D01*
G01X1236583D02*
X1232233D01*
G01Y890617D02*
X1227883D01*
G01X1236583D02*
X1232233D01*
G01X1227883Y914042D02*
X1232233D01*
G01D02*
X1236583D01*
G01X1227883Y907349D02*
X1232233D01*
G01D02*
X1236583D01*
G01X1227033Y927428D02*
X1232233D01*
G01D02*
X1237433D01*
G01X1227883Y920735D02*
X1232233D01*
G01D02*
X1236583D01*
G01X1227883Y944160D02*
X1232233D01*
G01D02*
X1236583D01*
G01X1227033Y937467D02*
X1232233D01*
G01D02*
X1237433D01*
G01X1227883Y960892D02*
X1232233D01*
G01D02*
X1236583D01*
G01X1232233Y950853D02*
X1236583D01*
G01X1227883D02*
X1232233D01*
G01X1227883Y974278D02*
X1232233D01*
G01D02*
X1236583D01*
G01X1227883Y967585D02*
X1232233D01*
G01D02*
X1236583D01*
G01X1227883Y980971D02*
X1232233D01*
G01D02*
X1236583D01*
G01X1227883Y987664D02*
X1232233D01*
G01D02*
X1236583D01*
G01X1227883Y1027822D02*
X1232233D01*
G01D02*
X1236583D01*
G01X1227883Y1017782D02*
X1232233D01*
G01D02*
X1236583D01*
G01X1227883Y1041207D02*
X1232233D01*
G01D02*
X1236583D01*
G01X1227883Y1034515D02*
X1232233D01*
G01D02*
X1236583D01*
G01X1227883Y1061286D02*
X1232233D01*
G01D02*
X1236583D01*
G01X1232233Y1054593D02*
X1236583D01*
G01X1227883D02*
X1232233D01*
G01X1227883Y1047900D02*
X1232233D01*
G01D02*
X1236583D01*
G01X1227033Y1074672D02*
X1232233D01*
G01D02*
X1237433D01*
G01X1227033Y1067979D02*
X1232233D01*
G01D02*
X1237433D01*
G01X1227883Y1091404D02*
X1232233D01*
G01D02*
X1236583D01*
G01X1227883Y1084711D02*
X1232233D01*
G01D02*
X1236583D01*
G01X1227883Y1104790D02*
X1232233D01*
G01D02*
X1236583D01*
G01X1232233Y1111483D02*
X1237433D01*
G01X1227033D02*
X1232233D01*
G01Y1098097D02*
X1236583D01*
G01X1227883D02*
X1232233D01*
G01Y1128215D02*
X1236583D01*
G01X1227883D02*
X1232233D01*
G01Y1121522D02*
X1237433D01*
G01X1227033D02*
X1232233D01*
G01X1227883Y1134908D02*
X1232233D01*
G01D02*
X1236583D01*
G01X1232233Y1141601D02*
X1236583D01*
G01X1227883D02*
X1232233D01*
G01X1227883Y1158333D02*
X1232233D01*
G01D02*
X1236583D01*
G01X1232233Y1148294D02*
X1236583D01*
G01X1227883D02*
X1232233D01*
G01Y1171719D02*
X1236583D01*
G01X1227883D02*
X1232233D01*
G01Y1165026D02*
X1236583D01*
G01X1227883D02*
X1232233D01*
G01Y1185105D02*
X1236583D01*
G01X1227883D02*
X1232233D01*
G01Y1178412D02*
X1236583D01*
G01X1227883D02*
X1232233D01*
G01Y1208530D02*
X1236583D01*
G01X1227883D02*
X1232233D01*
G01Y1201837D02*
X1236583D01*
G01X1227883D02*
X1232233D01*
G01Y1195144D02*
X1236583D01*
G01X1227033D02*
X1232233D01*
G01X1227033Y1221916D02*
X1232233D01*
G01D02*
X1237433D01*
G01X1227883Y1215223D02*
X1232233D01*
G01D02*
X1236583D01*
G01X1227883Y1238648D02*
X1232233D01*
G01D02*
X1236583D01*
G01X1227033Y1231955D02*
X1232233D01*
G01D02*
X1237433D01*
G01X1227883Y1245341D02*
X1232233D01*
G01D02*
X1236583D01*
G01X1218810Y1703640D02*
Y1700732D01*
G01X1236593Y209562D02*
X1238918D01*
X1239018Y209462D01*
G01X1248018Y219662D02*
Y215762D01*
G01Y211762D02*
X1245593D01*
G01X1248018Y223462D02*
Y227462D01*
G01X1245574Y234042D02*
X1246154Y233462D01*
X1248018D01*
G01X1245593Y219662D02*
X1248018D01*
G01Y241462D02*
X1245593D01*
G01X1248018Y237462D02*
X1245593D01*
G01X1246878Y248615D02*
X1248103Y247390D01*
Y245442D01*
G01X1258539Y103352D02*
Y100900D01*
G01X1259018Y217462D02*
X1256504D01*
G01X1259018Y221462D02*
Y217462D01*
G01X1256593Y233972D02*
X1258508D01*
X1259018Y233462D01*
G01Y225462D02*
Y229462D01*
G01X1256593Y225972D02*
X1258508D01*
X1259018Y225462D01*
G01X1256494Y243177D02*
X1256879Y243562D01*
X1259018D01*
G01Y238662D02*
X1256574D01*
G01X1256584Y248002D02*
X1258578D01*
X1259018Y247562D01*
G01X1255150Y303091D02*
Y306211D01*
G01X1259150Y303091D02*
X1255150D01*
G01X1266722Y101005D02*
X1267322Y101605D01*
Y103589D01*
G01X1267179Y96768D02*
Y100548D01*
X1266722Y101005D01*
G01X1266518Y233462D02*
Y237042D01*
G01X1271150Y303091D02*
Y305792D01*
G01X1279812Y1353552D02*
Y1351127D01*
G01X1289210Y81232D02*
Y80172D01*
X1288362Y79324D01*
X1286013D01*
G01X1296999Y209249D02*
X1299134D01*
G01X1311960Y55583D02*
X1309848D01*
X1307810Y57621D01*
X1306294D01*
G01X1314741Y68652D02*
Y66328D01*
X1313788Y65375D01*
G01X1308174Y68652D02*
X1308084Y68562D01*
X1305609D01*
G01X1311960Y58152D02*
Y55583D01*
G01X1315649Y75580D02*
X1315537Y75692D01*
X1311747D01*
X1311636Y75581D01*
G01X1310857Y78542D02*
X1311141Y78258D01*
Y76076D01*
X1311636Y75581D01*
G01X1303264Y74715D02*
X1303374Y74825D01*
X1306824D01*
X1307578Y75579D01*
G01X1307120Y78562D02*
X1307578Y78104D01*
Y75579D01*
G01X1312488Y1348353D02*
Y1350630D01*
X1312346Y1350772D01*
G01X1325902Y65432D02*
X1330102D01*
G01X1325902D02*
X1327332Y66862D01*
Y72577D01*
G01X1316478Y81133D02*
Y76409D01*
X1315649Y75580D01*
G01X1329891Y96898D02*
Y99455D01*
G01X1329646Y107394D02*
Y104954D01*
G01X1322906Y107308D02*
Y109733D01*
G01X1324945Y1346877D02*
X1324304D01*
X1323660Y1347521D01*
X1322385D01*
G01X1315058Y1346882D02*
Y1349488D01*
G01X1345583Y91307D02*
X1345083Y91807D01*
Y93768D01*
G01X1336549Y108370D02*
Y105970D01*
G01X1347015Y1333458D02*
Y1335876D01*
G01X1343631Y1332568D02*
X1343052Y1333147D01*
Y1333846D01*
X1343044Y1333854D01*
Y1335100D01*
G01X1349570Y104147D02*
X1349621Y104198D01*
Y106647D01*
G01X1356903Y1093703D02*
Y1095812D01*
X1356904Y1095813D01*
G01X1354513Y1334095D02*
X1356983D01*
G01X1366124Y101529D02*
X1366001Y101406D01*
Y98670D01*
G01X1366124Y103954D02*
Y101529D01*
G01X1366369Y89645D02*
Y92450D01*
G01X1379271Y1335963D02*
X1379114Y1335806D01*
Y1333428D01*
G01X1375814Y1332653D02*
X1375312Y1332151D01*
Y1330142D01*
G01X1370041Y1403458D02*
X1367316D01*
G01X1370098Y1399053D02*
X1367316D01*
G01X1379465Y1411231D02*
X1377060D01*
G01X1370891Y1413019D02*
Y1410306D01*
G01X1370041Y1407458D02*
X1367316D01*
G01X1382370Y898350D02*
Y896241D01*
X1382371Y896240D01*
G01X1391621Y901555D02*
Y899446D01*
X1391620Y899445D01*
G01X1384221Y901555D02*
Y899446D01*
G01X1395754Y1039230D02*
Y1041339D01*
X1395753Y1041340D01*
G01X1392054Y1039230D02*
Y1041339D01*
X1392053Y1041340D01*
G01X1388354Y1039230D02*
Y1041339D01*
X1388353Y1041340D01*
G01X1390758Y1333473D02*
X1390136Y1334095D01*
X1388259D01*
G01X1388813Y1393160D02*
X1387099D01*
X1386181Y1394078D01*
G01X1384695Y1425047D02*
X1385066Y1424676D01*
Y1422578D01*
G01X1381066D02*
Y1425008D01*
G01X1399021Y901555D02*
Y899446D01*
X1399020Y899445D01*
G01X1406421Y901555D02*
Y899446D01*
X1406420Y899445D01*
G01X1399454Y1039230D02*
Y1041340D01*
G01X1411124Y1333457D02*
Y1335924D01*
G01X1407719Y1332560D02*
X1406871Y1331712D01*
Y1330042D01*
G01X1406833Y1565037D02*
X1404433D01*
G01X1406833Y1570037D02*
X1404433D01*
G01X1399325Y1590200D02*
X1396600D01*
G01X1399325Y1586400D02*
X1396600D01*
G01X1402680Y1600197D02*
Y1597700D01*
G01X1410900Y1622200D02*
Y1624800D01*
G01X1402425Y1634362D02*
X1400000D01*
G01X1402425Y1638362D02*
X1400000D01*
G01X1427203Y1061660D02*
Y1063770D01*
G01X1425354Y1064864D02*
Y1066973D01*
X1425353Y1066974D01*
G01X1418769Y1334095D02*
X1421294D01*
G01X1427349Y1439716D02*
Y1442776D01*
G01X1423519Y1439726D02*
X1423829Y1440036D01*
Y1442776D01*
G01X1417258Y1516435D02*
X1414350D01*
G01X1417498Y1532255D02*
X1414590D01*
G01X1417258Y1521335D02*
X1414350D01*
G01X1417498Y1537155D02*
X1414590D01*
G01X1417648Y1543475D02*
X1414740D01*
G01X1417648Y1548375D02*
X1414740D01*
G01X1419450Y1596150D02*
X1417975Y1594675D01*
Y1593700D01*
G01X1423700Y1600400D02*
X1421792D01*
X1420695Y1601497D01*
Y1603262D01*
G01X1415730Y1603282D02*
X1420675D01*
X1420695Y1603262D01*
G01X1427325Y1612812D02*
X1430250D01*
G01X1444275Y60062D02*
Y57262D01*
G01X1450377Y60322D02*
X1444535D01*
X1444275Y60062D01*
G01X1430903Y1061660D02*
Y1063770D01*
G01X1432754Y1064864D02*
Y1066973D01*
X1432753Y1066974D01*
G01X1429054Y1064864D02*
Y1066973D01*
X1429053Y1066974D01*
G01X1443785Y1333475D02*
Y1335981D01*
G01X1440879Y1333085D02*
X1439796Y1332002D01*
Y1330533D01*
G01X1439155Y1399064D02*
X1440295Y1400204D01*
X1441847D01*
G01X1429317Y1420625D02*
X1431717D01*
G01X1429317Y1417125D02*
X1431717D01*
G01X1429317Y1409125D02*
X1431717D01*
G01X1429317Y1427632D02*
X1431717D01*
G01X1429317Y1424125D02*
X1431717D01*
G01X1440112Y1570610D02*
X1444468D01*
G01X1440105Y1593352D02*
Y1590382D01*
G01D02*
X1440046Y1590441D01*
X1435420D01*
G01X1440825Y1606800D02*
X1438300D01*
G01X1440825Y1602600D02*
X1438300D01*
G01X1439375Y1628700D02*
X1441800D01*
G01X1439375Y1624500D02*
X1441800D01*
G01X1438547Y1640760D02*
Y1638212D01*
G01X1443617Y1640740D02*
Y1638212D01*
G01X1431575Y1637362D02*
Y1634842D01*
G01X1459383Y238125D02*
X1462060D01*
X1463808Y239873D01*
Y242448D01*
G01X1463510Y271378D02*
Y268803D01*
X1461326Y266619D01*
X1458880D01*
G01X1455600Y294275D02*
Y297200D01*
G01X1449600Y399887D02*
Y402322D01*
G01X1455600Y401996D02*
Y405442D01*
X1453695Y407347D01*
X1451780D01*
G01D02*
X1449296D01*
G01X1450897Y1334095D02*
X1453303D01*
G01X1451176Y1399026D02*
X1452673D01*
X1454032Y1400385D01*
G01X1454842Y1526689D02*
X1457577D01*
G01X1455082Y1542509D02*
X1457817D01*
G01X1455232Y1553729D02*
X1457967D01*
G01X1453235Y1590302D02*
X1456030D01*
G01X1454390Y1612800D02*
X1451500D01*
G01X1454167Y1640840D02*
Y1638302D01*
G01X1459127Y1640840D02*
Y1638302D01*
G01X1448507Y1640750D02*
Y1638212D01*
G01X1463808Y242448D02*
Y244948D01*
G01X1463510Y273878D02*
Y271378D01*
G01X1475599Y1346914D02*
Y1349468D01*
G01X1472565Y1628027D02*
Y1623635D01*
G01X1463767Y1640840D02*
Y1638302D01*
G01X1476570Y1661124D02*
X1473527D01*
G01D02*
X1473465Y1661062D01*
X1469720D01*
X1467757Y1659099D01*
Y1655836D01*
G01X1487958Y233448D02*
Y236062D01*
G01X1487660Y255378D02*
X1490060D01*
G01X1495834Y280027D02*
X1493289D01*
G01X1495150Y369842D02*
X1493874Y368566D01*
Y367273D01*
G01X1483025Y1347521D02*
X1485523D01*
G01X1485387Y1422494D02*
Y1420002D01*
G01X1505533Y280056D02*
X1508049D01*
G01X1504602Y310331D02*
Y312867D01*
G01X1500904Y385843D02*
X1496071D01*
X1494561Y384333D01*
Y378788D01*
G01X1503450Y385843D02*
X1500904D01*
G01X1495221Y850286D02*
Y848177D01*
X1495220Y848176D01*
G01X1531917Y116180D02*
X1526118D01*
G01D02*
X1522920D01*
G01X1513900Y117762D02*
X1515200Y116462D01*
X1516425D01*
G01D02*
X1516776Y116813D01*
Y122122D01*
G01X1516993Y249698D02*
X1514593D01*
G01X1516993Y235116D02*
X1514593D01*
G01X1516683Y280956D02*
Y278437D01*
G01X1519833Y288956D02*
X1522258D01*
G01X1515953Y1369919D02*
X1518451D01*
G01X1540090Y122782D02*
X1541600D01*
X1543171Y124353D01*
X1543779D01*
G01X1542377Y152873D02*
Y152233D01*
X1542401Y152209D01*
Y147711D01*
G01X1535520Y151562D02*
X1536831Y152873D01*
X1542377D01*
G01X1529233Y150651D02*
Y153162D01*
G01Y150651D02*
X1530415Y149469D01*
Y145202D01*
G01X1543162Y634165D02*
X1540377D01*
G01X1543720Y584287D02*
Y581862D01*
G01X1548720Y584287D02*
Y581862D01*
G01X1556747Y592490D02*
X1555989Y593248D01*
Y601238D01*
G01X1559557Y593290D02*
X1558757Y592490D01*
X1556747D01*
G01X1557287Y628860D02*
Y625656D01*
X1555989Y624358D01*
Y622038D01*
G01X1554753Y628860D02*
X1557287D01*
G01X1553312Y634165D02*
Y636815D01*
G01X1561494Y584292D02*
X1563994D01*
G01X1564690Y663302D02*
X1566154Y661838D01*
Y659416D01*
G01X1597041Y770144D02*
X1601391D01*
G01D02*
X1605741D01*
G01X1597041Y776837D02*
X1601391D01*
G01D02*
X1605741D01*
G01X1597041Y783530D02*
X1601391D01*
G01D02*
X1605741D01*
G01X1597041Y793570D02*
X1601391D01*
G01D02*
X1605741D01*
G01X1601391Y800263D02*
X1605741D01*
G01X1596988D02*
X1601391D01*
G01Y806955D02*
X1606934D01*
G01X1595774D02*
X1601391D01*
G01Y813648D02*
X1606735D01*
G01X1596218D02*
X1601391D01*
G01Y820341D02*
X1605741D01*
G01X1597041D02*
X1601391D01*
G01Y830381D02*
X1605741D01*
G01X1597041D02*
X1601391D01*
G01X1597041Y837074D02*
X1601391D01*
G01D02*
X1605741D01*
G01X1601391Y843766D02*
X1605741D01*
G01X1597041D02*
X1601391D01*
G01Y850459D02*
X1606896D01*
G01X1596147D02*
X1601391D01*
G01Y857152D02*
X1606623D01*
G01X1596200D02*
X1601391D01*
G01Y867192D02*
X1605741D01*
G01X1597041D02*
X1601391D01*
G01Y873885D02*
X1605741D01*
G01X1597041D02*
X1601391D01*
G01Y880577D02*
X1605741D01*
G01X1597041D02*
X1601391D01*
G01X1605741Y887270D02*
X1601391D01*
G01D02*
X1597041D01*
G01Y893963D02*
X1601391D01*
G01D02*
X1606898D01*
G01X1597041Y904003D02*
X1601391D01*
G01D02*
X1605741D01*
G01X1601391Y917389D02*
X1605741D01*
G01X1597041D02*
X1601391D01*
G01Y910696D02*
X1605741D01*
G01X1597041D02*
X1601391D01*
G01Y924081D02*
X1605741D01*
G01X1597041D02*
X1601391D01*
G01Y930774D02*
X1596047D01*
G01X1606541Y930697D02*
X1605031D01*
X1604954Y930774D01*
X1601391D01*
G01Y940814D02*
X1606919D01*
G01X1596106D02*
X1601391D01*
G01Y947507D02*
X1597041D01*
G01X1605741D02*
X1601391D01*
G01X1597041Y954200D02*
X1601391D01*
G01D02*
X1605741D01*
G01X1601391Y964239D02*
X1605741D01*
G01X1597041D02*
X1601391D01*
G01Y977625D02*
X1605741D01*
G01X1597041D02*
X1601391D01*
G01Y970932D02*
X1597041D01*
G01X1605741D02*
X1601391D01*
G01Y984318D02*
X1605741D01*
G01X1597041D02*
X1601391D01*
G01Y991011D02*
X1605741D01*
G01X1597041D02*
X1601391D01*
G01Y1024475D02*
X1605741D01*
G01X1597041D02*
X1601391D01*
G01Y1017782D02*
X1605741D01*
G01X1597041D02*
X1601391D01*
G01Y1031168D02*
X1605741D01*
G01X1597041D02*
X1601391D01*
G01Y1037861D02*
X1605741D01*
G01X1597041D02*
X1601391D01*
G01Y1044554D02*
X1605741D01*
G01X1597041D02*
X1601391D01*
G01X1597041Y1051247D02*
X1601391D01*
G01D02*
X1605741D01*
G01X1601391Y1057940D02*
X1605741D01*
G01X1597041D02*
X1601391D01*
G01Y1064633D02*
X1605741D01*
G01X1597041D02*
X1601391D01*
G01Y1071326D02*
X1596141D01*
G01X1606541D02*
X1601391D01*
G01Y1078018D02*
X1605741D01*
G01X1597041D02*
X1601391D01*
G01X1597041Y1094751D02*
X1601391D01*
G01D02*
X1605741D01*
G01X1601391Y1088058D02*
X1605741D01*
G01X1597041D02*
X1601391D01*
G01Y1101444D02*
X1597041D01*
G01X1605741D02*
X1601391D01*
G01Y1108137D02*
X1605741D01*
G01X1597041D02*
X1601391D01*
G01Y1114829D02*
X1596241D01*
G01X1606541D02*
X1601391D01*
G01X1606505Y1124674D02*
X1605436D01*
X1605241Y1124869D01*
X1601391D01*
G01X1596511Y1124969D02*
X1596611Y1124869D01*
X1601391D01*
G01X1597041Y1138255D02*
X1601391D01*
G01D02*
X1605741D01*
G01X1597041Y1144948D02*
X1601391D01*
G01D02*
X1605741D01*
G01X1601391Y1131562D02*
X1605741D01*
G01X1597041D02*
X1601391D01*
G01X1605975Y1161581D02*
X1605876Y1161680D01*
X1601391D01*
G01X1597041Y1151641D02*
X1601391D01*
G01D02*
X1605741D01*
G01X1601391Y1161680D02*
X1596653D01*
G01X1597041Y1168373D02*
X1601391D01*
G01D02*
X1605741D01*
G01X1597041Y1175066D02*
X1601391D01*
G01D02*
X1605741D01*
G01X1597041Y1181759D02*
X1601391D01*
G01D02*
X1605741D01*
G01X1597041Y1188452D02*
X1601391D01*
G01D02*
X1606765D01*
G01X1605741Y1198491D02*
X1601391D01*
G01D02*
X1597041D01*
G01Y1205184D02*
X1601391D01*
G01D02*
X1605741D01*
G01X1601391Y1211877D02*
X1605741D01*
G01X1597041D02*
X1601391D01*
G01Y1218570D02*
X1605741D01*
G01X1597041D02*
X1601391D01*
G01Y1225263D02*
X1605741D01*
G01X1597041D02*
X1601391D01*
G01Y1235302D02*
X1596178D01*
G01X1607064D02*
X1601391D01*
G01Y1241995D02*
X1597041D01*
G01X1605741D02*
X1601391D01*
G01X1605741Y1248688D02*
X1601391D01*
G01D02*
X1597041D01*
G01X1606481Y1258649D02*
X1606151D01*
X1606073Y1258727D01*
X1601391D01*
G01X1600491Y1411169D02*
X1614116D01*
G01X1612630Y1418842D02*
X1611303Y1420169D01*
X1600491D01*
G01Y1415669D02*
X1613047D01*
G01X1600491Y1433669D02*
X1615597D01*
G01X1600491Y1438169D02*
Y1433669D01*
G01Y1429169D02*
Y1424669D01*
G01X1615062Y1421241D02*
X1611634Y1424669D01*
X1600491D01*
G01X1606980Y1449922D02*
X1604831Y1452071D01*
X1600491D01*
G01Y1447153D02*
Y1442669D01*
G01X1617215Y1440822D02*
X1615368Y1442669D01*
X1600491D01*
G01X1621883Y766798D02*
X1617533D01*
G01D02*
X1613183D01*
G01Y773491D02*
X1617533D01*
G01D02*
X1621883D01*
G01X1613183Y780184D02*
X1617533D01*
G01D02*
X1621883D01*
G01X1613183Y790223D02*
X1617533D01*
G01D02*
X1621883D01*
G01X1617533Y796916D02*
X1621883D01*
G01X1613183D02*
X1617533D01*
G01Y803609D02*
X1621883D01*
G01X1613183D02*
X1617533D01*
G01Y816995D02*
X1613183D01*
G01X1622916D02*
X1617533D01*
G01Y810302D02*
X1622986D01*
G01X1612363D02*
X1617533D01*
G01Y827034D02*
X1621883D01*
G01X1613183D02*
X1617533D01*
G01Y833727D02*
X1613183D01*
G01X1621883D02*
X1617533D01*
G01Y840420D02*
X1621883D01*
G01X1613183D02*
X1617533D01*
G01Y847113D02*
X1621943D01*
G01X1613183D02*
X1617533D01*
G01X1612408Y863845D02*
X1617533D01*
G01D02*
X1622060D01*
G01X1617533Y853806D02*
X1622961D01*
G01X1612474Y853955D02*
X1612748D01*
X1612897Y853806D01*
X1617533D01*
G01X1613183Y883924D02*
X1617533D01*
G01D02*
X1621883D01*
G01X1617533Y870538D02*
X1621883D01*
G01X1613183D02*
X1617533D01*
G01Y877231D02*
X1621883D01*
G01X1613183D02*
X1617533D01*
G01X1621883Y890617D02*
X1617533D01*
G01D02*
X1613183D01*
G01X1621883Y900656D02*
X1617533D01*
G01D02*
X1613183D01*
G01Y907349D02*
X1617533D01*
G01D02*
X1621883D01*
G01X1617533Y914042D02*
X1621883D01*
G01X1613183D02*
X1617533D01*
G01Y920735D02*
X1613183D01*
G01X1621883D02*
X1617533D01*
G01Y927428D02*
X1612168D01*
G01X1622535Y927526D02*
X1617631D01*
X1617533Y927428D01*
G01Y937467D02*
X1612312D01*
G01X1622845D02*
X1617533D01*
G01Y944160D02*
X1613183D01*
G01X1621883D02*
X1617533D01*
G01X1613183Y950853D02*
X1617533D01*
G01D02*
X1621883D01*
G01X1617533Y960892D02*
X1613183D01*
G01X1621883D02*
X1617533D01*
G01Y974278D02*
X1621883D01*
G01X1613183D02*
X1617533D01*
G01Y980971D02*
X1621883D01*
G01X1613183D02*
X1617533D01*
G01Y967585D02*
X1621883D01*
G01X1613183D02*
X1617533D01*
G01Y987664D02*
X1621883D01*
G01X1613183D02*
X1617533D01*
G01Y1017782D02*
X1613183D01*
G01X1621883D02*
X1617533D01*
G01Y1027822D02*
X1621883D01*
G01X1613183D02*
X1617533D01*
G01Y1034515D02*
X1621883D01*
G01X1613183D02*
X1617533D01*
G01Y1041207D02*
X1621883D01*
G01X1613183D02*
X1617533D01*
G01Y1047900D02*
X1621883D01*
G01X1613183D02*
X1617533D01*
G01X1613183Y1054593D02*
X1617533D01*
G01D02*
X1621883D01*
G01X1617533Y1061286D02*
X1621883D01*
G01X1613183D02*
X1617533D01*
G01Y1067979D02*
X1612983D01*
G01X1621883D02*
X1617533D01*
G01Y1074672D02*
X1622683D01*
G01X1612283D02*
X1617533D01*
G01Y1084711D02*
X1612383D01*
G01X1621883D02*
X1617533D01*
G01Y1091404D02*
X1621883D01*
G01X1613183D02*
X1617533D01*
G01X1613183Y1104790D02*
X1617533D01*
G01D02*
X1621883D01*
G01X1617533Y1098097D02*
X1613183D01*
G01X1621883D02*
X1617533D01*
G01Y1111483D02*
X1613183D01*
G01X1621883D02*
X1617533D01*
G01Y1128215D02*
X1621883D01*
G01X1613183Y1128915D02*
Y1128715D01*
X1613683Y1128215D01*
X1617533D01*
G01Y1121522D02*
X1621883D01*
G01X1613183D02*
X1617533D01*
G01Y1141601D02*
X1613183D01*
G01X1621883D02*
X1617533D01*
G01Y1134908D02*
X1611886D01*
G01X1622726Y1135108D02*
X1621883D01*
X1621683Y1134908D01*
X1617533D01*
G01X1613183Y1158333D02*
X1617533D01*
G01D02*
X1621883D01*
G01X1617533Y1148294D02*
X1613183D01*
G01X1621883D02*
X1617533D01*
G01X1613183Y1165026D02*
X1617533D01*
G01D02*
X1621883D01*
G01Y1171719D02*
X1617533D01*
G01D02*
X1613183D01*
G01Y1178412D02*
X1617533D01*
G01D02*
X1621883D01*
G01X1613183Y1185105D02*
X1617533D01*
G01D02*
X1621883D01*
G01Y1195144D02*
X1617533D01*
G01D02*
X1613183D01*
G01Y1201837D02*
X1617533D01*
G01D02*
X1621883D01*
G01X1613183Y1208530D02*
X1617533D01*
G01D02*
X1621883D01*
G01X1617533Y1215223D02*
X1613183D01*
G01X1621883D02*
X1617533D01*
G01Y1221916D02*
X1622712D01*
G01X1612147D02*
X1617533D01*
G01Y1231955D02*
X1622681D01*
G01X1612137Y1231862D02*
X1612437D01*
X1612530Y1231955D01*
X1617533D01*
G01Y1238648D02*
X1613183D01*
G01X1621883D02*
X1617533D01*
G01Y1245341D02*
X1613183D01*
G01X1621883D02*
X1617533D01*
G01X1614927Y1426076D02*
X1617037D01*
X1617327Y1426366D01*
G01Y1429896D02*
X1614927D01*
G01X1626741Y770144D02*
X1631091D01*
G01D02*
X1635441D01*
G01X1626741Y776837D02*
X1631091D01*
G01D02*
X1635441D01*
G01X1626741Y783530D02*
X1631091D01*
G01D02*
X1635441D01*
G01X1626741Y793570D02*
X1631091D01*
G01D02*
X1635441D01*
G01X1631091Y800263D02*
X1635441D01*
G01X1626741D02*
X1631091D01*
G01Y813648D02*
X1636574D01*
G01X1626741D02*
X1631091D01*
G01Y806955D02*
X1635441D01*
G01X1626741D02*
X1631091D01*
G01Y820341D02*
X1636341D01*
G01X1626741D02*
X1631091D01*
G01Y830381D02*
X1635441D01*
G01X1626741D02*
X1631091D01*
G01X1626741Y837074D02*
X1631091D01*
G01D02*
X1635441D01*
G01X1631091Y843766D02*
X1635441D01*
G01X1626741D02*
X1631091D01*
G01Y850459D02*
X1635441D01*
G01X1626741D02*
X1631091D01*
G01X1625705Y867192D02*
X1631091D01*
G01D02*
X1636441D01*
G01X1631091Y857152D02*
X1635441D01*
G01X1626741D02*
X1631091D01*
G01X1626741Y880577D02*
X1631091D01*
G01D02*
X1635441D01*
G01X1631091Y873885D02*
X1635441D01*
G01X1626741D02*
X1631091D01*
G01X1626741Y887270D02*
X1631091D01*
G01D02*
X1635441D01*
G01X1626741Y893963D02*
X1631091D01*
G01D02*
X1635441D01*
G01X1626741Y904003D02*
X1631091D01*
G01D02*
X1635441D01*
G01X1631091Y910696D02*
X1635441D01*
G01X1626741D02*
X1631091D01*
G01Y917389D02*
X1635441D01*
G01X1626741D02*
X1631091D01*
G01Y930774D02*
X1636316D01*
G01X1625803D02*
X1631091D01*
G01Y924081D02*
X1636646D01*
G01X1626741D02*
X1631091D01*
G01Y940814D02*
X1635441D01*
G01X1626741D02*
X1631091D01*
G01Y947507D02*
X1635441D01*
G01X1626741D02*
X1631091D01*
G01X1626741Y954200D02*
X1631091D01*
G01D02*
X1635441D01*
G01X1631091Y964239D02*
X1635441D01*
G01X1626741D02*
X1631091D01*
G01Y977625D02*
X1635441D01*
G01X1626741D02*
X1631091D01*
G01Y970932D02*
X1635441D01*
G01X1626741D02*
X1631091D01*
G01Y984318D02*
X1635441D01*
G01X1626741D02*
X1631091D01*
G01Y991011D02*
X1635441D01*
G01X1626741D02*
X1631091D01*
G01Y1024475D02*
X1635441D01*
G01X1626741D02*
X1631091D01*
G01Y1017782D02*
X1635441D01*
G01X1626741D02*
X1631091D01*
G01Y1031168D02*
X1635441D01*
G01X1626741D02*
X1631091D01*
G01Y1037861D02*
X1635441D01*
G01X1626741D02*
X1631091D01*
G01Y1044554D02*
X1635441D01*
G01X1626741D02*
X1631091D01*
G01X1626741Y1057940D02*
X1631091D01*
G01D02*
X1635441D01*
G01X1631091Y1051247D02*
X1635441D01*
G01X1626741D02*
X1631091D01*
G01Y1064633D02*
X1635441D01*
G01X1626741D02*
X1631091D01*
G01Y1071326D02*
X1635441D01*
G01X1626741D02*
X1631091D01*
G01Y1078018D02*
X1636241D01*
G01X1625941D02*
X1631091D01*
G01Y1088058D02*
X1636241D01*
G01X1625941D02*
X1631091D01*
G01Y1094751D02*
X1635441D01*
G01X1626741D02*
X1631091D01*
G01X1626741Y1101444D02*
X1631091D01*
G01D02*
X1635441D01*
G01X1626741Y1108137D02*
X1631091D01*
G01D02*
X1635441D01*
G01X1631091Y1124869D02*
X1636341D01*
G01X1626074Y1124640D02*
X1626303Y1124869D01*
X1631091D01*
G01Y1114829D02*
X1635441D01*
G01X1626741D02*
X1631091D01*
G01Y1144948D02*
X1635441D01*
G01X1626741D02*
X1631091D01*
G01Y1138255D02*
X1635441D01*
G01X1626741D02*
X1631091D01*
G01X1626741Y1130762D02*
X1627541Y1131562D01*
X1631091D01*
G01X1635441Y1130762D02*
X1634641Y1131562D01*
X1631091D01*
G01Y1151641D02*
X1635441D01*
G01X1626741D02*
X1631091D01*
G01X1626741Y1161680D02*
X1631091D01*
G01D02*
X1635441D01*
G01X1626741Y1168373D02*
X1631091D01*
G01D02*
X1635441D01*
G01X1626741Y1175066D02*
X1631091D01*
G01D02*
X1635441D01*
G01X1626741Y1181759D02*
X1631091D01*
G01D02*
X1635441D01*
G01X1626741Y1188452D02*
X1631091D01*
G01D02*
X1635441D01*
G01X1626741Y1198491D02*
X1631091D01*
G01D02*
X1635441D01*
G01X1626741Y1205184D02*
X1631091D01*
G01D02*
X1635441D01*
G01X1631091Y1211877D02*
X1635441D01*
G01X1626741D02*
X1631091D01*
G01Y1218570D02*
X1635441D01*
G01X1626741D02*
X1631091D01*
G01Y1225263D02*
X1636212D01*
G01X1626055D02*
X1631091D01*
G01Y1235302D02*
X1636376D01*
G01X1625843D02*
X1631091D01*
G01Y1241995D02*
X1635441D01*
G01X1626741D02*
X1631091D01*
G01X1626741Y1248688D02*
X1631091D01*
G01D02*
X1635441D01*
G01X1631091Y1258727D02*
X1626741D01*
G01X1627591Y1445155D02*
Y1447796D01*
G01X1637478Y1445150D02*
Y1445294D01*
X1636978Y1445794D01*
X1634918D01*
G01X1660636Y179313D02*
X1659489Y180460D01*
X1645030D01*
G01D02*
Y185952D01*
G01X1652113Y527325D02*
X1652859Y528071D01*
X1654654D01*
G01X1652138Y524071D02*
X1654654D01*
G01Y540071D02*
X1651931D01*
G01X1654654Y536071D02*
X1651931D01*
G01X1654654Y532071D02*
Y536071D01*
G01X1649291Y552310D02*
Y556057D01*
G01X1651112Y545572D02*
X1653704D01*
X1654654Y544622D01*
G01X1656550Y653086D02*
X1655702Y653934D01*
X1654032D01*
G01X1656550Y687086D02*
X1655702Y687934D01*
X1654032D01*
G01X1651583Y766798D02*
X1647233D01*
G01D02*
X1642883D01*
G01X1651583Y773491D02*
X1647233D01*
G01D02*
X1642883D01*
G01X1651583Y780184D02*
X1647233D01*
G01D02*
X1642883D01*
G01X1651583Y790223D02*
X1647233D01*
G01D02*
X1642883D01*
G01X1651583Y796916D02*
X1647233D01*
G01D02*
X1642883D01*
G01X1647233Y803609D02*
X1642883D01*
G01X1651583D02*
X1647233D01*
G01Y810302D02*
X1642883D01*
G01X1651583D02*
X1647233D01*
G01Y816995D02*
X1641945D01*
G01X1652545D02*
X1647233D01*
G01Y827034D02*
X1642018D01*
G01X1652767D02*
X1647233D01*
G01Y833727D02*
X1642883D01*
G01X1651583D02*
X1647233D01*
G01X1651583Y840420D02*
X1647233D01*
G01D02*
X1642883D01*
G01X1647233Y847113D02*
X1642883D01*
G01X1651583D02*
X1647233D01*
G01X1652742Y863845D02*
X1647233D01*
G01D02*
X1642058D01*
G01X1647233Y853806D02*
X1642032D01*
G01X1652559D02*
X1647233D01*
G01X1651583Y883924D02*
X1647233D01*
G01D02*
X1642883D01*
G01X1647233Y870538D02*
X1642883D01*
G01X1651583D02*
X1647233D01*
G01Y877231D02*
X1642883D01*
G01X1651583D02*
X1647233D01*
G01X1651583Y890617D02*
X1647233D01*
G01D02*
X1642883D01*
G01X1651583Y900656D02*
X1647233D01*
G01D02*
X1642883D01*
G01X1651583Y907349D02*
X1647233D01*
G01D02*
X1642883D01*
G01X1647233Y914042D02*
X1642883D01*
G01X1651583D02*
X1647233D01*
G01Y927428D02*
X1642038D01*
G01X1652630D02*
X1647233D01*
G01Y920735D02*
X1642883D01*
G01X1651583D02*
X1647233D01*
G01Y937467D02*
X1642065D01*
G01X1652501D02*
X1647233D01*
G01Y944160D02*
X1642883D01*
G01X1651583D02*
X1647233D01*
G01X1651583Y950853D02*
X1647233D01*
G01D02*
X1642883D01*
G01X1647233Y960892D02*
X1642883D01*
G01X1651583D02*
X1647233D01*
G01Y967585D02*
X1642883D01*
G01X1651583D02*
X1647233D01*
G01Y974278D02*
X1642883D01*
G01X1651583D02*
X1647233D01*
G01Y980971D02*
X1642883D01*
G01X1651583D02*
X1647233D01*
G01Y987664D02*
X1642883D01*
G01X1651583D02*
X1647233D01*
G01Y1017782D02*
X1642883D01*
G01X1651583D02*
X1647233D01*
G01Y1027822D02*
X1642883D01*
G01X1651583D02*
X1647233D01*
G01Y1034515D02*
X1642883D01*
G01X1651583D02*
X1647233D01*
G01Y1041207D02*
X1642883D01*
G01X1651583D02*
X1647233D01*
G01Y1047900D02*
X1642883D01*
G01X1651583D02*
X1647233D01*
G01X1651583Y1061286D02*
X1647233D01*
G01D02*
X1642883D01*
G01X1647233Y1054593D02*
X1642883D01*
G01X1651583D02*
X1647233D01*
G01Y1074672D02*
X1641983D01*
G01X1652483D02*
X1647233D01*
G01Y1067979D02*
X1642883D01*
G01X1651583D02*
X1647233D01*
G01Y1084711D02*
X1642083D01*
G01X1652383D02*
X1647233D01*
G01Y1091404D02*
X1642883D01*
G01X1651583D02*
X1647233D01*
G01X1651583Y1098097D02*
X1647233D01*
G01D02*
X1642883D01*
G01X1651583Y1104790D02*
X1647233D01*
G01D02*
X1642883D01*
G01X1651583Y1111483D02*
X1647233D01*
G01D02*
X1642883D01*
G01X1651583Y1121522D02*
X1647233D01*
G01D02*
X1642883D01*
G01X1651583Y1128215D02*
X1647233D01*
G01D02*
X1642883D01*
G01X1651583Y1134908D02*
X1647233D01*
G01D02*
X1642883D01*
G01X1651583Y1141601D02*
X1647233D01*
G01D02*
X1642883D01*
G01X1647233Y1158333D02*
X1642083D01*
G01X1652383D02*
X1647233D01*
G01Y1148294D02*
X1641744D01*
G01X1652794D02*
X1647233D01*
G01X1651583Y1171719D02*
X1647233D01*
G01D02*
X1642883D01*
G01X1647233Y1165026D02*
X1642883D01*
G01X1651583D02*
X1647233D01*
G01X1642883Y1178412D02*
X1647233D01*
G01D02*
X1651583D01*
G01X1642883Y1185105D02*
X1647233D01*
G01D02*
X1651583D01*
G01Y1195144D02*
X1647233D01*
G01D02*
X1642883D01*
G01X1651583Y1201837D02*
X1647233D01*
G01D02*
X1642883D01*
G01X1651583Y1208530D02*
X1647233D01*
G01D02*
X1642883D01*
G01X1647233Y1221916D02*
X1641793D01*
G01X1652590D02*
X1647233D01*
G01Y1215223D02*
X1642883D01*
G01X1651583D02*
X1647233D01*
G01Y1231955D02*
X1642054D01*
G01X1652604D02*
X1647233D01*
G01Y1238648D02*
X1642883D01*
G01X1651583D02*
X1647233D01*
G01Y1245341D02*
X1642883D01*
G01X1651583D02*
X1647233D01*
G01X1656170Y1260352D02*
X1657795Y1258727D01*
X1660791D01*
G01X1664376Y187187D02*
X1667739D01*
G01X1674755Y202806D02*
X1672181Y205380D01*
X1666038D01*
G01X1663376Y515531D02*
Y518013D01*
G01X1667376Y515531D02*
Y518013D01*
G01X1661132Y620434D02*
X1663720D01*
G01X1661120Y617037D02*
X1661776D01*
X1663202Y615611D01*
X1666894D01*
X1668920Y617637D01*
G01X1661120Y613887D02*
X1662016Y612991D01*
X1668324D01*
X1669397Y614064D01*
G01X1658085Y642036D02*
Y639511D01*
G01X1657447Y649681D02*
X1659914D01*
G01X1658085Y676036D02*
Y673511D01*
G01X1657447Y683681D02*
X1659914D01*
G01X1658085Y710036D02*
Y707511D01*
G01X1657447Y717681D02*
X1659914D01*
G01X1656441Y770144D02*
X1660791D01*
G01D02*
X1665141D01*
G01X1672583Y766798D02*
X1676933D01*
G01X1656441Y776837D02*
X1660791D01*
G01D02*
X1665141D01*
G01X1656441Y783530D02*
X1660791D01*
G01D02*
X1665141D01*
G01X1672583Y773491D02*
X1676933D01*
G01X1672583Y780184D02*
X1676933D01*
G01X1656441Y793570D02*
X1660791D01*
G01D02*
X1665141D01*
G01X1656441Y800263D02*
X1660791D01*
G01D02*
X1665141D01*
G01X1672583Y790223D02*
X1676933D01*
G01X1672583Y796916D02*
X1676933D01*
G01X1672583Y803609D02*
X1676933D01*
G01X1656441Y806955D02*
X1660791D01*
G01D02*
X1665141D01*
G01X1656441Y813648D02*
X1660791D01*
G01D02*
X1665141D01*
G01X1672583Y810302D02*
X1676933D01*
G01X1672583Y816995D02*
X1676933D01*
G01X1656441Y820341D02*
X1660791D01*
G01D02*
X1666030D01*
G01X1656441Y830381D02*
X1660791D01*
G01D02*
X1665141D01*
G01X1672583Y827034D02*
X1676933D01*
G01Y833727D02*
X1672583D01*
G01X1656441Y837074D02*
X1660791D01*
G01D02*
X1665141D01*
G01X1656441Y843766D02*
X1660791D01*
G01D02*
X1665141D01*
G01X1656441Y850459D02*
X1660791D01*
G01D02*
X1665141D01*
G01X1672583Y840420D02*
X1676933D01*
G01X1672583Y847113D02*
X1676933D01*
G01X1656441Y857152D02*
X1660791D01*
G01D02*
X1666038D01*
G01X1656441Y867192D02*
X1660791D01*
G01D02*
X1665141D01*
G01X1672583Y853806D02*
X1676933D01*
G01X1672583Y863845D02*
X1676933D01*
G01X1656441Y873885D02*
X1660791D01*
G01D02*
X1665141D01*
G01X1656441Y880577D02*
X1660791D01*
G01D02*
X1665141D01*
G01X1672583Y870538D02*
X1676933D01*
G01X1672583Y877231D02*
X1676933D01*
G01X1672583Y883924D02*
X1676933D01*
G01X1656441Y887270D02*
X1660791D01*
G01D02*
X1665141D01*
G01X1656441Y893963D02*
X1660791D01*
G01D02*
X1665141D01*
G01X1672583Y890617D02*
X1676933D01*
G01X1672583Y900656D02*
X1676933D01*
G01X1656441Y904003D02*
X1660791D01*
G01D02*
X1665141D01*
G01X1656441Y910696D02*
X1660791D01*
G01D02*
X1665141D01*
G01X1656441Y917389D02*
X1660791D01*
G01D02*
X1665141D01*
G01X1676933Y907349D02*
X1672583D01*
G01Y914042D02*
X1676933D01*
G01X1656441Y924081D02*
X1660791D01*
G01D02*
X1665141D01*
G01X1656441Y930774D02*
X1660791D01*
G01D02*
X1666246D01*
G01X1672583Y920735D02*
X1676933D01*
G01X1672583Y927428D02*
X1676933D01*
G01X1656441Y940814D02*
X1660791D01*
G01D02*
X1665141D01*
G01X1656441Y947507D02*
X1660791D01*
G01D02*
X1665141D01*
G01X1672583Y937467D02*
X1676933D01*
G01Y944160D02*
X1672583D01*
G01X1656441Y954200D02*
X1660791D01*
G01D02*
X1665141D01*
G01X1660791Y964239D02*
X1665141D01*
G01X1656441D02*
X1660791D01*
G01X1672583Y950853D02*
X1676933D01*
G01X1672583Y960892D02*
X1676933D01*
G01X1656441Y977625D02*
X1660791D01*
G01D02*
X1665141D01*
G01X1660791Y970932D02*
X1665141D01*
G01X1656441D02*
X1660791D01*
G01X1672583Y967585D02*
X1676933D01*
G01X1672583Y974278D02*
X1676933D01*
G01X1672583Y980971D02*
X1676933D01*
G01X1656441Y984318D02*
X1660791D01*
G01D02*
X1665141D01*
G01X1656441Y991011D02*
X1660791D01*
G01D02*
X1665141D01*
G01X1672583Y987664D02*
X1676933D01*
G01X1660791Y1017782D02*
X1665141D01*
G01X1656441D02*
X1660791D01*
G01Y1024475D02*
X1665141D01*
G01X1656441D02*
X1660791D01*
G01Y1031168D02*
X1665141D01*
G01X1656441D02*
X1660791D01*
G01X1672583Y1017782D02*
X1676933D01*
G01X1672583Y1027822D02*
X1676933D01*
G01X1656441Y1044554D02*
X1660791D01*
G01D02*
X1665141D01*
G01X1660791Y1037861D02*
X1665141D01*
G01X1656441D02*
X1660791D01*
G01X1672583Y1034515D02*
X1676933D01*
G01X1672583Y1041207D02*
X1676933D01*
G01X1656441Y1051247D02*
X1660791D01*
G01Y1057940D02*
X1665141D01*
G01X1656441D02*
X1660791D01*
G01X1672583Y1047900D02*
X1676933D01*
G01X1672583Y1061286D02*
X1676933D01*
G01X1672583Y1054593D02*
X1676933D01*
G01X1665141Y1071326D02*
X1660791D01*
G01D02*
X1656441D01*
G01Y1064633D02*
X1660791D01*
G01D02*
X1665141D01*
G01Y1077118D02*
X1664241Y1078018D01*
X1660791D01*
G01X1656441D02*
X1660791D01*
G01X1672583Y1067979D02*
X1676933D01*
G01Y1074672D02*
X1672583D01*
G01X1665141Y1094751D02*
X1660791D01*
G01D02*
X1656441D01*
G01X1665141Y1088058D02*
X1660791D01*
G01D02*
X1656441D01*
G01X1676933Y1084711D02*
X1672583D01*
G01X1676933Y1091404D02*
X1672583D01*
G01X1665141Y1108137D02*
X1660791D01*
G01D02*
X1656441D01*
G01X1665141Y1101444D02*
X1660791D01*
G01D02*
X1656441D01*
G01X1676933Y1098097D02*
X1672583D01*
G01X1676933Y1104790D02*
X1672583D01*
G01X1676933Y1111483D02*
X1672583D01*
G01X1665141Y1124869D02*
X1660791D01*
G01D02*
X1656441D01*
G01X1665141Y1114829D02*
X1660791D01*
G01D02*
X1656441D01*
G01X1676933Y1121522D02*
X1672583D01*
G01X1676933Y1128215D02*
X1672583D01*
G01X1665141Y1144948D02*
X1660791D01*
G01D02*
X1656441D01*
G01X1665141Y1138255D02*
X1660791D01*
G01D02*
X1656441D01*
G01X1665141Y1131562D02*
X1660791D01*
G01D02*
X1656441D01*
G01X1676933Y1134908D02*
X1672583D01*
G01X1676933Y1141601D02*
X1672583D01*
G01X1666141Y1151641D02*
X1660791D01*
G01D02*
X1656441D01*
G01X1676933Y1148294D02*
X1672583D01*
G01X1676933Y1158333D02*
X1672583D01*
G01X1665141Y1175066D02*
X1660791D01*
G01D02*
X1656441D01*
G01X1665141Y1168373D02*
X1660791D01*
G01D02*
X1656441D01*
G01X1665141Y1161680D02*
X1660791D01*
G01D02*
X1656441D01*
G01X1676933Y1165026D02*
X1672583D01*
G01X1676933Y1171719D02*
X1672583D01*
G01X1665141Y1188452D02*
X1660791D01*
G01D02*
X1656441D01*
G01X1665141Y1181759D02*
X1660791D01*
G01D02*
X1656441D01*
G01X1676933Y1178412D02*
X1672583D01*
G01X1676933Y1185105D02*
X1672583D01*
G01X1665141Y1205184D02*
X1660791D01*
G01D02*
X1656441D01*
G01X1665141Y1198491D02*
X1660791D01*
G01D02*
X1656441D01*
G01X1676933Y1195144D02*
X1672583D01*
G01X1676933Y1201837D02*
X1672583D01*
G01X1676933Y1208530D02*
X1672583D01*
G01X1660791Y1218570D02*
X1656441D01*
G01X1665141D02*
X1660791D01*
G01Y1225263D02*
X1656441D01*
G01X1665941D02*
X1660791D01*
G01X1665141Y1211877D02*
X1660791D01*
G01D02*
X1656441D01*
G01X1676933Y1215223D02*
X1672583D01*
G01X1676933Y1221916D02*
X1672583D01*
G01X1665141Y1235302D02*
X1660791D01*
G01D02*
X1656441D01*
G01Y1241995D02*
X1660791D01*
G01D02*
X1665141D01*
G01X1676933Y1231955D02*
X1672583D01*
G01X1676933Y1238648D02*
X1672583D01*
G01X1656441Y1248688D02*
X1660791D01*
G01D02*
X1665141D01*
G01X1676933Y1245341D02*
X1672583D01*
G01X1667577Y1447545D02*
X1665734Y1445702D01*
Y1445155D01*
G01X1668523Y1493362D02*
X1666123D01*
G01X1668523Y1516862D02*
Y1520862D01*
G01Y1524862D02*
X1666123D01*
G01X1668523Y1533862D02*
X1666123D01*
G01X1668523Y1545862D02*
X1666123D01*
G01X1668523Y1553557D02*
X1666123D01*
G01X1668598Y1565557D02*
X1666198D01*
G01X1668523Y1557557D02*
X1666123D01*
G01X1668598Y1561557D02*
X1666198D01*
G01X1668598Y1581321D02*
X1666198D01*
G01X1668598Y1585321D02*
X1666198D01*
G01X1674755Y201670D02*
Y202806D01*
G01X1684790Y409442D02*
Y399762D01*
X1686660Y397892D01*
X1712390D01*
X1714444Y399946D01*
Y404220D01*
X1715044Y404820D01*
Y406970D01*
G01X1683394Y469878D02*
X1685920D01*
G01X1683476Y473378D02*
X1683976Y473878D01*
X1685920D01*
G01X1684356Y476290D02*
Y478790D01*
G01X1681602Y485180D02*
X1683992Y482790D01*
X1684356D01*
G01Y488290D02*
Y485628D01*
G01X1679913Y491790D02*
X1677464D01*
G01X1676933Y766798D02*
X1681283D01*
G01X1686141Y770144D02*
X1690491D01*
G01X1676933Y773491D02*
X1681283D01*
G01X1676933Y780184D02*
X1681283D01*
G01X1686141Y776837D02*
X1690491D01*
G01X1686141Y783530D02*
X1690491D01*
G01X1676933Y790223D02*
X1681283D01*
G01X1676933Y796916D02*
X1681283D01*
G01X1676933Y803609D02*
X1681283D01*
G01X1686141Y793570D02*
X1690491D01*
G01X1686141Y800263D02*
X1690491D01*
G01X1676933Y810302D02*
X1681283D01*
G01X1676933Y816995D02*
X1681283D01*
G01X1686141Y806955D02*
X1690491D01*
G01X1686141Y813648D02*
X1690491D01*
G01X1676933Y827034D02*
X1681283D01*
G01Y833727D02*
X1676933D01*
G01X1686141Y820341D02*
X1690491D01*
G01X1686141Y830381D02*
X1690491D01*
G01X1676933Y840420D02*
X1681283D01*
G01X1676933Y847113D02*
X1681283D01*
G01X1686141Y837074D02*
X1690491D01*
G01X1686141Y843766D02*
X1690491D01*
G01X1686141Y850459D02*
X1690491D01*
G01X1676933Y853806D02*
X1681283D01*
G01X1676933Y863845D02*
X1681283D01*
G01X1686141Y857152D02*
X1690491D01*
G01X1686141Y867192D02*
X1690491D01*
G01X1676933Y870538D02*
X1681283D01*
G01X1676933Y877231D02*
X1681283D01*
G01X1676933Y883924D02*
X1681283D01*
G01X1686141Y873885D02*
X1690491D01*
G01X1686141Y880577D02*
X1690491D01*
G01X1676933Y890617D02*
X1681283D01*
G01X1676933Y900656D02*
X1681283D01*
G01X1686141Y887270D02*
X1690491D01*
G01X1686141Y893963D02*
X1690491D01*
G01X1681283Y907349D02*
X1676933D01*
G01Y914042D02*
X1681283D01*
G01X1686141Y904003D02*
X1690491D01*
G01X1686141Y910696D02*
X1690491D01*
G01X1686141Y917389D02*
X1690491D01*
G01X1676933Y920735D02*
X1681283D01*
G01X1676933Y927428D02*
X1681283D01*
G01X1686141Y924081D02*
X1690491D01*
G01X1686141Y930774D02*
X1690491D01*
G01X1676933Y937467D02*
X1681283D01*
G01Y944160D02*
X1676933D01*
G01X1686141Y940814D02*
X1690491D01*
G01X1686141Y947507D02*
X1690491D01*
G01X1676933Y950853D02*
X1681283D01*
G01X1676933Y960892D02*
X1681283D01*
G01X1686141Y954200D02*
X1690491D01*
G01X1686141Y964239D02*
X1690491D01*
G01X1676933Y967585D02*
X1681283D01*
G01X1676933Y974278D02*
X1681283D01*
G01X1676933Y980971D02*
X1681283D01*
G01X1686141Y970932D02*
X1690491D01*
G01X1686141Y977625D02*
X1690491D01*
G01X1676933Y987664D02*
X1681283D01*
G01X1686141Y984318D02*
X1690491D01*
G01X1686141Y991011D02*
X1690491D01*
G01X1676933Y1017782D02*
X1681283D01*
G01X1676933Y1027822D02*
X1681283D01*
G01X1686141Y1017782D02*
X1690491D01*
G01X1686141Y1024475D02*
X1690491D01*
G01X1686141Y1031168D02*
X1690491D01*
G01X1676933Y1034515D02*
X1681283D01*
G01X1676933Y1041207D02*
X1681283D01*
G01X1686141Y1037861D02*
X1690491D01*
G01X1686141Y1044554D02*
X1690491D01*
G01X1676933Y1047900D02*
X1681283D01*
G01X1676933Y1061286D02*
X1681283D01*
G01X1676933Y1054593D02*
X1681283D01*
G01X1686141Y1051247D02*
X1690491D01*
G01X1686141Y1057940D02*
X1690491D01*
G01X1676933Y1067979D02*
X1681283D01*
G01Y1074672D02*
X1676933D01*
G01X1686141Y1064633D02*
X1690491D01*
G01X1686141Y1071326D02*
X1690491D01*
G01X1686141Y1078018D02*
X1690491D01*
G01X1681283Y1084711D02*
X1676933D01*
G01X1681283Y1091404D02*
X1676933D01*
G01X1686141Y1088058D02*
X1690491D01*
G01X1686141Y1094751D02*
X1690491D01*
G01X1681283Y1098097D02*
X1676933D01*
G01X1681283Y1104790D02*
X1676933D01*
G01X1681283Y1111483D02*
X1676933D01*
G01X1686141Y1101444D02*
X1690491D01*
G01X1686141Y1108137D02*
X1690491D01*
G01X1681283Y1121522D02*
X1676933D01*
G01X1681283Y1128215D02*
X1676933D01*
G01X1686141Y1114829D02*
X1690491D01*
G01X1686141Y1124869D02*
X1690491D01*
G01X1681283Y1134908D02*
X1676933D01*
G01X1681283Y1141601D02*
X1676933D01*
G01X1686141Y1131562D02*
X1690491D01*
G01X1686141Y1138255D02*
X1690491D01*
G01X1686141Y1144948D02*
X1690491D01*
G01X1681283Y1148294D02*
X1676933D01*
G01X1681283Y1158333D02*
X1676933D01*
G01X1686141Y1151641D02*
X1690491D01*
G01X1681283Y1165026D02*
X1676933D01*
G01X1681283Y1171719D02*
X1676933D01*
G01X1686141Y1161680D02*
X1690491D01*
G01X1686141Y1168373D02*
X1690491D01*
G01X1686141Y1175066D02*
X1690491D01*
G01X1681283Y1178412D02*
X1676933D01*
G01X1681283Y1185105D02*
X1676933D01*
G01X1686141Y1181759D02*
X1690491D01*
G01X1686141Y1188452D02*
X1690491D01*
G01X1681283Y1195144D02*
X1676933D01*
G01X1681283Y1201837D02*
X1676933D01*
G01X1681283Y1208530D02*
X1676933D01*
G01X1686141Y1198491D02*
X1690491D01*
G01X1686141Y1205184D02*
X1690491D01*
G01X1681283Y1215223D02*
X1676933D01*
G01X1681283Y1221916D02*
X1676933D01*
G01X1686141Y1211877D02*
X1690491D01*
G01X1686141Y1218570D02*
X1690491D01*
G01X1686141Y1225263D02*
X1690491D01*
G01X1681283Y1231955D02*
X1676933D01*
G01X1681283Y1238648D02*
X1676933D01*
G01X1686141Y1235302D02*
X1690491D01*
G01X1686141Y1241995D02*
X1690491D01*
G01X1681283Y1245341D02*
X1676933D01*
G01X1686141Y1248688D02*
X1690491D01*
G01Y1258727D02*
X1686141D01*
G01X1675621Y1445150D02*
X1674980D01*
X1674336Y1445794D01*
X1673061D01*
G01X1697648Y463724D02*
Y466201D01*
G01X1693648Y463724D02*
Y466201D01*
G01X1699265Y525507D02*
X1696851D01*
G01X1699251Y529507D02*
X1696851D01*
G01X1704886Y534564D02*
X1703053Y536397D01*
X1702320D01*
G01X1699297Y549507D02*
X1696851D01*
G01X1707346Y547504D02*
X1704386D01*
X1703960Y547078D01*
G01X1695446Y703943D02*
X1692883D01*
G01X1690491Y770144D02*
X1694841D01*
G01X1702283Y766798D02*
X1706633D01*
G01X1690491Y776837D02*
X1694841D01*
G01X1690491Y783530D02*
X1694841D01*
G01X1702283Y773491D02*
X1706633D01*
G01X1702283Y780184D02*
X1706633D01*
G01X1690491Y793570D02*
X1694841D01*
G01X1690491Y800263D02*
X1694841D01*
G01X1702283Y790223D02*
X1706633D01*
G01X1702283Y796916D02*
X1706633D01*
G01X1702283Y803609D02*
X1706633D01*
G01X1690491Y806955D02*
X1694841D01*
G01X1690491Y813648D02*
X1694841D01*
G01X1702283Y810302D02*
X1706633D01*
G01X1702283Y816995D02*
X1706633D01*
G01X1690491Y820341D02*
X1694841D01*
G01X1690491Y830381D02*
X1694841D01*
G01X1702283Y827034D02*
X1706633D01*
G01X1702283Y833727D02*
X1706633D01*
G01X1690491Y837074D02*
X1694841D01*
G01X1690491Y843766D02*
X1694841D01*
G01X1690491Y850459D02*
X1694841D01*
G01X1702283Y840420D02*
X1706633D01*
G01X1702283Y847113D02*
X1706633D01*
G01X1690491Y857152D02*
X1694841D01*
G01X1690491Y867192D02*
X1694841D01*
G01X1702283Y853806D02*
X1706633D01*
G01X1702283Y863845D02*
X1706633D01*
G01X1690491Y873885D02*
X1694841D01*
G01X1690491Y880577D02*
X1694841D01*
G01X1702283Y870538D02*
X1706633D01*
G01X1702283Y877231D02*
X1706633D01*
G01X1702283Y883924D02*
X1706633D01*
G01X1690491Y887270D02*
X1694841D01*
G01X1690491Y893963D02*
X1694841D01*
G01X1702283Y890617D02*
X1706633D01*
G01X1702283Y900656D02*
X1706633D01*
G01X1690491Y904003D02*
X1694841D01*
G01X1690491Y910696D02*
X1694841D01*
G01X1690491Y917389D02*
X1694841D01*
G01X1702283Y907349D02*
X1706633D01*
G01X1702283Y914042D02*
X1706633D01*
G01X1690491Y924081D02*
X1694841D01*
G01X1690491Y930774D02*
X1694841D01*
G01X1702283Y920735D02*
X1706633D01*
G01X1702283Y927428D02*
X1706633D01*
G01X1690491Y940814D02*
X1694841D01*
G01X1690491Y947507D02*
X1694841D01*
G01X1702283Y937467D02*
X1706633D01*
G01X1702283Y944160D02*
X1706633D01*
G01X1690491Y954200D02*
X1694841D01*
G01X1690491Y964239D02*
X1694841D01*
G01X1702283Y950853D02*
X1706633D01*
G01X1702283Y960892D02*
X1706633D01*
G01X1690491Y970932D02*
X1694841D01*
G01X1690491Y977625D02*
X1694841D01*
G01X1702283Y967585D02*
X1706633D01*
G01X1702283Y974278D02*
X1706633D01*
G01X1702283Y980971D02*
X1706633D01*
G01X1690491Y984318D02*
X1694841D01*
G01X1690491Y991011D02*
X1694841D01*
G01X1702283Y987664D02*
X1706633D01*
G01X1690491Y1017782D02*
X1694841D01*
G01X1690491Y1024475D02*
X1694841D01*
G01X1690491Y1031168D02*
X1694841D01*
G01X1702283Y1017782D02*
X1706633D01*
G01X1702283Y1027822D02*
X1706633D01*
G01X1690491Y1037861D02*
X1694841D01*
G01X1690491Y1044554D02*
X1694841D01*
G01X1702283Y1034515D02*
X1706633D01*
G01X1702283Y1041207D02*
X1706633D01*
G01X1690491Y1051247D02*
X1694841D01*
G01X1690491Y1057940D02*
X1694841D01*
G01X1702283Y1047900D02*
X1706633D01*
G01X1702283Y1054593D02*
X1706633D01*
G01X1702283Y1061286D02*
X1706633D01*
G01X1690491Y1064633D02*
X1694841D01*
G01X1690491Y1071326D02*
X1694841D01*
G01X1690491Y1078018D02*
X1694841D01*
G01X1702283Y1067979D02*
X1706633D01*
G01X1702283Y1074672D02*
X1706633D01*
G01X1690491Y1088058D02*
X1694841D01*
G01X1690491Y1094751D02*
X1694841D01*
G01X1702283Y1084711D02*
X1706633D01*
G01X1702283Y1091404D02*
X1706633D01*
G01X1690491Y1101444D02*
X1694841D01*
G01X1690491Y1108137D02*
X1694841D01*
G01X1702283Y1098097D02*
X1706633D01*
G01X1702283Y1104790D02*
X1706633D01*
G01X1702283Y1111483D02*
X1706633D01*
G01X1690491Y1114829D02*
X1694841D01*
G01X1690491Y1124869D02*
X1694841D01*
G01X1702283Y1121522D02*
X1706633D01*
G01X1702283Y1128215D02*
X1706633D01*
G01X1690491Y1131562D02*
X1694841D01*
G01X1690491Y1138255D02*
X1694841D01*
G01X1690491Y1144948D02*
X1694841D01*
G01X1702283Y1134908D02*
X1706633D01*
G01X1702283Y1141601D02*
X1706633D01*
G01X1690491Y1151641D02*
X1694841D01*
G01X1702283Y1148294D02*
X1706633D01*
G01X1702283Y1158333D02*
X1706633D01*
G01X1690491Y1161680D02*
X1694841D01*
G01X1690491Y1168373D02*
X1694841D01*
G01X1690491Y1175066D02*
X1694841D01*
G01X1702283Y1165026D02*
X1706633D01*
G01X1702283Y1171719D02*
X1706633D01*
G01X1690491Y1181759D02*
X1694841D01*
G01X1690491Y1188452D02*
X1694841D01*
G01X1702283Y1178412D02*
X1706633D01*
G01X1702283Y1185105D02*
X1706633D01*
G01X1690491Y1198491D02*
X1694841D01*
G01X1690491Y1205184D02*
X1694841D01*
G01X1702283Y1195144D02*
X1706633D01*
G01X1702283Y1201837D02*
X1706633D01*
G01X1702283Y1208530D02*
X1706633D01*
G01X1690491Y1211877D02*
X1694841D01*
G01X1690491Y1218570D02*
X1694841D01*
G01X1690491Y1225263D02*
X1694841D01*
G01X1702283Y1215223D02*
X1706633D01*
G01X1702283Y1221916D02*
X1706633D01*
G01X1690491Y1235302D02*
X1694841D01*
G01X1690491Y1241995D02*
X1694841D01*
G01X1702283Y1231955D02*
X1706633D01*
G01X1702283Y1238648D02*
X1706633D01*
G01X1690491Y1248688D02*
X1694841D01*
G01X1702283Y1245341D02*
X1706633D01*
G01X1702323Y1500862D02*
X1704723D01*
G01X1702323Y1520362D02*
X1704723D01*
G01X1702323Y1541362D02*
X1704723D01*
G01X1702603Y1564057D02*
X1705003D01*
G01X1703323Y1583821D02*
X1705723D01*
G01X1714855Y165909D02*
X1717619D01*
G01X1714904Y161900D02*
X1715250D01*
X1718110Y159040D01*
G01X1723090Y173072D02*
X1720344Y170326D01*
X1714855D01*
G01X1719200Y371162D02*
Y370662D01*
X1721075Y368787D01*
X1722500D01*
G01X1715044Y406970D02*
X1715052Y406962D01*
X1718931D01*
G01X1707610Y531613D02*
Y534113D01*
G01X1708137Y706545D02*
X1709060Y705622D01*
Y704566D01*
X1710118Y703508D01*
X1710121D01*
X1710122Y703509D01*
G01D02*
Y703504D01*
X1710495Y703131D01*
Y701062D01*
G01X1706633Y766798D02*
X1710983D01*
G01X1720191Y770144D02*
X1724541D01*
G01X1715841D02*
X1720191D01*
G01X1706633Y773491D02*
X1710983D01*
G01X1706633Y780184D02*
X1710983D01*
G01X1720191Y783530D02*
X1724541D01*
G01X1715841D02*
X1720191D01*
G01Y776837D02*
X1724541D01*
G01X1715841D02*
X1720191D01*
G01X1706633Y790223D02*
X1710983D01*
G01X1706633Y796916D02*
X1710983D01*
G01X1706633Y803609D02*
X1710983D01*
G01X1715841Y793570D02*
X1720191D01*
G01D02*
X1724541D01*
G01X1715841Y800263D02*
X1720191D01*
G01D02*
X1724541D01*
G01X1706633Y810302D02*
X1710983D01*
G01X1706633Y816995D02*
X1710983D01*
G01X1715841Y806955D02*
X1720191D01*
G01D02*
X1724541D01*
G01X1715841Y813648D02*
X1720191D01*
G01D02*
X1724541D01*
G01X1706633Y827034D02*
X1710983D01*
G01X1706633Y833727D02*
X1710983D01*
G01X1715841Y820341D02*
X1720191D01*
G01D02*
X1724541D01*
G01X1715841Y830381D02*
X1720191D01*
G01D02*
X1724541D01*
G01X1706633Y840420D02*
X1710983D01*
G01X1706633Y847113D02*
X1710983D01*
G01X1715841Y837074D02*
X1720191D01*
G01D02*
X1724541D01*
G01X1715841Y843766D02*
X1720191D01*
G01D02*
X1724541D01*
G01X1715841Y850459D02*
X1720191D01*
G01D02*
X1724541D01*
G01X1706633Y853806D02*
X1710983D01*
G01X1706633Y863845D02*
X1710983D01*
G01X1715841Y857152D02*
X1720191D01*
G01D02*
X1724541D01*
G01X1715841Y867192D02*
X1720191D01*
G01D02*
X1724541D01*
G01X1706633Y870538D02*
X1710983D01*
G01X1706633Y877231D02*
X1710983D01*
G01X1706633Y883924D02*
X1710983D01*
G01X1715841Y873885D02*
X1720191D01*
G01D02*
X1724541D01*
G01X1715841Y880577D02*
X1720191D01*
G01D02*
X1724541D01*
G01X1706633Y890617D02*
X1710983D01*
G01X1706633Y900656D02*
X1710983D01*
G01X1715841Y893963D02*
X1720191D01*
G01D02*
X1724541D01*
G01X1715841Y887270D02*
X1720191D01*
G01D02*
X1724541D01*
G01X1706633Y907349D02*
X1710983D01*
G01X1706633Y914042D02*
X1710983D01*
G01X1715841Y904003D02*
X1720191D01*
G01D02*
X1724541D01*
G01X1715841Y910696D02*
X1720191D01*
G01D02*
X1724541D01*
G01X1715841Y917389D02*
X1720191D01*
G01D02*
X1724541D01*
G01X1706633Y920735D02*
X1710983D01*
G01X1706633Y927428D02*
X1710983D01*
G01X1715841Y924081D02*
X1720191D01*
G01D02*
X1724541D01*
G01X1715841Y930774D02*
X1720191D01*
G01D02*
X1724541D01*
G01X1706633Y937467D02*
X1710983D01*
G01X1706633Y944160D02*
X1710983D01*
G01X1715841Y940814D02*
X1720191D01*
G01D02*
X1724541D01*
G01X1715841Y947507D02*
X1720191D01*
G01D02*
X1724541D01*
G01X1706633Y950853D02*
X1710983D01*
G01X1706633Y960892D02*
X1710983D01*
G01X1715841Y954200D02*
X1720191D01*
G01D02*
X1724541D01*
G01X1715841Y964239D02*
X1720191D01*
G01D02*
X1724541D01*
G01X1706633Y967585D02*
X1710983D01*
G01X1706633Y974278D02*
X1710983D01*
G01X1706633Y980971D02*
X1710983D01*
G01X1715841Y970932D02*
X1720191D01*
G01D02*
X1724541D01*
G01X1715841Y977625D02*
X1720191D01*
G01D02*
X1724541D01*
G01X1706633Y987664D02*
X1710983D01*
G01X1715841Y984318D02*
X1720191D01*
G01D02*
X1724541D01*
G01X1715841Y991011D02*
X1720191D01*
G01D02*
X1724541D01*
G01X1706633Y1017782D02*
X1710983D01*
G01X1706633Y1027822D02*
X1710983D01*
G01X1715841Y1017782D02*
X1720191D01*
G01D02*
X1724541D01*
G01X1715841Y1024475D02*
X1720191D01*
G01D02*
X1724541D01*
G01X1715841Y1031168D02*
X1720191D01*
G01D02*
X1724541D01*
G01X1706633Y1034515D02*
X1710983D01*
G01X1706633Y1041207D02*
X1710983D01*
G01X1715841Y1037861D02*
X1720191D01*
G01D02*
X1724541D01*
G01X1715841Y1044554D02*
X1720191D01*
G01D02*
X1724541D01*
G01X1706633Y1047900D02*
X1710983D01*
G01X1706633Y1054593D02*
X1710983D01*
G01X1706633Y1061286D02*
X1710983D01*
G01X1715841Y1051247D02*
X1720191D01*
G01D02*
X1724541D01*
G01X1715841Y1057940D02*
X1720191D01*
G01D02*
X1724541D01*
G01X1706633Y1067979D02*
X1710983D01*
G01X1706633Y1074672D02*
X1710983D01*
G01X1715841Y1071326D02*
X1720191D01*
G01D02*
X1724541D01*
G01X1715841Y1064633D02*
X1720191D01*
G01D02*
X1724541D01*
G01X1715841Y1078018D02*
X1720191D01*
G01D02*
X1724541D01*
G01X1706633Y1084711D02*
X1710983D01*
G01X1706633Y1091404D02*
X1710983D01*
G01X1715841Y1088058D02*
X1720191D01*
G01D02*
X1724541D01*
G01X1715841Y1094751D02*
X1720191D01*
G01D02*
X1724541D01*
G01X1706633Y1098097D02*
X1710983D01*
G01X1706633Y1104790D02*
X1710983D01*
G01X1706633Y1111483D02*
X1710983D01*
G01X1715841Y1101444D02*
X1720191D01*
G01D02*
X1724541D01*
G01X1715841Y1108137D02*
X1720191D01*
G01D02*
X1724541D01*
G01X1706633Y1121522D02*
X1710983D01*
G01X1706633Y1128215D02*
X1710983D01*
G01X1715841Y1114829D02*
X1720191D01*
G01D02*
X1724541D01*
G01X1715841Y1124869D02*
X1720191D01*
G01D02*
X1724541D01*
G01X1706633Y1134908D02*
X1710983D01*
G01X1706633Y1141601D02*
X1710983D01*
G01X1715841Y1131562D02*
X1720191D01*
G01D02*
X1724541D01*
G01X1715841Y1138255D02*
X1720191D01*
G01D02*
X1724541D01*
G01X1715841Y1144948D02*
X1720191D01*
G01D02*
X1724541D01*
G01X1706633Y1148294D02*
X1710983D01*
G01X1706633Y1158333D02*
X1710983D01*
G01X1715841Y1151641D02*
X1720191D01*
G01D02*
X1724541D01*
G01X1706633Y1165026D02*
X1710983D01*
G01X1706633Y1171719D02*
X1710983D01*
G01X1715841Y1161680D02*
X1720191D01*
G01D02*
X1724541D01*
G01X1715841Y1168373D02*
X1720191D01*
G01D02*
X1724541D01*
G01X1715841Y1175066D02*
X1720191D01*
G01D02*
X1724541D01*
G01X1706633Y1178412D02*
X1710983D01*
G01X1706633Y1185105D02*
X1710983D01*
G01X1715841Y1181759D02*
X1720191D01*
G01D02*
X1724541D01*
G01X1715841Y1188452D02*
X1720191D01*
G01D02*
X1724541D01*
G01X1706633Y1195144D02*
X1710983D01*
G01X1706633Y1201837D02*
X1710983D01*
G01X1706633Y1208530D02*
X1710983D01*
G01X1715841Y1198491D02*
X1720191D01*
G01D02*
X1724541D01*
G01X1715841Y1205184D02*
X1720191D01*
G01D02*
X1724541D01*
G01X1706633Y1215223D02*
X1710983D01*
G01X1706633Y1221916D02*
X1710983D01*
G01X1715841Y1211877D02*
X1720191D01*
G01D02*
X1724541D01*
G01X1715841Y1218570D02*
X1720191D01*
G01D02*
X1724541D01*
G01X1715841Y1225263D02*
X1720191D01*
G01D02*
X1724541D01*
G01X1706633Y1231955D02*
X1710983D01*
G01X1706633Y1238648D02*
X1710983D01*
G01X1715841Y1235302D02*
X1720191D01*
G01D02*
X1724541D01*
G01X1715841Y1241995D02*
X1720191D01*
G01D02*
X1724541D01*
G01X1706633Y1245341D02*
X1710983D01*
G01X1715841Y1248688D02*
X1720191D01*
G01D02*
X1724541D01*
G01X1713620Y1258512D02*
X1713835Y1258727D01*
X1720191D01*
G01X1726290Y173072D02*
X1723090D01*
G01X1726290Y177072D02*
X1723090D01*
G01X1734857Y184865D02*
X1731047D01*
X1729609Y183427D01*
Y181234D01*
G01D02*
X1730842Y180001D01*
X1742907D01*
G01X1727325Y373337D02*
X1725500Y375162D01*
Y377787D01*
G01D02*
X1728300D01*
G01X1722500Y368787D02*
X1726425D01*
G01X1733780Y393195D02*
Y390620D01*
G01X1729954Y411578D02*
Y414444D01*
X1730290Y414780D01*
Y417265D01*
G01D02*
X1727700D01*
G01X1725473Y474859D02*
X1723004D01*
G01X1730954Y478062D02*
Y480669D01*
G01X1740886Y493960D02*
X1736729D01*
X1736611Y493842D01*
G01X1725522Y482869D02*
X1723004D01*
G01X1730954Y490869D02*
X1733354D01*
G01D02*
X1733833Y491348D01*
X1735955D01*
X1736611Y490692D01*
G01X1730954Y486869D02*
X1733354D01*
G01D02*
X1733386Y486837D01*
X1736126D01*
G01X1731983Y766798D02*
X1736333D01*
G01D02*
X1740683D01*
G01X1731983Y773491D02*
X1736333D01*
G01D02*
X1740683D01*
G01X1731983Y780184D02*
X1736333D01*
G01D02*
X1740683D01*
G01X1731983Y790223D02*
X1736333D01*
G01D02*
X1740683D01*
G01X1731983Y796916D02*
X1736333D01*
G01D02*
X1740683D01*
G01X1731983Y803609D02*
X1736333D01*
G01D02*
X1740683D01*
G01X1731983Y810302D02*
X1736333D01*
G01D02*
X1740683D01*
G01X1731983Y816995D02*
X1736333D01*
G01D02*
X1740683D01*
G01X1731983Y827034D02*
X1736333D01*
G01D02*
X1740683D01*
G01X1731983Y833727D02*
X1736333D01*
G01D02*
X1740683D01*
G01X1731983Y840420D02*
X1736333D01*
G01D02*
X1740683D01*
G01X1731983Y847113D02*
X1736333D01*
G01D02*
X1740683D01*
G01X1731983Y853806D02*
X1736333D01*
G01D02*
X1740683D01*
G01X1731983Y863845D02*
X1736333D01*
G01D02*
X1740683D01*
G01X1731983Y870538D02*
X1736333D01*
G01D02*
X1740683D01*
G01X1731983Y877231D02*
X1736333D01*
G01D02*
X1740683D01*
G01X1731983Y883924D02*
X1736333D01*
G01D02*
X1740683D01*
G01X1731983Y890617D02*
X1736333D01*
G01D02*
X1740683D01*
G01X1731983Y900656D02*
X1736333D01*
G01D02*
X1740683D01*
G01X1731983Y907349D02*
X1736333D01*
G01D02*
X1740683D01*
G01X1731983Y914042D02*
X1736333D01*
G01D02*
X1740683D01*
G01X1731983Y920735D02*
X1736333D01*
G01D02*
X1740683D01*
G01X1731983Y927428D02*
X1736333D01*
G01D02*
X1740683D01*
G01X1731983Y937467D02*
X1736333D01*
G01D02*
X1740683D01*
G01X1731983Y944160D02*
X1736333D01*
G01D02*
X1740683D01*
G01X1731983Y950853D02*
X1736333D01*
G01D02*
X1740683D01*
G01X1731983Y960892D02*
X1736333D01*
G01D02*
X1740683D01*
G01X1731983Y967585D02*
X1736333D01*
G01D02*
X1740683D01*
G01X1731983Y974278D02*
X1736333D01*
G01D02*
X1740683D01*
G01X1731983Y980971D02*
X1736333D01*
G01D02*
X1740683D01*
G01X1731983Y987664D02*
X1736333D01*
G01D02*
X1740683D01*
G01X1731983Y1017782D02*
X1736333D01*
G01D02*
X1740683D01*
G01X1731983Y1027822D02*
X1736333D01*
G01D02*
X1740683D01*
G01X1731983Y1034515D02*
X1736333D01*
G01D02*
X1740683D01*
G01X1731983Y1041207D02*
X1736333D01*
G01D02*
X1740683D01*
G01X1731983Y1047900D02*
X1736333D01*
G01D02*
X1740683D01*
G01X1731983Y1054593D02*
X1736333D01*
G01D02*
X1740683D01*
G01X1731983Y1061286D02*
X1736333D01*
G01D02*
X1740683D01*
G01X1731983Y1074672D02*
X1736333D01*
G01D02*
X1740683D01*
G01X1731983Y1067979D02*
X1736333D01*
G01D02*
X1740683D01*
G01X1731983Y1084711D02*
X1736333D01*
G01D02*
X1740683D01*
G01X1731983Y1091404D02*
X1736333D01*
G01D02*
X1740683D01*
G01X1731983Y1098097D02*
X1736333D01*
G01D02*
X1740683D01*
G01X1731983Y1104790D02*
X1736333D01*
G01D02*
X1740683D01*
G01X1731983Y1111483D02*
X1736333D01*
G01D02*
X1740683D01*
G01X1731983Y1121522D02*
X1736333D01*
G01D02*
X1740683D01*
G01X1731983Y1128215D02*
X1736333D01*
G01D02*
X1740683D01*
G01X1731983Y1134908D02*
X1736333D01*
G01D02*
X1740683D01*
G01X1731983Y1141601D02*
X1736333D01*
G01D02*
X1740683D01*
G01X1731983Y1148294D02*
X1736333D01*
G01D02*
X1740683D01*
G01X1731983Y1158333D02*
X1736333D01*
G01D02*
X1740683D01*
G01X1731983Y1165026D02*
X1736333D01*
G01D02*
X1740683D01*
G01X1731983Y1171719D02*
X1736333D01*
G01D02*
X1740683D01*
G01X1731983Y1178412D02*
X1736333D01*
G01D02*
X1740683D01*
G01X1731983Y1185105D02*
X1736333D01*
G01D02*
X1740683D01*
G01X1731983Y1195144D02*
X1736333D01*
G01D02*
X1740683D01*
G01X1731983Y1201837D02*
X1736333D01*
G01D02*
X1740683D01*
G01X1731983Y1208530D02*
X1736333D01*
G01D02*
X1740683D01*
G01X1731983Y1215223D02*
X1736333D01*
G01D02*
X1740683D01*
G01X1731983Y1221916D02*
X1736333D01*
G01D02*
X1740683D01*
G01X1731983Y1231955D02*
X1736333D01*
G01D02*
X1740683D01*
G01X1731983Y1238648D02*
X1736333D01*
G01D02*
X1740683D01*
G01X1731983Y1245341D02*
X1736333D01*
G01D02*
X1740683D01*
G01X1754234Y187509D02*
X1754637Y187106D01*
Y181701D01*
X1756337Y180001D01*
X1760033D01*
G01X1740831Y489362D02*
Y488392D01*
X1739276Y486837D01*
G01X1754241Y770144D02*
X1749891D01*
G01D02*
X1745541D01*
G01X1754241Y776837D02*
X1749891D01*
G01D02*
X1745541D01*
G01X1754241Y783530D02*
X1749891D01*
G01D02*
X1745541D01*
G01X1754241Y793570D02*
X1749891D01*
G01D02*
X1745541D01*
G01X1754241Y800263D02*
X1749891D01*
G01D02*
X1745541D01*
G01X1754241Y806955D02*
X1749891D01*
G01D02*
X1745541D01*
G01X1754241Y813648D02*
X1749891D01*
G01D02*
X1745541D01*
G01X1754241Y820341D02*
X1749891D01*
G01D02*
X1745541D01*
G01X1754241Y830381D02*
X1749891D01*
G01D02*
X1745541D01*
G01Y843766D02*
X1749891D01*
G01D02*
X1754241D01*
G01Y837074D02*
X1749891D01*
G01D02*
X1745541D01*
G01X1754241Y850459D02*
X1749891D01*
G01D02*
X1745541D01*
G01X1754241Y857152D02*
X1749891D01*
G01D02*
X1745541D01*
G01Y867192D02*
X1749891D01*
G01D02*
X1754241D01*
G01Y873885D02*
X1749891D01*
G01D02*
X1745541D01*
G01X1754241Y880577D02*
X1749891D01*
G01D02*
X1745541D01*
G01Y893963D02*
X1749891D01*
G01D02*
X1754241D01*
G01Y887270D02*
X1749891D01*
G01D02*
X1745541D01*
G01Y904003D02*
X1749891D01*
G01D02*
X1754241D01*
G01X1745541Y910696D02*
X1749891D01*
G01D02*
X1754241D01*
G01X1745541Y917389D02*
X1749891D01*
G01D02*
X1754241D01*
G01X1745541Y924081D02*
X1749891D01*
G01D02*
X1754241D01*
G01X1745541Y930774D02*
X1749891D01*
G01D02*
X1754241D01*
G01X1745541Y940814D02*
X1749891D01*
G01D02*
X1754241D01*
G01X1745541Y947507D02*
X1749891D01*
G01D02*
X1754241D01*
G01X1745541Y954200D02*
X1749891D01*
G01D02*
X1754241D01*
G01X1745541Y964239D02*
X1749891D01*
G01D02*
X1754241D01*
G01X1745541Y970932D02*
X1749891D01*
G01D02*
X1754241D01*
G01X1745541Y977625D02*
X1749891D01*
G01D02*
X1754241D01*
G01X1745541Y984318D02*
X1749891D01*
G01D02*
X1754241D01*
G01X1745541Y991011D02*
X1749891D01*
G01D02*
X1754241D01*
G01X1745541Y1017782D02*
X1749891D01*
G01D02*
X1754241D01*
G01Y1024475D02*
X1749891D01*
G01D02*
X1745541D01*
G01X1754241Y1031168D02*
X1749891D01*
G01D02*
X1745541D01*
G01Y1044554D02*
X1749891D01*
G01D02*
X1754241D01*
G01Y1037861D02*
X1749891D01*
G01D02*
X1745541D01*
G01X1754241Y1051247D02*
X1749891D01*
G01D02*
X1745541D01*
G01X1754241Y1057940D02*
X1749891D01*
G01D02*
X1745541D01*
G01Y1071326D02*
X1749891D01*
G01D02*
X1754241D01*
G01Y1064633D02*
X1749891D01*
G01D02*
X1745541D01*
G01Y1078018D02*
X1749891D01*
G01D02*
X1754241D01*
G01X1745541Y1088058D02*
X1749891D01*
G01D02*
X1754241D01*
G01X1745541Y1094751D02*
X1749891D01*
G01D02*
X1754241D01*
G01X1745541Y1101444D02*
X1749891D01*
G01D02*
X1754241D01*
G01X1745541Y1108137D02*
X1749891D01*
G01D02*
X1754241D01*
G01X1745541Y1114829D02*
X1749891D01*
G01D02*
X1754241D01*
G01X1745541Y1124869D02*
X1749891D01*
G01D02*
X1754241D01*
G01X1745541Y1131562D02*
X1749891D01*
G01D02*
X1754241D01*
G01X1745541Y1138255D02*
X1749891D01*
G01D02*
X1754241D01*
G01X1745541Y1144948D02*
X1749891D01*
G01D02*
X1754241D01*
G01X1745541Y1151641D02*
X1749891D01*
G01D02*
X1754241D01*
G01X1745541Y1161680D02*
X1749891D01*
G01D02*
X1754241D01*
G01Y1175066D02*
X1749891D01*
G01D02*
X1745541D01*
G01Y1168373D02*
X1749891D01*
G01D02*
X1754241D01*
G01Y1181759D02*
X1749891D01*
G01D02*
X1745541D01*
G01Y1188452D02*
X1749891D01*
G01D02*
X1754241D01*
G01X1745541Y1198491D02*
X1749891D01*
G01D02*
X1754241D01*
G01X1745541Y1205184D02*
X1749891D01*
G01D02*
X1754241D01*
G01X1745541Y1211877D02*
X1749891D01*
G01D02*
X1754241D01*
G01X1745541Y1218570D02*
X1749891D01*
G01D02*
X1754241D01*
G01X1745541Y1225263D02*
X1749891D01*
G01D02*
X1754241D01*
G01X1745541Y1235302D02*
X1749891D01*
G01D02*
X1754241D01*
G01X1745541Y1241995D02*
X1749891D01*
G01D02*
X1754241D01*
G01X1745541Y1248688D02*
X1749891D01*
G01D02*
X1754241D01*
G01X1749891Y1258727D02*
X1745541D01*
G01X1758398Y159597D02*
X1761514D01*
X1763435Y161518D01*
Y164362D01*
G01D02*
Y166862D01*
G01X1754234Y190836D02*
Y187509D01*
G01X1758563Y307992D02*
Y310478D01*
G01X1754963Y307992D02*
Y310478D01*
G01X1769230D02*
Y307992D01*
G01D02*
X1765663D01*
G01X1754162Y364048D02*
X1756800D01*
G01X1754162Y368048D02*
X1756800D01*
G01X1767795Y372452D02*
X1770280D01*
G01X1757066Y433221D02*
Y435721D01*
G01X1757650Y461393D02*
X1760166D01*
G01X1760276Y465893D02*
Y461503D01*
X1760166Y461393D01*
G01X1761683Y766798D02*
X1766033D01*
G01D02*
X1770383D01*
G01X1761683Y773491D02*
X1766033D01*
G01D02*
X1770383D01*
G01Y780184D02*
X1766033D01*
G01D02*
X1761683D01*
G01X1770383Y790223D02*
X1766033D01*
G01D02*
X1761683D01*
G01X1770383Y796916D02*
X1766033D01*
G01D02*
X1761683D01*
G01X1770383Y803609D02*
X1766033D01*
G01D02*
X1761683D01*
G01X1770383Y810302D02*
X1766033D01*
G01D02*
X1761683D01*
G01X1770383Y816995D02*
X1766033D01*
G01D02*
X1761683D01*
G01X1770383Y827034D02*
X1766033D01*
G01D02*
X1761683D01*
G01X1770383Y833727D02*
X1766033D01*
G01D02*
X1761683D01*
G01X1770383Y840420D02*
X1766033D01*
G01D02*
X1761683D01*
G01X1770383Y847113D02*
X1766033D01*
G01D02*
X1761683D01*
G01X1770383Y853806D02*
X1766033D01*
G01D02*
X1761683D01*
G01X1770383Y863845D02*
X1766033D01*
G01D02*
X1761683D01*
G01X1770383Y870538D02*
X1766033D01*
G01D02*
X1761683D01*
G01X1770383Y877231D02*
X1766033D01*
G01D02*
X1761683D01*
G01X1770383Y883924D02*
X1766033D01*
G01D02*
X1761683D01*
G01X1770383Y890617D02*
X1766033D01*
G01D02*
X1761683D01*
G01X1770383Y900656D02*
X1766033D01*
G01D02*
X1761683D01*
G01X1770383Y907349D02*
X1766033D01*
G01D02*
X1761683D01*
G01X1770383Y914042D02*
X1766033D01*
G01D02*
X1761683D01*
G01Y927428D02*
X1766033D01*
G01D02*
X1770383D01*
G01Y920735D02*
X1766033D01*
G01D02*
X1761683D01*
G01X1770383Y937467D02*
X1766033D01*
G01D02*
X1761683D01*
G01X1770383Y944160D02*
X1766033D01*
G01D02*
X1761683D01*
G01X1770383Y950853D02*
X1766033D01*
G01D02*
X1761683D01*
G01X1770383Y960892D02*
X1766033D01*
G01D02*
X1761683D01*
G01X1770383Y967585D02*
X1766033D01*
G01D02*
X1761683D01*
G01X1770383Y974278D02*
X1766033D01*
G01D02*
X1761683D01*
G01X1770383Y980971D02*
X1766033D01*
G01D02*
X1761683D01*
G01X1770383Y987664D02*
X1766033D01*
G01D02*
X1761683D01*
G01X1770383Y1017782D02*
X1766033D01*
G01D02*
X1761683D01*
G01X1770383Y1027822D02*
X1766033D01*
G01D02*
X1761683D01*
G01X1770383Y1034515D02*
X1766033D01*
G01D02*
X1761683D01*
G01X1770383Y1041207D02*
X1766033D01*
G01D02*
X1761683D01*
G01X1770383Y1047900D02*
X1766033D01*
G01D02*
X1761683D01*
G01X1770383Y1054593D02*
X1766033D01*
G01D02*
X1761683D01*
G01X1770383Y1061286D02*
X1766033D01*
G01D02*
X1761683D01*
G01X1770383Y1067979D02*
X1766033D01*
G01D02*
X1761683D01*
G01X1770383Y1074672D02*
X1766033D01*
G01D02*
X1761683D01*
G01X1770383Y1084711D02*
X1766033D01*
G01D02*
X1761683D01*
G01X1770383Y1091404D02*
X1766033D01*
G01D02*
X1761683D01*
G01Y1098097D02*
X1766033D01*
G01D02*
X1770383D01*
G01Y1104790D02*
X1766033D01*
G01D02*
X1761683D01*
G01X1770383Y1111483D02*
X1766033D01*
G01D02*
X1761683D01*
G01X1770383Y1121522D02*
X1766033D01*
G01D02*
X1761683D01*
G01X1770383Y1128215D02*
X1766033D01*
G01D02*
X1761683D01*
G01X1770383Y1134908D02*
X1766033D01*
G01D02*
X1761683D01*
G01X1770383Y1141601D02*
X1766033D01*
G01D02*
X1761683D01*
G01X1770383Y1148294D02*
X1766033D01*
G01D02*
X1761683D01*
G01X1770383Y1158333D02*
X1766033D01*
G01D02*
X1761683D01*
G01X1770383Y1165026D02*
X1766033D01*
G01D02*
X1761683D01*
G01X1770383Y1171719D02*
X1766033D01*
G01D02*
X1761683D01*
G01X1770383Y1178412D02*
X1766033D01*
G01D02*
X1761683D01*
G01X1770383Y1185105D02*
X1766033D01*
G01D02*
X1761683D01*
G01X1770383Y1195144D02*
X1766033D01*
G01D02*
X1761683D01*
G01X1770383Y1201837D02*
X1766033D01*
G01D02*
X1761683D01*
G01X1770383Y1208530D02*
X1766033D01*
G01D02*
X1761683D01*
G01X1770383Y1215223D02*
X1766033D01*
G01D02*
X1761683D01*
G01X1770383Y1221916D02*
X1766033D01*
G01D02*
X1761683D01*
G01X1770383Y1231955D02*
X1766033D01*
G01D02*
X1761683D01*
G01X1770383Y1238648D02*
X1766033D01*
G01D02*
X1761683D01*
G01X1770383Y1245341D02*
X1766033D01*
G01D02*
X1761683D01*
G01X1774950Y178403D02*
X1777520D01*
G01X1774950Y173903D02*
X1777520D01*
G01X1783018Y299243D02*
Y301729D01*
G01X1772863Y307992D02*
Y310478D01*
G01X1784724Y410432D02*
X1782324D01*
G01X1784724Y403932D02*
X1782324D01*
G01X1784724Y425432D02*
X1782324D01*
G01X1784724Y418932D02*
X1782324D01*
G01X1773150Y444538D02*
Y446092D01*
X1774520Y447462D01*
X1778485D01*
X1778810Y447137D01*
G01D02*
X1782420D01*
G01X1778810Y452065D02*
X1781470D01*
G01X1779591Y770144D02*
X1775241D01*
G01X1783941D02*
X1779591D01*
G01Y776837D02*
X1775241D01*
G01X1783941D02*
X1779591D01*
G01Y783530D02*
X1775241D01*
G01X1783941D02*
X1779591D01*
G01Y793570D02*
X1775241D01*
G01X1783941D02*
X1779591D01*
G01Y800263D02*
X1775241D01*
G01X1783941D02*
X1779591D01*
G01Y806955D02*
X1775241D01*
G01X1783941D02*
X1779591D01*
G01Y813648D02*
X1775241D01*
G01X1783941D02*
X1779591D01*
G01Y820341D02*
X1775241D01*
G01X1783941D02*
X1779591D01*
G01Y830381D02*
X1783941D01*
G01X1775241D02*
X1779591D01*
G01Y837074D02*
X1775241D01*
G01X1783941D02*
X1779591D01*
G01Y843766D02*
X1775241D01*
G01X1783941D02*
X1779591D01*
G01Y850459D02*
X1775241D01*
G01X1783941D02*
X1779591D01*
G01Y857152D02*
X1775241D01*
G01X1783941D02*
X1779591D01*
G01Y867192D02*
X1775241D01*
G01X1783941D02*
X1779591D01*
G01Y873885D02*
X1775241D01*
G01X1783941D02*
X1779591D01*
G01Y880577D02*
X1775241D01*
G01X1783941D02*
X1779591D01*
G01Y887270D02*
X1775241D01*
G01X1783941D02*
X1779591D01*
G01Y893963D02*
X1775241D01*
G01X1783941D02*
X1779591D01*
G01Y904003D02*
X1775241D01*
G01X1783941D02*
X1779591D01*
G01Y910696D02*
X1775241D01*
G01X1783941D02*
X1779591D01*
G01Y917389D02*
X1775241D01*
G01X1783941D02*
X1779591D01*
G01Y924081D02*
X1775241D01*
G01X1783941D02*
X1779591D01*
G01Y930774D02*
X1775241D01*
G01X1783941D02*
X1779591D01*
G01Y940814D02*
X1775241D01*
G01X1783941D02*
X1779591D01*
G01Y947507D02*
X1775241D01*
G01X1783941D02*
X1779591D01*
G01Y954200D02*
X1775241D01*
G01X1783941D02*
X1779591D01*
G01Y964239D02*
X1775241D01*
G01X1783941D02*
X1779591D01*
G01Y970932D02*
X1775241D01*
G01X1783941D02*
X1779591D01*
G01Y977625D02*
X1775241D01*
G01X1783941D02*
X1779591D01*
G01Y984318D02*
X1775241D01*
G01X1783941D02*
X1779591D01*
G01Y991011D02*
X1775241D01*
G01X1783941D02*
X1779591D01*
G01Y1017782D02*
X1775241D01*
G01X1783941D02*
X1779591D01*
G01Y1024475D02*
X1775241D01*
G01X1783941D02*
X1779591D01*
G01Y1031168D02*
X1775241D01*
G01X1783941D02*
X1779591D01*
G01Y1037861D02*
X1775241D01*
G01X1783941D02*
X1779591D01*
G01Y1044554D02*
X1775241D01*
G01X1783941D02*
X1779591D01*
G01Y1051247D02*
X1775241D01*
G01X1783941D02*
X1779591D01*
G01Y1057940D02*
X1775241D01*
G01X1783941D02*
X1779591D01*
G01Y1064633D02*
X1775241D01*
G01X1783941D02*
X1779591D01*
G01Y1071326D02*
X1775241D01*
G01X1783941D02*
X1779591D01*
G01Y1078018D02*
X1775241D01*
G01X1783941D02*
X1779591D01*
G01Y1088058D02*
X1775241D01*
G01X1783941D02*
X1779591D01*
G01Y1094751D02*
X1775241D01*
G01X1783941D02*
X1779591D01*
G01Y1101444D02*
X1775241D01*
G01X1783941D02*
X1779591D01*
G01Y1108137D02*
X1775241D01*
G01X1783941D02*
X1779591D01*
G01Y1114829D02*
X1775241D01*
G01X1783941D02*
X1779591D01*
G01Y1124869D02*
X1775241D01*
G01X1783941D02*
X1779591D01*
G01Y1131562D02*
X1775241D01*
G01X1783941D02*
X1779591D01*
G01Y1138255D02*
X1775241D01*
G01X1783941D02*
X1779591D01*
G01Y1144948D02*
X1775241D01*
G01X1783941D02*
X1779591D01*
G01Y1151641D02*
X1783941D01*
G01X1775241D02*
X1779591D01*
G01Y1161680D02*
X1775241D01*
G01X1783941D02*
X1779591D01*
G01Y1168373D02*
X1775241D01*
G01X1783941D02*
X1779591D01*
G01Y1175066D02*
X1775241D01*
G01X1783941D02*
X1779591D01*
G01Y1181759D02*
X1775241D01*
G01X1783941D02*
X1779591D01*
G01Y1188452D02*
X1775241D01*
G01X1783941D02*
X1779591D01*
G01Y1198491D02*
X1775241D01*
G01X1783941D02*
X1779591D01*
G01Y1205184D02*
X1775241D01*
G01X1783941D02*
X1779591D01*
G01Y1211877D02*
X1775241D01*
G01X1783941D02*
X1779591D01*
G01Y1218570D02*
X1775241D01*
G01X1783941D02*
X1779591D01*
G01Y1225263D02*
X1775241D01*
G01X1783941D02*
X1779591D01*
G01Y1235302D02*
X1775241D01*
G01X1783941D02*
X1779591D01*
G01Y1241995D02*
X1775241D01*
G01X1783941D02*
X1779591D01*
G01Y1248688D02*
X1775241D01*
G01X1783941D02*
X1779591D01*
G01Y1258727D02*
X1775241D01*
G01X1803215Y156557D02*
X1800925D01*
X1800230Y155862D01*
X1796768D01*
G01X1795733Y766798D02*
X1791383D01*
G01X1800083D02*
X1795733D01*
G01Y773491D02*
X1791383D01*
G01X1800083D02*
X1795733D01*
G01Y780184D02*
X1791383D01*
G01X1800083D02*
X1795733D01*
G01Y790223D02*
X1791383D01*
G01X1800083D02*
X1795733D01*
G01Y796916D02*
X1791383D01*
G01X1800083D02*
X1795733D01*
G01Y803609D02*
X1791383D01*
G01X1800083D02*
X1795733D01*
G01Y810302D02*
X1791383D01*
G01X1800083D02*
X1795733D01*
G01Y816995D02*
X1791383D01*
G01X1800083D02*
X1795733D01*
G01Y827034D02*
X1791383D01*
G01X1800083D02*
X1795733D01*
G01Y833727D02*
X1800083D01*
G01X1791383D02*
X1795733D01*
G01Y840420D02*
X1791383D01*
G01X1800083D02*
X1795733D01*
G01Y847113D02*
X1791383D01*
G01X1800083D02*
X1795733D01*
G01Y853806D02*
X1791383D01*
G01X1800083D02*
X1795733D01*
G01Y863845D02*
X1791383D01*
G01X1800083D02*
X1795733D01*
G01Y870538D02*
X1791383D01*
G01X1800083D02*
X1795733D01*
G01Y877231D02*
X1791383D01*
G01X1800083D02*
X1795733D01*
G01Y883924D02*
X1791383D01*
G01X1800083D02*
X1795733D01*
G01Y890617D02*
X1791383D01*
G01X1800083D02*
X1795733D01*
G01Y900656D02*
X1791383D01*
G01X1800083D02*
X1795733D01*
G01Y907349D02*
X1791383D01*
G01X1800083D02*
X1795733D01*
G01Y914042D02*
X1791383D01*
G01X1800083D02*
X1795733D01*
G01Y920735D02*
X1791383D01*
G01X1800083D02*
X1795733D01*
G01Y927428D02*
X1791383D01*
G01X1800083D02*
X1795733D01*
G01Y937467D02*
X1791383D01*
G01X1800083D02*
X1795733D01*
G01Y944160D02*
X1791383D01*
G01X1800083D02*
X1795733D01*
G01Y950853D02*
X1800083D01*
G01X1791383D02*
X1795733D01*
G01Y960892D02*
X1791383D01*
G01X1800083D02*
X1795733D01*
G01Y967585D02*
X1791383D01*
G01X1800083D02*
X1795733D01*
G01Y974278D02*
X1791383D01*
G01X1800083D02*
X1795733D01*
G01Y980971D02*
X1791383D01*
G01X1800083D02*
X1795733D01*
G01Y987664D02*
X1791383D01*
G01X1800083D02*
X1795733D01*
G01Y1017782D02*
X1791383D01*
G01X1800083D02*
X1795733D01*
G01Y1027822D02*
X1791383D01*
G01X1800083D02*
X1795733D01*
G01Y1034515D02*
X1791383D01*
G01X1800083D02*
X1795733D01*
G01Y1041207D02*
X1791383D01*
G01X1800083D02*
X1795733D01*
G01Y1047900D02*
X1791383D01*
G01X1800083D02*
X1795733D01*
G01Y1054593D02*
X1791383D01*
G01X1800083D02*
X1795733D01*
G01Y1061286D02*
X1791383D01*
G01X1800083D02*
X1795733D01*
G01Y1067979D02*
X1791383D01*
G01X1800083D02*
X1795733D01*
G01Y1074672D02*
X1791383D01*
G01X1800083D02*
X1795733D01*
G01Y1084711D02*
X1791383D01*
G01X1800083D02*
X1795733D01*
G01Y1091404D02*
X1791383D01*
G01X1800083D02*
X1795733D01*
G01Y1098097D02*
X1791383D01*
G01X1800083D02*
X1795733D01*
G01Y1104790D02*
X1791383D01*
G01X1800083D02*
X1795733D01*
G01Y1111483D02*
X1791383D01*
G01X1800083D02*
X1795733D01*
G01Y1121522D02*
X1791383D01*
G01X1800083D02*
X1795733D01*
G01Y1128215D02*
X1791383D01*
G01X1800083D02*
X1795733D01*
G01Y1134908D02*
X1800083D01*
G01X1791383D02*
X1795733D01*
G01Y1141601D02*
X1791383D01*
G01X1800083D02*
X1795733D01*
G01Y1148294D02*
X1791383D01*
G01X1800083D02*
X1795733D01*
G01Y1158333D02*
X1791383D01*
G01X1800083D02*
X1795733D01*
G01Y1165026D02*
X1791383D01*
G01X1800083D02*
X1795733D01*
G01Y1171719D02*
X1791383D01*
G01X1800083D02*
X1795733D01*
G01Y1178412D02*
X1791383D01*
G01X1800083D02*
X1795733D01*
G01Y1185105D02*
X1791383D01*
G01X1800083D02*
X1795733D01*
G01Y1195144D02*
X1791383D01*
G01X1800083D02*
X1795733D01*
G01Y1201837D02*
X1791383D01*
G01X1800083D02*
X1795733D01*
G01Y1208530D02*
X1791383D01*
G01X1800083D02*
X1795733D01*
G01Y1215223D02*
X1791383D01*
G01X1800083D02*
X1795733D01*
G01Y1221916D02*
X1791383D01*
G01X1800083D02*
X1795733D01*
G01Y1231955D02*
X1791383D01*
G01X1800083D02*
X1795733D01*
G01Y1238648D02*
X1791383D01*
G01X1800083D02*
X1795733D01*
G01Y1245341D02*
X1791383D01*
G01X1800083D02*
X1795733D01*
G01X1795223Y1502745D02*
Y1500372D01*
X1796127Y1499468D01*
X1797722D01*
G01X1802150Y1499405D02*
X1802087Y1499468D01*
X1797722D01*
G01X1795484Y1496401D02*
X1795984D01*
X1797722Y1498139D01*
Y1499468D01*
G01X1790011Y1511423D02*
X1792645D01*
G01X1795561Y1524729D02*
Y1527257D01*
X1795452Y1527366D01*
G01X1803215Y154032D02*
Y156557D01*
G01X1810175Y179897D02*
X1807220D01*
G01X1817157Y371329D02*
Y373829D01*
G01Y371329D02*
X1816999Y371171D01*
X1812549D01*
G01X1816994Y398052D02*
Y395552D01*
G01D02*
Y391708D01*
X1815697Y390411D01*
X1813109D01*
G01X1816224Y410432D02*
Y407932D01*
G01D02*
X1805783D01*
X1805659Y408056D01*
G01X1815724Y423932D02*
Y421432D01*
G01D02*
X1815626Y421334D01*
X1805648D01*
G01X1818874Y413432D02*
X1821280D01*
G01X1812161Y472521D02*
X1815666D01*
G01X1813578Y467092D02*
X1814571D01*
X1815666Y468187D01*
Y472521D01*
G01X1809291Y770144D02*
X1804941D01*
G01X1813641D02*
X1809291D01*
G01Y776837D02*
X1804941D01*
G01X1813641D02*
X1809291D01*
G01X1813641Y783530D02*
X1809291D01*
G01D02*
X1804941D01*
G01X1809291Y793570D02*
X1804941D01*
G01X1813641D02*
X1809291D01*
G01Y800263D02*
X1804941D01*
G01X1813641D02*
X1809291D01*
G01Y806955D02*
X1804941D01*
G01X1813641D02*
X1809291D01*
G01Y813648D02*
X1804941D01*
G01X1813641D02*
X1809291D01*
G01Y820341D02*
X1804941D01*
G01X1813641D02*
X1809291D01*
G01Y830381D02*
X1804941D01*
G01X1813641D02*
X1809291D01*
G01Y843766D02*
X1804941D01*
G01X1813641D02*
X1809291D01*
G01Y837074D02*
X1804941D01*
G01X1813641D02*
X1809291D01*
G01Y850459D02*
X1804941D01*
G01X1813641D02*
X1809291D01*
G01Y857152D02*
X1804941D01*
G01X1813641D02*
X1809291D01*
G01Y867192D02*
X1813641D01*
G01X1804941D02*
X1809291D01*
G01Y873885D02*
X1804941D01*
G01X1813641D02*
X1809291D01*
G01Y880577D02*
X1804941D01*
G01X1813641D02*
X1809291D01*
G01Y887270D02*
X1804941D01*
G01X1813641D02*
X1809291D01*
G01Y893963D02*
X1804941D01*
G01X1813641D02*
X1809291D01*
G01Y904003D02*
X1804941D01*
G01X1813641D02*
X1809291D01*
G01Y910696D02*
X1804941D01*
G01X1813641D02*
X1809291D01*
G01Y917389D02*
X1804941D01*
G01X1813641D02*
X1809291D01*
G01Y924081D02*
X1804941D01*
G01X1813641D02*
X1809291D01*
G01Y930774D02*
X1804941D01*
G01X1813641D02*
X1809291D01*
G01Y940814D02*
X1804941D01*
G01X1813641D02*
X1809291D01*
G01Y947507D02*
X1804941D01*
G01X1813641D02*
X1809291D01*
G01Y954200D02*
X1804941D01*
G01X1813641D02*
X1809291D01*
G01Y964239D02*
X1804941D01*
G01X1813641D02*
X1809291D01*
G01Y970932D02*
X1804941D01*
G01X1813641D02*
X1809291D01*
G01Y977625D02*
X1804941D01*
G01X1813641D02*
X1809291D01*
G01Y984318D02*
X1804941D01*
G01X1813641D02*
X1809291D01*
G01Y991011D02*
X1804941D01*
G01X1813641D02*
X1809291D01*
G01Y1017782D02*
X1804941D01*
G01X1813641D02*
X1809291D01*
G01Y1024475D02*
X1804941D01*
G01X1813641D02*
X1809291D01*
G01Y1031168D02*
X1804941D01*
G01X1813641D02*
X1809291D01*
G01Y1037861D02*
X1804941D01*
G01X1813641D02*
X1809291D01*
G01Y1044554D02*
X1804941D01*
G01X1813641D02*
X1809291D01*
G01Y1057940D02*
X1813641D01*
G01X1804941D02*
X1809291D01*
G01Y1051247D02*
X1804941D01*
G01X1813641D02*
X1809291D01*
G01Y1064633D02*
X1804941D01*
G01X1813641D02*
X1809291D01*
G01Y1071326D02*
X1813641D01*
G01X1804941D02*
X1809291D01*
G01Y1078018D02*
X1813641D01*
G01X1804941D02*
X1809291D01*
G01Y1088058D02*
X1813641D01*
G01X1804941D02*
X1809291D01*
G01Y1094751D02*
X1813641D01*
G01X1804941D02*
X1809291D01*
G01Y1101444D02*
X1813641D01*
G01X1804941D02*
X1809291D01*
G01Y1108137D02*
X1813641D01*
G01X1804941D02*
X1809291D01*
G01Y1114829D02*
X1813641D01*
G01X1804941D02*
X1809291D01*
G01Y1124869D02*
X1813641D01*
G01X1804941D02*
X1809291D01*
G01Y1131562D02*
X1813641D01*
G01X1804941D02*
X1809291D01*
G01Y1138255D02*
X1813641D01*
G01X1804941D02*
X1809291D01*
G01Y1144948D02*
X1813641D01*
G01X1804941D02*
X1809291D01*
G01Y1151641D02*
X1813641D01*
G01X1804941D02*
X1809291D01*
G01Y1161680D02*
X1813641D01*
G01X1804941D02*
X1809291D01*
G01Y1168373D02*
X1813641D01*
G01X1804941D02*
X1809291D01*
G01Y1175066D02*
X1813641D01*
G01X1804941D02*
X1809291D01*
G01Y1181759D02*
X1813641D01*
G01X1804941D02*
X1809291D01*
G01Y1188452D02*
X1813641D01*
G01X1804941D02*
X1809291D01*
G01Y1198491D02*
X1813641D01*
G01X1804941D02*
X1809291D01*
G01Y1205184D02*
X1813641D01*
G01X1804941D02*
X1809291D01*
G01Y1211877D02*
X1813641D01*
G01X1804941D02*
X1809291D01*
G01Y1218570D02*
X1813641D01*
G01X1804941D02*
X1809291D01*
G01Y1225263D02*
X1813641D01*
G01X1804941D02*
X1809291D01*
G01Y1235302D02*
X1813641D01*
G01X1804941D02*
X1809291D01*
G01Y1241995D02*
X1813641D01*
G01X1804941D02*
X1809291D01*
G01Y1248688D02*
X1813641D01*
G01X1804941D02*
X1809291D01*
G01Y1258727D02*
X1804941D01*
G01X1813700Y1497212D02*
Y1494762D01*
G01X1825762Y170162D02*
Y167662D01*
G01X1823085Y177243D02*
X1819939D01*
G01X1835760Y182712D02*
X1835409Y182361D01*
X1830565D01*
G01X1834005Y401421D02*
X1832454Y399870D01*
Y399185D01*
G01X1826914Y434202D02*
Y431718D01*
G01X1825433Y766798D02*
X1829783D01*
G01X1821083D02*
X1825433D01*
G01Y773491D02*
X1829783D01*
G01X1821083D02*
X1825433D01*
G01Y780184D02*
X1829783D01*
G01X1821083D02*
X1825433D01*
G01Y790223D02*
X1829783D01*
G01X1821083D02*
X1825433D01*
G01Y796916D02*
X1829783D01*
G01X1821083D02*
X1825433D01*
G01Y803609D02*
X1829783D01*
G01X1821083D02*
X1825433D01*
G01Y810302D02*
X1829783D01*
G01X1821083D02*
X1825433D01*
G01Y816995D02*
X1829783D01*
G01X1821083D02*
X1825433D01*
G01Y827034D02*
X1829783D01*
G01X1821083D02*
X1825433D01*
G01Y833727D02*
X1829783D01*
G01X1821083D02*
X1825433D01*
G01Y847113D02*
X1821083D01*
G01X1829783D02*
X1825433D01*
G01Y840420D02*
X1829783D01*
G01X1821083D02*
X1825433D01*
G01Y853806D02*
X1829783D01*
G01X1821083D02*
X1825433D01*
G01Y863845D02*
X1829783D01*
G01X1821083D02*
X1825433D01*
G01Y870538D02*
X1829783D01*
G01X1821083D02*
X1825433D01*
G01Y877231D02*
X1829783D01*
G01X1821083D02*
X1825433D01*
G01Y883924D02*
X1829783D01*
G01X1821083D02*
X1825433D01*
G01Y890617D02*
X1829783D01*
G01X1821083D02*
X1825433D01*
G01Y900656D02*
X1829783D01*
G01X1821083D02*
X1825433D01*
G01Y907349D02*
X1829783D01*
G01X1821083D02*
X1825433D01*
G01Y914042D02*
X1829783D01*
G01X1821083D02*
X1825433D01*
G01Y920735D02*
X1829783D01*
G01X1821083D02*
X1825433D01*
G01Y927428D02*
X1829783D01*
G01X1821083D02*
X1825433D01*
G01Y937467D02*
X1829783D01*
G01X1821083D02*
X1825433D01*
G01Y944160D02*
X1829783D01*
G01X1821083D02*
X1825433D01*
G01Y950853D02*
X1829783D01*
G01X1821083D02*
X1825433D01*
G01Y960892D02*
X1829783D01*
G01X1821083D02*
X1825433D01*
G01Y967585D02*
X1829783D01*
G01X1821083D02*
X1825433D01*
G01Y974278D02*
X1829783D01*
G01X1821083D02*
X1825433D01*
G01Y980971D02*
X1829783D01*
G01X1821083D02*
X1825433D01*
G01Y987664D02*
X1829783D01*
G01X1821083D02*
X1825433D01*
G01Y1017782D02*
X1829783D01*
G01X1821083D02*
X1825433D01*
G01Y1027822D02*
X1829783D01*
G01X1821083D02*
X1825433D01*
G01Y1034515D02*
X1829783D01*
G01X1821083D02*
X1825433D01*
G01Y1041207D02*
X1829783D01*
G01X1821083D02*
X1825433D01*
G01Y1047900D02*
X1829783D01*
G01X1821083D02*
X1825433D01*
G01Y1054593D02*
X1829783D01*
G01X1821083D02*
X1825433D01*
G01Y1061286D02*
X1829783D01*
G01X1821083D02*
X1825433D01*
G01Y1067979D02*
X1829783D01*
G01X1821083D02*
X1825433D01*
G01Y1074672D02*
X1821083D01*
G01X1829783D02*
X1825433D01*
G01Y1084711D02*
X1821083D01*
G01X1829783D02*
X1825433D01*
G01Y1091404D02*
X1821083D01*
G01X1829783D02*
X1825433D01*
G01Y1098097D02*
X1821083D01*
G01X1829783D02*
X1825433D01*
G01Y1104790D02*
X1821083D01*
G01X1829783D02*
X1825433D01*
G01Y1111483D02*
X1821083D01*
G01X1829783D02*
X1825433D01*
G01Y1121522D02*
X1821083D01*
G01X1829783D02*
X1825433D01*
G01Y1128215D02*
X1821083D01*
G01X1829783D02*
X1825433D01*
G01Y1134908D02*
X1821083D01*
G01X1829783D02*
X1825433D01*
G01Y1141601D02*
X1821083D01*
G01X1829783D02*
X1825433D01*
G01Y1148294D02*
X1821083D01*
G01X1829783D02*
X1825433D01*
G01Y1158333D02*
X1821083D01*
G01X1829783D02*
X1825433D01*
G01Y1165026D02*
X1821083D01*
G01X1829783D02*
X1825433D01*
G01Y1171719D02*
X1821083D01*
G01X1829783D02*
X1825433D01*
G01Y1178412D02*
X1821083D01*
G01X1829783D02*
X1825433D01*
G01Y1185105D02*
X1821083D01*
G01X1829783D02*
X1825433D01*
G01Y1195144D02*
X1821083D01*
G01X1829783D02*
X1825433D01*
G01Y1201837D02*
X1821083D01*
G01X1829783D02*
X1825433D01*
G01Y1208530D02*
X1821083D01*
G01X1829783D02*
X1825433D01*
G01Y1215223D02*
X1821083D01*
G01X1829783D02*
X1825433D01*
G01Y1221916D02*
X1821083D01*
G01X1829783D02*
X1825433D01*
G01Y1231955D02*
X1821083D01*
G01X1829783D02*
X1825433D01*
G01Y1238648D02*
X1821083D01*
G01X1829783D02*
X1825433D01*
G01Y1245341D02*
X1821083D01*
G01X1829783D02*
X1825433D01*
G01X1849191Y166450D02*
X1846691D01*
G01X1846035Y172187D02*
X1848435D01*
G01X1835760Y185772D02*
Y182712D01*
G01X1838880Y192678D02*
Y195162D01*
G01X1835526Y453921D02*
X1838379D01*
X1295929Y166699D03*
Y162999D03*
Y159299D03*
Y185199D03*
Y181499D03*
Y177799D03*
Y174099D03*
Y170399D03*
Y196299D03*
Y192599D03*
Y188899D03*
Y199999D03*
Y214799D03*
Y211099D03*
Y207399D03*
Y203699D03*
Y222199D03*
Y218499D03*
X1305544Y168549D03*
X1311955D03*
X1299134D03*
X1302340Y166699D03*
X1308749D03*
X1305544Y164849D03*
X1311955D03*
X1299134D03*
X1302340Y162999D03*
X1308749D03*
X1305544Y161149D03*
X1311955D03*
X1299134D03*
X1302340Y159299D03*
X1308749D03*
X1305544Y157449D03*
X1311955D03*
X1299134D03*
X1302340Y185199D03*
X1308749D03*
X1305544Y183349D03*
X1311955D03*
X1299134D03*
X1302340Y181499D03*
X1308749D03*
X1305544Y179649D03*
X1311955D03*
X1299134D03*
X1302340Y177799D03*
X1308749D03*
X1305544Y175949D03*
X1311955D03*
X1299134D03*
X1302340Y174099D03*
X1308749D03*
X1305544Y172249D03*
X1311955D03*
X1299134D03*
X1302340Y170399D03*
X1308749D03*
X1302340Y196299D03*
X1308749D03*
X1305544Y194449D03*
X1311955D03*
X1299134D03*
X1302340Y192599D03*
X1308749D03*
X1305544Y190749D03*
X1311955D03*
X1299134D03*
X1302340Y188899D03*
X1308749D03*
X1305544Y187049D03*
X1311955D03*
X1299134D03*
X1302340Y199999D03*
X1308749D03*
X1305544Y198149D03*
X1311955D03*
X1299134D03*
X1305544Y216649D03*
X1311955D03*
X1299134D03*
X1302340Y214799D03*
X1308749D03*
X1305544Y212949D03*
X1311955D03*
X1299134D03*
X1302340Y211099D03*
X1308749D03*
X1305544Y209249D03*
X1311955D03*
X1299134D03*
X1302340Y207399D03*
X1308749D03*
X1305544Y205549D03*
X1311955D03*
X1299134D03*
X1302340Y203699D03*
X1308749D03*
X1305544Y201849D03*
X1311955D03*
X1299134D03*
X1305544Y224049D03*
X1311955D03*
X1299134D03*
X1302340Y222199D03*
X1308749D03*
X1305544Y220349D03*
X1311955D03*
X1299134D03*
X1302340Y218499D03*
X1308749D03*
X1318364Y168549D03*
X1324775D03*
X1315160Y166699D03*
X1321570D03*
X1327979D03*
X1318364Y164849D03*
X1324775D03*
X1315160Y162999D03*
X1321570D03*
X1327979D03*
X1318364Y161149D03*
X1324775D03*
X1315160Y159299D03*
X1321570D03*
X1327979D03*
X1318364Y157449D03*
X1324775D03*
X1316927Y184449D03*
X1320077D03*
X1323227D03*
X1326377D03*
X1329527D03*
X1316927Y181299D03*
X1320077D03*
X1323227D03*
X1326377D03*
X1329527D03*
X1316927Y178149D03*
X1320077D03*
X1323227D03*
X1326377D03*
X1329527D03*
X1315160Y174099D03*
X1321570D03*
X1327979D03*
X1318364Y172249D03*
X1324775D03*
X1315160Y170399D03*
X1321570D03*
X1327979D03*
X1316927Y197049D03*
X1320077D03*
X1323227D03*
X1326377D03*
X1329527D03*
X1316927Y193899D03*
X1320077D03*
X1323227D03*
X1326377D03*
X1329527D03*
X1316927Y190749D03*
X1320077D03*
X1323227D03*
X1326377D03*
X1329527D03*
X1316927Y187599D03*
X1320077D03*
X1323227D03*
X1326377D03*
X1329527D03*
X1316927Y200199D03*
X1320077D03*
X1323227D03*
X1326377D03*
X1329527D03*
X1318364Y216649D03*
X1324775D03*
X1315160Y214799D03*
X1321570D03*
X1327979D03*
X1318364Y212949D03*
X1324775D03*
X1315160Y211099D03*
X1321570D03*
X1327979D03*
X1318364Y209249D03*
X1324775D03*
X1315160Y207399D03*
X1321570D03*
X1327979D03*
X1316927Y203349D03*
X1320077D03*
X1323227D03*
X1326377D03*
X1329527D03*
X1318364Y224049D03*
X1324775D03*
X1315160Y222199D03*
X1321570D03*
X1327979D03*
X1318364Y220349D03*
X1324775D03*
X1315160Y218499D03*
X1321570D03*
X1327979D03*
X1331184Y168549D03*
X1337594D03*
X1344005D03*
X1334390Y166699D03*
X1340799D03*
X1347210D03*
X1331184Y164849D03*
X1337594D03*
X1344005D03*
X1334390Y162999D03*
X1340799D03*
X1347210D03*
X1331184Y161149D03*
X1337594D03*
X1344005D03*
X1334390Y159299D03*
X1340799D03*
X1347210D03*
X1331184Y157449D03*
X1337594D03*
X1344005D03*
X1332677Y184449D03*
X1335827D03*
X1340799Y185199D03*
X1347210D03*
X1344005Y183349D03*
X1332677Y181299D03*
X1335827D03*
X1340799Y181499D03*
X1347210D03*
X1344005Y179649D03*
X1332677Y178149D03*
X1335827D03*
X1340799Y177799D03*
X1347210D03*
X1344005Y175949D03*
X1334390Y174099D03*
X1340799D03*
X1347210D03*
X1331184Y172249D03*
X1337594D03*
X1344005D03*
X1334390Y170399D03*
X1340799D03*
X1347210D03*
X1332677Y197049D03*
X1335827D03*
X1340799Y196299D03*
X1347210D03*
X1332677Y193899D03*
X1335827D03*
X1344005Y194449D03*
X1340799Y192599D03*
X1347210D03*
X1332677Y190749D03*
X1335827D03*
X1344005D03*
X1340799Y188899D03*
X1347210D03*
X1332677Y187599D03*
X1335827D03*
X1344005Y187049D03*
X1332677Y200199D03*
X1335827D03*
X1340799Y199999D03*
X1347210D03*
X1344005Y198149D03*
X1331184Y216649D03*
X1337594D03*
X1344005D03*
X1334390Y214799D03*
X1340799D03*
X1347210D03*
X1331184Y212949D03*
X1337594D03*
X1344005D03*
X1334390Y211099D03*
X1340799D03*
X1347210D03*
X1331184Y209249D03*
X1337594D03*
X1344005D03*
X1334390Y207399D03*
X1340799D03*
X1347210D03*
X1344005Y205549D03*
X1332677Y203349D03*
X1335827D03*
X1340799Y203699D03*
X1347210D03*
X1344005Y201849D03*
X1331184Y224049D03*
X1337594D03*
X1344005D03*
X1334390Y222199D03*
X1340799D03*
X1347210D03*
X1331184Y220349D03*
X1337594D03*
X1344005D03*
X1334390Y218499D03*
X1340799D03*
X1347210D03*
X1350414Y168549D03*
X1356825D03*
X1353620Y166699D03*
X1350414Y164849D03*
X1356825D03*
X1353620Y162999D03*
X1350414Y161149D03*
X1356825D03*
X1353620Y159299D03*
X1350414Y157449D03*
X1356825D03*
X1353620Y185199D03*
X1350414Y183349D03*
X1356825D03*
X1353620Y181499D03*
X1350414Y179649D03*
X1356825D03*
X1353620Y177799D03*
X1350414Y175949D03*
X1356825D03*
X1353620Y174099D03*
X1350414Y172249D03*
X1356825D03*
X1353620Y170399D03*
Y196299D03*
X1350414Y194449D03*
X1356825D03*
X1353620Y192599D03*
X1350414Y190749D03*
X1356825D03*
X1353620Y188899D03*
X1350414Y187049D03*
X1356825D03*
X1353620Y199999D03*
X1350414Y198149D03*
X1356825D03*
X1350414Y216649D03*
X1356825D03*
X1353620Y214799D03*
X1350414Y212949D03*
X1356825D03*
X1353620Y211099D03*
X1350414Y209249D03*
X1356825D03*
X1353620Y207399D03*
X1350414Y205549D03*
X1356825D03*
X1353620Y203699D03*
X1350414Y201849D03*
X1356825D03*
X1350414Y224049D03*
X1356825D03*
X1353620Y222199D03*
X1350414Y220349D03*
X1356825D03*
X1353620Y218499D03*
G54D79*
X109696Y639477D03*
X108122D03*
X106547D03*
X104972D03*
X103397D03*
X101822D03*
Y658375D03*
X103397D03*
X104972D03*
X106547D03*
X108122D03*
X109696D03*
X125438Y500919D03*
X123863D03*
X122288D03*
X120713D03*
X119138D03*
Y519817D03*
X120713D03*
X122288D03*
X123863D03*
X125438D03*
X115996Y639477D03*
X114421D03*
X112846D03*
X111271D03*
Y658375D03*
X112846D03*
X114421D03*
X115996D03*
X133312Y500919D03*
X131737D03*
X130162D03*
X128587D03*
X127012D03*
Y519817D03*
X128587D03*
X130162D03*
X131737D03*
X133312D03*
X1672067Y527616D03*
X1670492D03*
X1668917D03*
Y546514D03*
X1670492D03*
X1672067D03*
X1683091Y527616D03*
X1681516D03*
X1679941D03*
X1678366D03*
X1676791D03*
X1675217D03*
X1673642D03*
Y546514D03*
X1675217D03*
X1676791D03*
X1678366D03*
X1679941D03*
X1681516D03*
X1683091D03*
X1703547Y474758D03*
X1701973D03*
X1700398D03*
X1698823D03*
X1697248D03*
X1695673D03*
Y493656D03*
X1697248D03*
X1698823D03*
X1700398D03*
X1701973D03*
X1703547D03*
X1709847Y474758D03*
X1708272D03*
X1706697D03*
X1705122D03*
Y493656D03*
X1706697D03*
X1708272D03*
X1709847D03*
G54D299*
X1595750Y128005D03*
Y159305D03*
X1613466Y128005D03*
Y159305D03*
G54D89*
X159474Y1320753D03*
X183847Y1320778D03*
X208247D03*
X275289Y575702D03*
Y599861D03*
Y624015D03*
Y648169D03*
X278126Y676260D03*
Y700414D03*
X395771Y1242785D03*
X420171D03*
X444493D03*
X468893D03*
X493293D03*
X673093Y1320778D03*
X697466Y1320803D03*
X721866D03*
X1100800Y251488D03*
X1100700Y275788D03*
X1131100Y1357088D03*
X1155500D03*
X1179900D03*
X1371912Y1242785D03*
X1396312D03*
X1420634D03*
X1445034D03*
X1469434D03*
X1577000Y591888D03*
Y616388D03*
Y640888D03*
Y665288D03*
Y689788D03*
Y714288D03*
X1634259Y1354374D03*
X1658632Y1354399D03*
X1683032D03*
G54D98*
X154193Y1392019D03*
Y1393791D03*
Y1395563D03*
Y1397334D03*
Y1399106D03*
Y1400878D03*
X192336Y1392019D03*
Y1393791D03*
Y1395563D03*
Y1397334D03*
Y1399106D03*
Y1400878D03*
X204723Y574220D03*
Y590165D03*
Y588394D03*
Y586622D03*
Y584850D03*
Y583079D03*
Y575992D03*
Y577764D03*
Y579535D03*
Y581307D03*
Y608220D03*
Y624165D03*
Y622394D03*
Y620622D03*
Y618850D03*
Y617079D03*
Y609992D03*
Y611764D03*
Y613535D03*
Y615307D03*
Y656394D03*
Y654622D03*
Y652850D03*
Y651079D03*
Y642220D03*
Y643992D03*
Y645764D03*
Y647535D03*
Y649307D03*
Y658165D03*
X280741Y151850D03*
Y153819D03*
Y155787D03*
Y157756D03*
X291765Y151850D03*
Y157756D03*
Y155787D03*
Y153819D03*
X308176Y1350165D03*
Y1351937D03*
Y1353709D03*
Y1355480D03*
Y1357252D03*
Y1359024D03*
X340304Y1327367D03*
Y1329139D03*
Y1330911D03*
Y1332682D03*
Y1334454D03*
Y1336226D03*
X372432Y1313941D03*
Y1315713D03*
Y1317485D03*
Y1319256D03*
Y1321028D03*
Y1322800D03*
X404560Y1313941D03*
Y1315713D03*
Y1317485D03*
Y1319256D03*
Y1321028D03*
Y1322800D03*
X436688Y1313941D03*
Y1315713D03*
Y1317485D03*
Y1319256D03*
Y1321028D03*
Y1322800D03*
X468816Y1313941D03*
Y1315713D03*
Y1317485D03*
Y1319256D03*
Y1321028D03*
Y1322800D03*
X500944Y1327367D03*
Y1329139D03*
Y1330911D03*
Y1332682D03*
Y1334454D03*
Y1336226D03*
X533072Y1350165D03*
Y1351937D03*
Y1353709D03*
Y1355480D03*
Y1357252D03*
Y1359024D03*
X595644Y203025D03*
Y204994D03*
Y206962D03*
Y208931D03*
X606668D03*
Y206962D03*
Y204994D03*
Y203025D03*
X667812Y1392044D03*
Y1393816D03*
Y1395588D03*
Y1397359D03*
Y1399131D03*
Y1400903D03*
X705955Y1392044D03*
Y1393816D03*
Y1395588D03*
Y1397359D03*
Y1399131D03*
Y1400903D03*
X818002Y133945D03*
Y135914D03*
Y137882D03*
Y139851D03*
X829026Y135914D03*
Y133945D03*
Y139851D03*
Y137882D03*
X841967Y211438D03*
Y213407D03*
Y215375D03*
Y217344D03*
X852991D03*
Y215375D03*
Y213407D03*
Y211438D03*
X1127504Y1428348D03*
Y1430120D03*
Y1431892D03*
Y1433663D03*
Y1435435D03*
Y1437207D03*
X1165647Y1428348D03*
Y1430120D03*
Y1431892D03*
Y1433663D03*
Y1435435D03*
Y1437207D03*
X1180193Y1628173D03*
Y1626204D03*
Y1624236D03*
Y1622267D03*
X1169169D03*
Y1624236D03*
Y1626204D03*
Y1628173D03*
X1284437Y1350401D03*
Y1352173D03*
Y1353945D03*
Y1355716D03*
Y1357488D03*
Y1359260D03*
X1316445Y1327367D03*
Y1329139D03*
Y1330911D03*
Y1332682D03*
Y1334454D03*
Y1336226D03*
X1348573Y1313941D03*
Y1315713D03*
Y1317485D03*
Y1319256D03*
Y1321028D03*
Y1322800D03*
X1380701Y1313941D03*
Y1315713D03*
Y1317485D03*
Y1319256D03*
Y1321028D03*
Y1322800D03*
X1412829Y1313941D03*
Y1315713D03*
Y1317485D03*
Y1319256D03*
Y1321028D03*
Y1322800D03*
X1444957Y1313941D03*
Y1315713D03*
Y1317485D03*
Y1319256D03*
Y1321028D03*
Y1322800D03*
X1477085Y1327367D03*
Y1329139D03*
Y1330911D03*
Y1332682D03*
Y1334454D03*
Y1336226D03*
X1509213Y1350165D03*
Y1351937D03*
Y1353709D03*
Y1355480D03*
Y1357252D03*
Y1359024D03*
X1628978Y1425640D03*
Y1427412D03*
Y1429184D03*
Y1430955D03*
Y1432727D03*
Y1434499D03*
X1649250Y630417D03*
Y632188D03*
Y633960D03*
Y635732D03*
Y637503D03*
Y639275D03*
Y646362D03*
Y644590D03*
Y642818D03*
Y641047D03*
Y664417D03*
Y666188D03*
Y667960D03*
Y669732D03*
Y671503D03*
Y673275D03*
Y680362D03*
Y678590D03*
Y676818D03*
Y675047D03*
Y698417D03*
Y700188D03*
Y701960D03*
Y703732D03*
Y705503D03*
Y714362D03*
Y712590D03*
Y710818D03*
Y709047D03*
Y707275D03*
X1667121Y1425640D03*
Y1427412D03*
Y1429184D03*
Y1430955D03*
Y1432727D03*
Y1434499D03*
X1729480Y367431D03*
Y369400D03*
Y371368D03*
Y373337D03*
X1740504D03*
Y371368D03*
Y369400D03*
Y367431D03*
G54D99*
X157323Y1545001D03*
M02*
